G04*
G04 #@! TF.GenerationSoftware,Altium Limited,Altium Designer,23.0.1 (38)*
G04*
G04 Layer_Color=8388736*
%FSLAX25Y25*%
%MOIN*%
G70*
G04*
G04 #@! TF.SameCoordinates,C48E81DB-6E20-4E2D-80E6-7C5AFAA1A21F*
G04*
G04*
G04 #@! TF.FilePolarity,Positive*
G04*
G01*
G75*
%ADD15C,0.00787*%
G36*
X688389Y-28727D02*
X688386Y-28757D01*
Y-28789D01*
X688382Y-28866D01*
X688371Y-28946D01*
X688360Y-29033D01*
X688342Y-29113D01*
X688331Y-29153D01*
X688320Y-29186D01*
Y-29190D01*
X688316Y-29193D01*
X688306Y-29215D01*
X688291Y-29248D01*
X688266Y-29288D01*
X688233Y-29332D01*
X688189Y-29379D01*
X688138Y-29423D01*
X688080Y-29466D01*
X688076D01*
X688073Y-29470D01*
X688051Y-29485D01*
X688014Y-29499D01*
X687967Y-29521D01*
X687912Y-29539D01*
X687847Y-29557D01*
X687778Y-29568D01*
X687701Y-29572D01*
X687698D01*
X687690D01*
X687676D01*
X687658Y-29568D01*
X687632D01*
X687607Y-29565D01*
X687545Y-29550D01*
X687472Y-29528D01*
X687396Y-29499D01*
X687319Y-29456D01*
X687283Y-29426D01*
X687246Y-29397D01*
X687243Y-29394D01*
X687239Y-29390D01*
X687228Y-29379D01*
X687217Y-29364D01*
X687203Y-29346D01*
X687188Y-29324D01*
X687170Y-29295D01*
X687148Y-29266D01*
X687130Y-29230D01*
X687112Y-29190D01*
X687090Y-29146D01*
X687072Y-29099D01*
X687057Y-29044D01*
X687039Y-28990D01*
X687028Y-28928D01*
X687017Y-28862D01*
X687013Y-28869D01*
X687006Y-28884D01*
X686992Y-28906D01*
X686977Y-28935D01*
X686937Y-29000D01*
X686911Y-29033D01*
X686890Y-29062D01*
X686882Y-29070D01*
X686864Y-29088D01*
X686835Y-29117D01*
X686799Y-29153D01*
X686748Y-29193D01*
X686693Y-29241D01*
X686627Y-29288D01*
X686555Y-29339D01*
X685870Y-29772D01*
Y-29357D01*
X686395Y-29026D01*
X686398D01*
X686406Y-29019D01*
X686416Y-29011D01*
X686431Y-29000D01*
X686471Y-28975D01*
X686522Y-28942D01*
X686577Y-28902D01*
X686635Y-28862D01*
X686689Y-28822D01*
X686740Y-28786D01*
X686744Y-28782D01*
X686759Y-28771D01*
X686780Y-28753D01*
X686806Y-28727D01*
X686861Y-28673D01*
X686886Y-28644D01*
X686908Y-28615D01*
X686911Y-28611D01*
X686915Y-28604D01*
X686922Y-28589D01*
X686933Y-28567D01*
X686944Y-28545D01*
X686955Y-28520D01*
X686973Y-28462D01*
Y-28458D01*
X686977Y-28451D01*
Y-28436D01*
X686981Y-28418D01*
X686984Y-28393D01*
Y-28363D01*
X686988Y-28323D01*
Y-27894D01*
X685870D01*
Y-27559D01*
X688389D01*
Y-28727D01*
D02*
G37*
G36*
X686635Y-29969D02*
X686657D01*
X686682Y-29972D01*
X686740Y-29980D01*
X686806Y-29994D01*
X686871Y-30016D01*
X686941Y-30049D01*
X687006Y-30089D01*
X687010D01*
X687013Y-30096D01*
X687032Y-30111D01*
X687061Y-30140D01*
X687097Y-30180D01*
X687134Y-30231D01*
X687174Y-30293D01*
X687206Y-30362D01*
X687232Y-30446D01*
Y-30442D01*
X687235Y-30438D01*
X687239Y-30427D01*
X687246Y-30413D01*
X687261Y-30380D01*
X687283Y-30336D01*
X687312Y-30289D01*
X687348Y-30242D01*
X687388Y-30198D01*
X687432Y-30158D01*
X687439Y-30154D01*
X687454Y-30143D01*
X687483Y-30129D01*
X687519Y-30114D01*
X687567Y-30096D01*
X687621Y-30081D01*
X687683Y-30071D01*
X687749Y-30067D01*
X687752D01*
X687760D01*
X687774D01*
X687796Y-30071D01*
X687818Y-30074D01*
X687847Y-30078D01*
X687909Y-30092D01*
X687982Y-30114D01*
X688058Y-30151D01*
X688098Y-30173D01*
X688138Y-30198D01*
X688174Y-30231D01*
X688211Y-30264D01*
X688215Y-30267D01*
X688218Y-30275D01*
X688229Y-30285D01*
X688240Y-30300D01*
X688255Y-30318D01*
X688269Y-30344D01*
X688287Y-30373D01*
X688306Y-30402D01*
X688324Y-30438D01*
X688342Y-30478D01*
X688356Y-30522D01*
X688371Y-30569D01*
X688393Y-30671D01*
X688397Y-30729D01*
X688400Y-30788D01*
Y-30821D01*
X688397Y-30842D01*
X688393Y-30871D01*
X688389Y-30904D01*
X688386Y-30941D01*
X688375Y-30977D01*
X688353Y-31064D01*
X688320Y-31152D01*
X688298Y-31195D01*
X688273Y-31239D01*
X688240Y-31279D01*
X688207Y-31319D01*
X688204Y-31323D01*
X688200Y-31326D01*
X688189Y-31337D01*
X688174Y-31352D01*
X688153Y-31367D01*
X688131Y-31385D01*
X688076Y-31421D01*
X688007Y-31457D01*
X687927Y-31490D01*
X687836Y-31516D01*
X687789Y-31519D01*
X687738Y-31523D01*
X687734D01*
X687730D01*
X687709D01*
X687676Y-31519D01*
X687636Y-31512D01*
X687585Y-31501D01*
X687534Y-31483D01*
X687483Y-31461D01*
X687432Y-31428D01*
X687425Y-31425D01*
X687410Y-31410D01*
X687388Y-31388D01*
X687359Y-31359D01*
X687326Y-31319D01*
X687294Y-31272D01*
X687261Y-31217D01*
X687232Y-31152D01*
Y-31155D01*
X687228Y-31163D01*
X687224Y-31174D01*
X687217Y-31188D01*
X687199Y-31232D01*
X687174Y-31283D01*
X687137Y-31337D01*
X687097Y-31396D01*
X687046Y-31450D01*
X686988Y-31501D01*
X686984D01*
X686981Y-31505D01*
X686959Y-31519D01*
X686922Y-31541D01*
X686875Y-31563D01*
X686817Y-31585D01*
X686748Y-31607D01*
X686671Y-31621D01*
X686587Y-31625D01*
X686584D01*
X686573D01*
X686555D01*
X686533Y-31621D01*
X686507Y-31618D01*
X686475Y-31614D01*
X686438Y-31607D01*
X686398Y-31596D01*
X686314Y-31570D01*
X686267Y-31552D01*
X686224Y-31527D01*
X686176Y-31501D01*
X686132Y-31472D01*
X686089Y-31436D01*
X686045Y-31396D01*
X686041Y-31392D01*
X686034Y-31385D01*
X686023Y-31374D01*
X686012Y-31356D01*
X685994Y-31330D01*
X685976Y-31305D01*
X685958Y-31272D01*
X685936Y-31235D01*
X685914Y-31195D01*
X685896Y-31148D01*
X685878Y-31097D01*
X685859Y-31046D01*
X685849Y-30988D01*
X685838Y-30926D01*
X685830Y-30864D01*
X685827Y-30795D01*
Y-30759D01*
X685830Y-30733D01*
X685834Y-30700D01*
X685838Y-30664D01*
X685845Y-30624D01*
X685856Y-30580D01*
X685881Y-30482D01*
X685899Y-30431D01*
X685918Y-30384D01*
X685943Y-30333D01*
X685972Y-30282D01*
X686005Y-30234D01*
X686045Y-30191D01*
X686049Y-30187D01*
X686056Y-30180D01*
X686067Y-30169D01*
X686085Y-30154D01*
X686107Y-30140D01*
X686132Y-30118D01*
X686162Y-30100D01*
X686198Y-30078D01*
X686234Y-30056D01*
X686278Y-30038D01*
X686369Y-30002D01*
X686424Y-29987D01*
X686478Y-29976D01*
X686537Y-29969D01*
X686595Y-29965D01*
X686598D01*
X686606D01*
X686620D01*
X686635Y-29969D01*
D02*
G37*
G36*
X685883Y-31677D02*
X685912Y-31680D01*
X685944Y-31687D01*
X685981Y-31695D01*
X686021Y-31702D01*
X686108Y-31731D01*
X686156Y-31753D01*
X686199Y-31775D01*
X686247Y-31804D01*
X686294Y-31837D01*
X686341Y-31873D01*
X686385Y-31917D01*
X686388Y-31920D01*
X686396Y-31928D01*
X686407Y-31942D01*
X686414Y-31952D01*
X686424Y-31949D01*
X686478Y-31938D01*
X686537Y-31931D01*
X686577Y-32240D01*
X686573D01*
X686568Y-32243D01*
X686578Y-32274D01*
X686592Y-32332D01*
X686603Y-32394D01*
X686611Y-32456D01*
X686614Y-32525D01*
Y-32557D01*
X686611Y-32579D01*
X686607Y-32608D01*
X686603Y-32641D01*
X686596Y-32678D01*
X686589Y-32717D01*
X686567Y-32805D01*
X686530Y-32896D01*
X686509Y-32943D01*
X686483Y-32987D01*
X686450Y-33031D01*
X686418Y-33074D01*
X686414Y-33078D01*
X686407Y-33085D01*
X686396Y-33096D01*
X686381Y-33107D01*
X686363Y-33125D01*
X686338Y-33143D01*
X686316Y-33162D01*
X686336Y-33176D01*
X686391Y-33205D01*
X686453Y-33226D01*
X686526Y-33245D01*
X686606Y-33252D01*
X686609D01*
X686617D01*
X686627D01*
X686642Y-33248D01*
X686682Y-33245D01*
X686729Y-33234D01*
X686788Y-33219D01*
X686846Y-33194D01*
X686904Y-33157D01*
X686959Y-33110D01*
X686966Y-33103D01*
X686981Y-33085D01*
X687002Y-33055D01*
X687028Y-33015D01*
X687053Y-32964D01*
X687075Y-32903D01*
X687090Y-32833D01*
X687097Y-32757D01*
Y-32724D01*
X687093Y-32699D01*
X687090Y-32666D01*
X687082Y-32630D01*
X687075Y-32586D01*
X687064Y-32539D01*
X687337Y-32575D01*
Y-32593D01*
X687334Y-32608D01*
Y-32655D01*
X687341Y-32695D01*
X687348Y-32742D01*
X687359Y-32797D01*
X687377Y-32859D01*
X687403Y-32917D01*
X687436Y-32979D01*
Y-32983D01*
X687439Y-32986D01*
X687454Y-33005D01*
X687479Y-33030D01*
X687512Y-33059D01*
X687559Y-33088D01*
X687614Y-33114D01*
X687676Y-33132D01*
X687712Y-33139D01*
X687752D01*
X687756D01*
X687760D01*
X687781D01*
X687811Y-33132D01*
X687851Y-33125D01*
X687894Y-33110D01*
X687942Y-33092D01*
X687989Y-33063D01*
X688033Y-33023D01*
X688036Y-33019D01*
X688051Y-33001D01*
X688069Y-32975D01*
X688091Y-32943D01*
X688109Y-32899D01*
X688127Y-32848D01*
X688142Y-32790D01*
X688145Y-32724D01*
Y-32695D01*
X688138Y-32662D01*
X688131Y-32619D01*
X688116Y-32571D01*
X688098Y-32524D01*
X688069Y-32473D01*
X688033Y-32426D01*
X688029Y-32422D01*
X688011Y-32408D01*
X687985Y-32386D01*
X687949Y-32360D01*
X687901Y-32335D01*
X687843Y-32309D01*
X687774Y-32287D01*
X687694Y-32273D01*
X687749Y-31963D01*
X687752D01*
X687763Y-31967D01*
X687778Y-31971D01*
X687800Y-31974D01*
X687825Y-31982D01*
X687854Y-31993D01*
X687923Y-32014D01*
X688003Y-32051D01*
X688084Y-32094D01*
X688160Y-32149D01*
X688229Y-32218D01*
X688233Y-32222D01*
X688236Y-32229D01*
X688244Y-32240D01*
X688255Y-32255D01*
X688269Y-32273D01*
X688284Y-32298D01*
X688298Y-32324D01*
X688316Y-32357D01*
X688346Y-32429D01*
X688375Y-32513D01*
X688393Y-32611D01*
X688400Y-32662D01*
Y-32753D01*
X688397Y-32793D01*
X688389Y-32841D01*
X688378Y-32899D01*
X688360Y-32964D01*
X688338Y-33030D01*
X688309Y-33095D01*
Y-33099D01*
X688306Y-33103D01*
X688295Y-33125D01*
X688273Y-33157D01*
X688247Y-33194D01*
X688211Y-33237D01*
X688171Y-33281D01*
X688124Y-33325D01*
X688069Y-33361D01*
X688062Y-33365D01*
X688043Y-33376D01*
X688011Y-33390D01*
X687971Y-33408D01*
X687923Y-33427D01*
X687869Y-33441D01*
X687807Y-33452D01*
X687745Y-33456D01*
X687738D01*
X687716D01*
X687687Y-33452D01*
X687647Y-33445D01*
X687599Y-33434D01*
X687548Y-33416D01*
X687498Y-33394D01*
X687446Y-33365D01*
X687439Y-33361D01*
X687425Y-33350D01*
X687399Y-33328D01*
X687370Y-33299D01*
X687337Y-33263D01*
X687301Y-33219D01*
X687268Y-33168D01*
X687235Y-33106D01*
Y-33110D01*
X687232Y-33117D01*
X687228Y-33128D01*
X687224Y-33143D01*
X687210Y-33183D01*
X687188Y-33234D01*
X687159Y-33292D01*
X687123Y-33350D01*
X687075Y-33405D01*
X687021Y-33456D01*
X687013Y-33459D01*
X686992Y-33474D01*
X686955Y-33496D01*
X686908Y-33518D01*
X686850Y-33540D01*
X686780Y-33561D01*
X686700Y-33576D01*
X686613Y-33580D01*
X686609D01*
X686598D01*
X686580D01*
X686558Y-33576D01*
X686529Y-33572D01*
X686496Y-33565D01*
X686460Y-33558D01*
X686420Y-33551D01*
X686333Y-33521D01*
X686285Y-33500D01*
X686242Y-33478D01*
X686194Y-33449D01*
X686147Y-33416D01*
X686100Y-33379D01*
X686056Y-33336D01*
X686052Y-33332D01*
X686045Y-33325D01*
X686034Y-33310D01*
X686026Y-33301D01*
X686017Y-33304D01*
X685963Y-33314D01*
X685904Y-33322D01*
X685864Y-33012D01*
X685868D01*
X685873Y-33010D01*
X685863Y-32979D01*
X685849Y-32921D01*
X685838Y-32859D01*
X685830Y-32797D01*
X685827Y-32728D01*
Y-32695D01*
X685830Y-32673D01*
X685834Y-32644D01*
X685838Y-32611D01*
X685845Y-32575D01*
X685852Y-32535D01*
X685874Y-32448D01*
X685910Y-32357D01*
X685932Y-32309D01*
X685958Y-32266D01*
X685990Y-32222D01*
X686023Y-32178D01*
X686027Y-32175D01*
X686034Y-32167D01*
X686045Y-32156D01*
X686060Y-32145D01*
X686078Y-32127D01*
X686103Y-32109D01*
X686125Y-32090D01*
X686105Y-32077D01*
X686050Y-32048D01*
X685988Y-32026D01*
X685915Y-32008D01*
X685835Y-32000D01*
X685832D01*
X685824D01*
X685813D01*
X685799Y-32004D01*
X685759Y-32008D01*
X685711Y-32019D01*
X685653Y-32033D01*
X685595Y-32059D01*
X685537Y-32095D01*
X685482Y-32142D01*
X685475Y-32150D01*
X685460Y-32168D01*
X685438Y-32197D01*
X685413Y-32237D01*
X685388Y-32288D01*
X685366Y-32350D01*
X685351Y-32419D01*
X685344Y-32495D01*
Y-32528D01*
X685348Y-32554D01*
X685351Y-32587D01*
X685358Y-32623D01*
X685366Y-32667D01*
X685377Y-32714D01*
X685104Y-32678D01*
Y-32659D01*
X685107Y-32645D01*
Y-32597D01*
X685100Y-32557D01*
X685093Y-32510D01*
X685082Y-32456D01*
X685064Y-32394D01*
X685038Y-32335D01*
X685005Y-32274D01*
Y-32270D01*
X685002Y-32266D01*
X684987Y-32248D01*
X684962Y-32223D01*
X684929Y-32193D01*
X684882Y-32164D01*
X684827Y-32139D01*
X684765Y-32121D01*
X684729Y-32113D01*
X684689D01*
X684685D01*
X684681D01*
X684659D01*
X684630Y-32121D01*
X684590Y-32128D01*
X684547Y-32142D01*
X684499Y-32161D01*
X684452Y-32190D01*
X684408Y-32230D01*
X684405Y-32233D01*
X684390Y-32252D01*
X684372Y-32277D01*
X684350Y-32310D01*
X684332Y-32353D01*
X684314Y-32405D01*
X684299Y-32463D01*
X684296Y-32528D01*
Y-32557D01*
X684303Y-32590D01*
X684310Y-32634D01*
X684325Y-32681D01*
X684343Y-32728D01*
X684372Y-32779D01*
X684408Y-32827D01*
X684412Y-32830D01*
X684430Y-32845D01*
X684456Y-32867D01*
X684492Y-32892D01*
X684539Y-32918D01*
X684598Y-32943D01*
X684667Y-32965D01*
X684747Y-32980D01*
X684692Y-33289D01*
X684689D01*
X684678Y-33285D01*
X684663Y-33282D01*
X684641Y-33278D01*
X684616Y-33271D01*
X684587Y-33260D01*
X684518Y-33238D01*
X684438Y-33202D01*
X684357Y-33158D01*
X684281Y-33103D01*
X684212Y-33034D01*
X684208Y-33031D01*
X684204Y-33023D01*
X684197Y-33012D01*
X684186Y-32998D01*
X684172Y-32980D01*
X684157Y-32954D01*
X684143Y-32929D01*
X684124Y-32896D01*
X684095Y-32823D01*
X684066Y-32739D01*
X684048Y-32641D01*
X684041Y-32590D01*
Y-32499D01*
X684044Y-32459D01*
X684052Y-32412D01*
X684063Y-32353D01*
X684081Y-32288D01*
X684103Y-32223D01*
X684132Y-32157D01*
Y-32153D01*
X684135Y-32150D01*
X684146Y-32128D01*
X684168Y-32095D01*
X684194Y-32059D01*
X684230Y-32015D01*
X684270Y-31971D01*
X684317Y-31928D01*
X684372Y-31891D01*
X684379Y-31888D01*
X684397Y-31877D01*
X684430Y-31862D01*
X684470Y-31844D01*
X684518Y-31826D01*
X684572Y-31811D01*
X684634Y-31800D01*
X684696Y-31797D01*
X684703D01*
X684725D01*
X684754Y-31800D01*
X684794Y-31808D01*
X684841Y-31819D01*
X684893Y-31837D01*
X684943Y-31859D01*
X684994Y-31888D01*
X685002Y-31891D01*
X685016Y-31902D01*
X685042Y-31924D01*
X685071Y-31953D01*
X685104Y-31989D01*
X685140Y-32033D01*
X685173Y-32084D01*
X685206Y-32146D01*
Y-32142D01*
X685209Y-32135D01*
X685213Y-32124D01*
X685216Y-32110D01*
X685231Y-32070D01*
X685253Y-32019D01*
X685282Y-31960D01*
X685318Y-31902D01*
X685366Y-31848D01*
X685420Y-31797D01*
X685428Y-31793D01*
X685449Y-31778D01*
X685486Y-31757D01*
X685533Y-31735D01*
X685591Y-31713D01*
X685661Y-31691D01*
X685741Y-31677D01*
X685828Y-31673D01*
X685832D01*
X685843D01*
X685861D01*
X685883Y-31677D01*
D02*
G37*
G36*
X685380Y-33631D02*
X685428D01*
X685482Y-33635D01*
X685537Y-33642D01*
X685661Y-33653D01*
X685792Y-33671D01*
X685915Y-33697D01*
X685977Y-33715D01*
X686032Y-33733D01*
X686035D01*
X686043Y-33737D01*
X686057Y-33744D01*
X686079Y-33751D01*
X686101Y-33762D01*
X686130Y-33777D01*
X686192Y-33813D01*
X686261Y-33857D01*
X686334Y-33908D01*
X686403Y-33973D01*
X686465Y-34046D01*
Y-34050D01*
X686472Y-34057D01*
X686480Y-34068D01*
X686487Y-34082D01*
X686498Y-34104D01*
X686512Y-34126D01*
X686527Y-34155D01*
X686538Y-34184D01*
X686567Y-34254D01*
X686592Y-34337D01*
X686607Y-34428D01*
X686614Y-34530D01*
Y-34559D01*
X686611Y-34578D01*
Y-34603D01*
X686607Y-34632D01*
X686592Y-34701D01*
X686574Y-34778D01*
X686545Y-34858D01*
X686505Y-34938D01*
X686480Y-34978D01*
X686450Y-35014D01*
X686447Y-35018D01*
X686443Y-35022D01*
X686432Y-35033D01*
X686421Y-35043D01*
X686403Y-35058D01*
X686381Y-35076D01*
X686330Y-35113D01*
X686265Y-35149D01*
X686185Y-35185D01*
X686094Y-35215D01*
X685988Y-35236D01*
X685963Y-34938D01*
X685966D01*
X685974Y-34934D01*
X685981D01*
X685995Y-34931D01*
X686035Y-34920D01*
X686079Y-34905D01*
X686130Y-34887D01*
X686181Y-34861D01*
X686228Y-34832D01*
X686268Y-34796D01*
X686272Y-34792D01*
X686283Y-34778D01*
X686298Y-34752D01*
X686312Y-34723D01*
X686330Y-34683D01*
X686345Y-34636D01*
X686356Y-34581D01*
X686359Y-34523D01*
Y-34497D01*
X686356Y-34472D01*
X686352Y-34439D01*
X686345Y-34399D01*
X686334Y-34359D01*
X686319Y-34315D01*
X686298Y-34275D01*
X686294Y-34272D01*
X686287Y-34257D01*
X686272Y-34235D01*
X686250Y-34214D01*
X686225Y-34184D01*
X686196Y-34155D01*
X686163Y-34126D01*
X686123Y-34097D01*
X686119Y-34093D01*
X686101Y-34086D01*
X686075Y-34072D01*
X686043Y-34057D01*
X685999Y-34039D01*
X685948Y-34021D01*
X685890Y-34002D01*
X685824Y-33984D01*
X685821D01*
X685817Y-33981D01*
X685806D01*
X685792Y-33977D01*
X685755Y-33970D01*
X685708Y-33959D01*
X685650Y-33952D01*
X685588Y-33944D01*
X685519Y-33941D01*
X685446Y-33937D01*
X685442D01*
X685431D01*
X685413D01*
X685384D01*
X685391Y-33941D01*
X685409Y-33955D01*
X685435Y-33977D01*
X685471Y-34002D01*
X685508Y-34039D01*
X685548Y-34082D01*
X685588Y-34133D01*
X685624Y-34192D01*
X685628Y-34199D01*
X685639Y-34221D01*
X685653Y-34254D01*
X685668Y-34294D01*
X685686Y-34348D01*
X685701Y-34407D01*
X685711Y-34472D01*
X685715Y-34541D01*
Y-34570D01*
X685711Y-34592D01*
X685708Y-34621D01*
X685704Y-34650D01*
X685697Y-34687D01*
X685686Y-34723D01*
X685661Y-34807D01*
X685642Y-34851D01*
X685620Y-34894D01*
X685595Y-34942D01*
X685562Y-34985D01*
X685530Y-35029D01*
X685489Y-35069D01*
X685486Y-35073D01*
X685478Y-35080D01*
X685468Y-35087D01*
X685449Y-35102D01*
X685424Y-35120D01*
X685398Y-35138D01*
X685366Y-35156D01*
X685329Y-35175D01*
X685289Y-35196D01*
X685246Y-35215D01*
X685195Y-35233D01*
X685144Y-35251D01*
X685085Y-35265D01*
X685023Y-35273D01*
X684962Y-35280D01*
X684893Y-35284D01*
X684889D01*
X684874D01*
X684856D01*
X684831Y-35280D01*
X684798Y-35276D01*
X684758Y-35273D01*
X684718Y-35265D01*
X684670Y-35255D01*
X684576Y-35229D01*
X684525Y-35211D01*
X684470Y-35189D01*
X684419Y-35164D01*
X684372Y-35131D01*
X684321Y-35098D01*
X684277Y-35058D01*
X684274Y-35054D01*
X684266Y-35047D01*
X684256Y-35036D01*
X684241Y-35018D01*
X684223Y-34996D01*
X684201Y-34967D01*
X684183Y-34938D01*
X684157Y-34901D01*
X684135Y-34865D01*
X684117Y-34821D01*
X684077Y-34723D01*
X684063Y-34672D01*
X684052Y-34614D01*
X684044Y-34556D01*
X684041Y-34494D01*
Y-34468D01*
X684044Y-34450D01*
Y-34432D01*
X684048Y-34407D01*
X684059Y-34345D01*
X684073Y-34275D01*
X684099Y-34199D01*
X684132Y-34123D01*
X684175Y-34046D01*
Y-34043D01*
X684183Y-34039D01*
X684190Y-34028D01*
X684201Y-34013D01*
X684230Y-33977D01*
X684270Y-33930D01*
X684325Y-33882D01*
X684390Y-33828D01*
X684467Y-33780D01*
X684554Y-33737D01*
X684558D01*
X684565Y-33733D01*
X684579Y-33726D01*
X684598Y-33718D01*
X684623Y-33711D01*
X684656Y-33700D01*
X684692Y-33693D01*
X684732Y-33682D01*
X684780Y-33671D01*
X684834Y-33660D01*
X684893Y-33653D01*
X684954Y-33646D01*
X685023Y-33639D01*
X685096Y-33631D01*
X685176Y-33628D01*
X685260D01*
X685264D01*
X685282D01*
X685307D01*
X685340D01*
X685380Y-33631D01*
D02*
G37*
G36*
X685792Y-35571D02*
X685813Y-35579D01*
X685843Y-35590D01*
X685875Y-35600D01*
X685915Y-35615D01*
X685959Y-35633D01*
X686006Y-35655D01*
X686108Y-35706D01*
X686210Y-35772D01*
X686261Y-35811D01*
X686312Y-35852D01*
X686356Y-35895D01*
X686399Y-35946D01*
X686403Y-35950D01*
X686410Y-35957D01*
X686418Y-35975D01*
X686432Y-35993D01*
X686450Y-36023D01*
X686469Y-36052D01*
X686487Y-36092D01*
X686505Y-36132D01*
X686527Y-36179D01*
X686545Y-36230D01*
X686563Y-36285D01*
X686581Y-36343D01*
X686596Y-36405D01*
X686603Y-36470D01*
X686611Y-36540D01*
X686614Y-36612D01*
Y-36652D01*
X686611Y-36682D01*
Y-36714D01*
X686607Y-36754D01*
X686600Y-36798D01*
X686592Y-36849D01*
X686574Y-36955D01*
X686545Y-37064D01*
X686505Y-37173D01*
X686480Y-37224D01*
X686450Y-37275D01*
X686447Y-37278D01*
X686443Y-37286D01*
X686432Y-37300D01*
X686418Y-37315D01*
X686403Y-37337D01*
X686381Y-37362D01*
X686356Y-37391D01*
X686327Y-37420D01*
X686294Y-37449D01*
X686261Y-37482D01*
X686177Y-37548D01*
X686079Y-37610D01*
X685970Y-37664D01*
X685966D01*
X685955Y-37672D01*
X685937Y-37675D01*
X685915Y-37686D01*
X685886Y-37693D01*
X685850Y-37704D01*
X685810Y-37719D01*
X685766Y-37730D01*
X685719Y-37741D01*
X685664Y-37755D01*
X685551Y-37773D01*
X685424Y-37788D01*
X685293Y-37795D01*
X685289D01*
X685275D01*
X685253D01*
X685227Y-37792D01*
X685191D01*
X685155Y-37788D01*
X685107Y-37784D01*
X685060Y-37777D01*
X684954Y-37759D01*
X684838Y-37733D01*
X684721Y-37697D01*
X684609Y-37646D01*
X684605Y-37642D01*
X684594Y-37639D01*
X684579Y-37631D01*
X684561Y-37617D01*
X684536Y-37602D01*
X684507Y-37584D01*
X684441Y-37537D01*
X684368Y-37475D01*
X684296Y-37402D01*
X684223Y-37319D01*
X684161Y-37220D01*
X684157Y-37217D01*
X684154Y-37206D01*
X684146Y-37191D01*
X684135Y-37173D01*
X684124Y-37144D01*
X684114Y-37115D01*
X684099Y-37078D01*
X684084Y-37038D01*
X684070Y-36994D01*
X684055Y-36947D01*
X684033Y-36845D01*
X684015Y-36729D01*
X684008Y-36609D01*
Y-36572D01*
X684012Y-36547D01*
X684015Y-36514D01*
X684019Y-36474D01*
X684023Y-36434D01*
X684033Y-36387D01*
X684055Y-36288D01*
X684088Y-36179D01*
X684110Y-36125D01*
X684135Y-36074D01*
X684168Y-36023D01*
X684201Y-35972D01*
X684204Y-35968D01*
X684208Y-35961D01*
X684219Y-35946D01*
X684237Y-35928D01*
X684256Y-35910D01*
X684281Y-35884D01*
X684310Y-35859D01*
X684339Y-35830D01*
X684376Y-35801D01*
X684419Y-35772D01*
X684463Y-35739D01*
X684510Y-35710D01*
X684565Y-35684D01*
X684620Y-35655D01*
X684678Y-35633D01*
X684743Y-35611D01*
X684820Y-35939D01*
X684816D01*
X684809Y-35943D01*
X684794Y-35950D01*
X684776Y-35957D01*
X684754Y-35964D01*
X684725Y-35975D01*
X684667Y-36004D01*
X684601Y-36041D01*
X684536Y-36084D01*
X684474Y-36139D01*
X684419Y-36197D01*
X684412Y-36205D01*
X684397Y-36226D01*
X684379Y-36263D01*
X684354Y-36310D01*
X684332Y-36372D01*
X684310Y-36441D01*
X684296Y-36525D01*
X684292Y-36616D01*
Y-36645D01*
X684296Y-36663D01*
Y-36689D01*
X684299Y-36718D01*
X684310Y-36787D01*
X684325Y-36863D01*
X684350Y-36944D01*
X684386Y-37027D01*
X684434Y-37104D01*
Y-37107D01*
X684441Y-37111D01*
X684459Y-37137D01*
X684488Y-37169D01*
X684532Y-37209D01*
X684587Y-37257D01*
X684649Y-37300D01*
X684725Y-37340D01*
X684809Y-37377D01*
X684812D01*
X684820Y-37380D01*
X684831Y-37384D01*
X684849Y-37388D01*
X684871Y-37395D01*
X684896Y-37402D01*
X684958Y-37413D01*
X685031Y-37428D01*
X685111Y-37442D01*
X685198Y-37449D01*
X685293Y-37453D01*
X685296D01*
X685307D01*
X685326D01*
X685348D01*
X685373Y-37449D01*
X685406D01*
X685442Y-37446D01*
X685482Y-37442D01*
X685569Y-37431D01*
X685664Y-37413D01*
X685759Y-37391D01*
X685853Y-37362D01*
X685857D01*
X685864Y-37358D01*
X685875Y-37351D01*
X685893Y-37344D01*
X685937Y-37322D01*
X685988Y-37289D01*
X686046Y-37249D01*
X686108Y-37198D01*
X686163Y-37140D01*
X686214Y-37071D01*
Y-37067D01*
X686217Y-37060D01*
X686225Y-37049D01*
X686232Y-37035D01*
X686239Y-37016D01*
X686250Y-36994D01*
X686272Y-36944D01*
X686294Y-36878D01*
X686312Y-36805D01*
X686327Y-36725D01*
X686330Y-36641D01*
Y-36616D01*
X686327Y-36594D01*
Y-36569D01*
X686323Y-36543D01*
X686308Y-36478D01*
X686290Y-36401D01*
X686261Y-36325D01*
X686221Y-36245D01*
X686199Y-36205D01*
X686170Y-36168D01*
X686166Y-36165D01*
X686163Y-36161D01*
X686152Y-36150D01*
X686141Y-36136D01*
X686123Y-36121D01*
X686101Y-36103D01*
X686079Y-36081D01*
X686050Y-36063D01*
X686017Y-36041D01*
X685981Y-36015D01*
X685944Y-35993D01*
X685901Y-35972D01*
X685853Y-35954D01*
X685803Y-35935D01*
X685748Y-35917D01*
X685690Y-35903D01*
X685773Y-35568D01*
X685777D01*
X685792Y-35571D01*
D02*
G37*
G36*
X566603Y-243020D02*
X566636Y-243024D01*
X566676Y-243028D01*
X566716Y-243031D01*
X566763Y-243042D01*
X566861Y-243064D01*
X566970Y-243097D01*
X567025Y-243119D01*
X567076Y-243144D01*
X567127Y-243177D01*
X567178Y-243210D01*
X567182Y-243213D01*
X567189Y-243217D01*
X567203Y-243228D01*
X567222Y-243246D01*
X567240Y-243264D01*
X567265Y-243290D01*
X567291Y-243319D01*
X567320Y-243348D01*
X567349Y-243384D01*
X567378Y-243428D01*
X567411Y-243472D01*
X567440Y-243519D01*
X567465Y-243574D01*
X567495Y-243628D01*
X567517Y-243687D01*
X567538Y-243752D01*
X567211Y-243829D01*
Y-243825D01*
X567207Y-243818D01*
X567200Y-243803D01*
X567193Y-243785D01*
X567185Y-243763D01*
X567174Y-243734D01*
X567145Y-243676D01*
X567109Y-243610D01*
X567065Y-243545D01*
X567010Y-243483D01*
X566952Y-243428D01*
X566945Y-243421D01*
X566923Y-243406D01*
X566887Y-243388D01*
X566840Y-243363D01*
X566778Y-243341D01*
X566708Y-243319D01*
X566625Y-243304D01*
X566534Y-243301D01*
X566505D01*
X566486Y-243304D01*
X566461D01*
X566432Y-243308D01*
X566363Y-243319D01*
X566286Y-243333D01*
X566206Y-243359D01*
X566122Y-243395D01*
X566046Y-243443D01*
X566042D01*
X566039Y-243450D01*
X566013Y-243468D01*
X565980Y-243497D01*
X565940Y-243541D01*
X565893Y-243596D01*
X565849Y-243657D01*
X565809Y-243734D01*
X565773Y-243818D01*
Y-243821D01*
X565769Y-243829D01*
X565766Y-243839D01*
X565762Y-243858D01*
X565755Y-243879D01*
X565747Y-243905D01*
X565736Y-243967D01*
X565722Y-244040D01*
X565707Y-244120D01*
X565700Y-244207D01*
X565696Y-244302D01*
Y-244305D01*
Y-244316D01*
Y-244335D01*
Y-244356D01*
X565700Y-244382D01*
Y-244414D01*
X565704Y-244451D01*
X565707Y-244491D01*
X565718Y-244578D01*
X565736Y-244673D01*
X565758Y-244768D01*
X565788Y-244862D01*
Y-244866D01*
X565791Y-244873D01*
X565798Y-244884D01*
X565806Y-244902D01*
X565828Y-244946D01*
X565860Y-244997D01*
X565900Y-245055D01*
X565951Y-245117D01*
X566010Y-245172D01*
X566079Y-245223D01*
X566082D01*
X566090Y-245226D01*
X566101Y-245233D01*
X566115Y-245241D01*
X566133Y-245248D01*
X566155Y-245259D01*
X566206Y-245281D01*
X566272Y-245303D01*
X566344Y-245321D01*
X566425Y-245335D01*
X566508Y-245339D01*
X566534D01*
X566556Y-245335D01*
X566581D01*
X566607Y-245332D01*
X566672Y-245317D01*
X566748Y-245299D01*
X566825Y-245270D01*
X566905Y-245230D01*
X566945Y-245208D01*
X566981Y-245179D01*
X566985Y-245175D01*
X566989Y-245172D01*
X567000Y-245161D01*
X567014Y-245150D01*
X567029Y-245132D01*
X567047Y-245110D01*
X567069Y-245088D01*
X567087Y-245059D01*
X567109Y-245026D01*
X567134Y-244990D01*
X567156Y-244953D01*
X567178Y-244910D01*
X567196Y-244862D01*
X567214Y-244811D01*
X567233Y-244757D01*
X567247Y-244699D01*
X567582Y-244782D01*
Y-244786D01*
X567578Y-244800D01*
X567571Y-244822D01*
X567560Y-244851D01*
X567549Y-244884D01*
X567535Y-244924D01*
X567517Y-244968D01*
X567495Y-245015D01*
X567444Y-245117D01*
X567378Y-245219D01*
X567338Y-245270D01*
X567298Y-245321D01*
X567254Y-245365D01*
X567203Y-245408D01*
X567200Y-245412D01*
X567193Y-245419D01*
X567174Y-245427D01*
X567156Y-245441D01*
X567127Y-245459D01*
X567098Y-245477D01*
X567058Y-245496D01*
X567018Y-245514D01*
X566970Y-245536D01*
X566920Y-245554D01*
X566865Y-245572D01*
X566807Y-245590D01*
X566745Y-245605D01*
X566679Y-245612D01*
X566610Y-245619D01*
X566537Y-245623D01*
X566497D01*
X566468Y-245619D01*
X566435D01*
X566395Y-245616D01*
X566352Y-245608D01*
X566301Y-245601D01*
X566195Y-245583D01*
X566086Y-245554D01*
X565977Y-245514D01*
X565926Y-245488D01*
X565875Y-245459D01*
X565871Y-245456D01*
X565864Y-245452D01*
X565849Y-245441D01*
X565835Y-245427D01*
X565813Y-245412D01*
X565788Y-245390D01*
X565758Y-245365D01*
X565729Y-245335D01*
X565700Y-245303D01*
X565667Y-245270D01*
X565602Y-245186D01*
X565540Y-245088D01*
X565485Y-244979D01*
Y-244975D01*
X565478Y-244964D01*
X565474Y-244946D01*
X565463Y-244924D01*
X565456Y-244895D01*
X565445Y-244859D01*
X565431Y-244819D01*
X565420Y-244775D01*
X565409Y-244728D01*
X565394Y-244673D01*
X565376Y-244560D01*
X565362Y-244433D01*
X565354Y-244302D01*
Y-244298D01*
Y-244284D01*
Y-244262D01*
X565358Y-244236D01*
Y-244200D01*
X565362Y-244163D01*
X565365Y-244116D01*
X565373Y-244069D01*
X565391Y-243963D01*
X565416Y-243847D01*
X565453Y-243730D01*
X565504Y-243617D01*
X565507Y-243614D01*
X565511Y-243603D01*
X565518Y-243588D01*
X565533Y-243570D01*
X565547Y-243545D01*
X565565Y-243515D01*
X565613Y-243450D01*
X565675Y-243377D01*
X565747Y-243304D01*
X565831Y-243232D01*
X565929Y-243170D01*
X565933Y-243166D01*
X565944Y-243162D01*
X565959Y-243155D01*
X565977Y-243144D01*
X566006Y-243133D01*
X566035Y-243122D01*
X566071Y-243108D01*
X566111Y-243093D01*
X566155Y-243079D01*
X566202Y-243064D01*
X566304Y-243042D01*
X566421Y-243024D01*
X566541Y-243017D01*
X566577D01*
X566603Y-243020D01*
D02*
G37*
G36*
X571375Y-243388D02*
X570367D01*
X570232Y-244069D01*
X570236Y-244065D01*
X570243Y-244061D01*
X570254Y-244054D01*
X570272Y-244043D01*
X570294Y-244032D01*
X570319Y-244018D01*
X570377Y-243989D01*
X570450Y-243959D01*
X570530Y-243934D01*
X570618Y-243916D01*
X570661Y-243909D01*
X570742D01*
X570763Y-243912D01*
X570792Y-243916D01*
X570825Y-243919D01*
X570862Y-243927D01*
X570902Y-243938D01*
X570989Y-243963D01*
X571036Y-243981D01*
X571084Y-244007D01*
X571131Y-244032D01*
X571178Y-244061D01*
X571222Y-244098D01*
X571266Y-244138D01*
X571269Y-244142D01*
X571277Y-244149D01*
X571287Y-244160D01*
X571302Y-244178D01*
X571320Y-244203D01*
X571339Y-244229D01*
X571360Y-244262D01*
X571382Y-244298D01*
X571400Y-244338D01*
X571422Y-244382D01*
X571440Y-244433D01*
X571459Y-244484D01*
X571473Y-244538D01*
X571484Y-244600D01*
X571491Y-244662D01*
X571495Y-244728D01*
Y-244731D01*
Y-244742D01*
Y-244760D01*
X571491Y-244786D01*
X571488Y-244815D01*
X571484Y-244848D01*
X571477Y-244888D01*
X571469Y-244928D01*
X571448Y-245022D01*
X571411Y-245121D01*
X571389Y-245172D01*
X571360Y-245219D01*
X571331Y-245270D01*
X571295Y-245317D01*
X571291Y-245321D01*
X571284Y-245332D01*
X571269Y-245346D01*
X571251Y-245365D01*
X571226Y-245386D01*
X571197Y-245415D01*
X571160Y-245441D01*
X571120Y-245470D01*
X571076Y-245499D01*
X571026Y-245525D01*
X570971Y-245550D01*
X570913Y-245576D01*
X570851Y-245594D01*
X570782Y-245608D01*
X570709Y-245619D01*
X570632Y-245623D01*
X570600D01*
X570574Y-245619D01*
X570545Y-245616D01*
X570512Y-245612D01*
X570472Y-245608D01*
X570432Y-245598D01*
X570341Y-245576D01*
X570250Y-245543D01*
X570203Y-245521D01*
X570155Y-245496D01*
X570112Y-245466D01*
X570068Y-245434D01*
X570064Y-245430D01*
X570057Y-245427D01*
X570050Y-245412D01*
X570035Y-245397D01*
X570017Y-245379D01*
X569999Y-245357D01*
X569977Y-245328D01*
X569959Y-245295D01*
X569937Y-245263D01*
X569915Y-245223D01*
X569875Y-245135D01*
X569842Y-245033D01*
X569832Y-244979D01*
X569824Y-244920D01*
X570148Y-244895D01*
Y-244899D01*
Y-244906D01*
X570152Y-244917D01*
X570155Y-244935D01*
X570166Y-244975D01*
X570181Y-245030D01*
X570203Y-245084D01*
X570232Y-245146D01*
X570268Y-245201D01*
X570312Y-245252D01*
X570319Y-245255D01*
X570334Y-245270D01*
X570363Y-245288D01*
X570403Y-245310D01*
X570447Y-245332D01*
X570501Y-245350D01*
X570563Y-245365D01*
X570632Y-245368D01*
X570654D01*
X570669Y-245365D01*
X570712Y-245361D01*
X570763Y-245346D01*
X570825Y-245328D01*
X570887Y-245299D01*
X570953Y-245255D01*
X570982Y-245230D01*
X571011Y-245201D01*
X571014Y-245197D01*
X571018Y-245194D01*
X571026Y-245183D01*
X571036Y-245172D01*
X571062Y-245132D01*
X571091Y-245081D01*
X571116Y-245019D01*
X571142Y-244942D01*
X571160Y-244851D01*
X571167Y-244804D01*
Y-244753D01*
Y-244749D01*
Y-244742D01*
Y-244728D01*
X571164Y-244709D01*
Y-244688D01*
X571160Y-244662D01*
X571149Y-244604D01*
X571131Y-244535D01*
X571105Y-244465D01*
X571069Y-244400D01*
X571018Y-244338D01*
Y-244335D01*
X571011Y-244331D01*
X570993Y-244313D01*
X570960Y-244287D01*
X570916Y-244258D01*
X570858Y-244233D01*
X570792Y-244207D01*
X570716Y-244189D01*
X570672Y-244182D01*
X570603D01*
X570574Y-244185D01*
X570538Y-244189D01*
X570494Y-244200D01*
X570450Y-244211D01*
X570403Y-244229D01*
X570356Y-244251D01*
X570352Y-244254D01*
X570337Y-244262D01*
X570316Y-244280D01*
X570287Y-244298D01*
X570257Y-244323D01*
X570228Y-244356D01*
X570195Y-244389D01*
X570170Y-244429D01*
X569879Y-244389D01*
X570123Y-243093D01*
X571375D01*
Y-243388D01*
D02*
G37*
G36*
X569519Y-243337D02*
X569515Y-243341D01*
X569508Y-243348D01*
X569493Y-243363D01*
X569478Y-243384D01*
X569457Y-243410D01*
X569427Y-243439D01*
X569398Y-243475D01*
X569366Y-243519D01*
X569333Y-243563D01*
X569293Y-243614D01*
X569253Y-243672D01*
X569213Y-243730D01*
X569169Y-243796D01*
X569125Y-243865D01*
X569082Y-243941D01*
X569038Y-244018D01*
X569034Y-244021D01*
X569027Y-244036D01*
X569016Y-244058D01*
X568998Y-244091D01*
X568980Y-244131D01*
X568958Y-244174D01*
X568932Y-244225D01*
X568907Y-244284D01*
X568878Y-244349D01*
X568845Y-244414D01*
X568816Y-244487D01*
X568787Y-244564D01*
X568729Y-244720D01*
X568674Y-244888D01*
Y-244891D01*
X568670Y-244902D01*
X568667Y-244920D01*
X568659Y-244942D01*
X568652Y-244971D01*
X568645Y-245008D01*
X568634Y-245048D01*
X568627Y-245092D01*
X568616Y-245143D01*
X568605Y-245197D01*
X568587Y-245314D01*
X568569Y-245441D01*
X568558Y-245579D01*
X568241D01*
Y-245576D01*
Y-245565D01*
Y-245550D01*
X568245Y-245528D01*
Y-245499D01*
X568248Y-245463D01*
X568252Y-245423D01*
X568255Y-245379D01*
X568263Y-245328D01*
X568270Y-245277D01*
X568281Y-245215D01*
X568292Y-245153D01*
X568303Y-245088D01*
X568317Y-245015D01*
X568354Y-244866D01*
Y-244862D01*
X568357Y-244848D01*
X568365Y-244826D01*
X568375Y-244793D01*
X568386Y-244757D01*
X568401Y-244713D01*
X568416Y-244662D01*
X568437Y-244607D01*
X568459Y-244546D01*
X568481Y-244484D01*
X568536Y-244345D01*
X568601Y-244200D01*
X568674Y-244054D01*
X568678Y-244051D01*
X568685Y-244036D01*
X568696Y-244018D01*
X568710Y-243989D01*
X568729Y-243956D01*
X568754Y-243916D01*
X568780Y-243872D01*
X568809Y-243825D01*
X568878Y-243719D01*
X568951Y-243610D01*
X569034Y-243497D01*
X569122Y-243392D01*
X567888D01*
Y-243093D01*
X569519D01*
Y-243337D01*
D02*
G37*
G36*
X615733Y-273458D02*
X615762Y-273462D01*
X615799Y-273465D01*
X615839Y-273473D01*
X615879Y-273480D01*
X615973Y-273505D01*
X616068Y-273542D01*
X616115Y-273564D01*
X616162Y-273589D01*
X616206Y-273622D01*
X616246Y-273658D01*
X616250Y-273662D01*
X616257Y-273666D01*
X616264Y-273680D01*
X616279Y-273695D01*
X616297Y-273713D01*
X616315Y-273738D01*
X616334Y-273764D01*
X616355Y-273797D01*
X616392Y-273866D01*
X616428Y-273953D01*
X616443Y-273997D01*
X616450Y-274048D01*
X616457Y-274099D01*
X616461Y-274153D01*
Y-274161D01*
Y-274179D01*
X616457Y-274208D01*
X616454Y-274248D01*
X616446Y-274292D01*
X616432Y-274343D01*
X616417Y-274397D01*
X616396Y-274452D01*
X616392Y-274459D01*
X616385Y-274477D01*
X616370Y-274506D01*
X616348Y-274547D01*
X616319Y-274590D01*
X616283Y-274645D01*
X616239Y-274699D01*
X616188Y-274761D01*
X616181Y-274768D01*
X616162Y-274790D01*
X616144Y-274809D01*
X616126Y-274827D01*
X616104Y-274849D01*
X616075Y-274878D01*
X616046Y-274907D01*
X616010Y-274940D01*
X615973Y-274976D01*
X615930Y-275016D01*
X615882Y-275056D01*
X615831Y-275103D01*
X615773Y-275151D01*
X615715Y-275202D01*
X615711Y-275205D01*
X615704Y-275213D01*
X615689Y-275223D01*
X615671Y-275238D01*
X615649Y-275260D01*
X615624Y-275282D01*
X615566Y-275329D01*
X615504Y-275384D01*
X615445Y-275438D01*
X615394Y-275486D01*
X615373Y-275504D01*
X615354Y-275522D01*
X615351Y-275526D01*
X615340Y-275537D01*
X615325Y-275551D01*
X615307Y-275573D01*
X615289Y-275599D01*
X615267Y-275624D01*
X615223Y-275686D01*
X616465D01*
Y-275984D01*
X614794D01*
Y-275981D01*
Y-275966D01*
Y-275944D01*
X614797Y-275915D01*
X614801Y-275882D01*
X614808Y-275846D01*
X614816Y-275810D01*
X614830Y-275769D01*
Y-275766D01*
X614834Y-275762D01*
X614841Y-275740D01*
X614856Y-275708D01*
X614878Y-275664D01*
X614907Y-275613D01*
X614943Y-275555D01*
X614983Y-275497D01*
X615034Y-275435D01*
Y-275431D01*
X615041Y-275427D01*
X615060Y-275406D01*
X615092Y-275373D01*
X615140Y-275325D01*
X615194Y-275271D01*
X615263Y-275205D01*
X615347Y-275132D01*
X615438Y-275056D01*
X615442Y-275052D01*
X615456Y-275042D01*
X615478Y-275023D01*
X615504Y-275002D01*
X615536Y-274972D01*
X615577Y-274940D01*
X615617Y-274903D01*
X615664Y-274863D01*
X615755Y-274776D01*
X615846Y-274689D01*
X615890Y-274645D01*
X615930Y-274601D01*
X615966Y-274561D01*
X615995Y-274521D01*
Y-274517D01*
X616002Y-274514D01*
X616010Y-274503D01*
X616017Y-274488D01*
X616042Y-274448D01*
X616072Y-274401D01*
X616097Y-274343D01*
X616122Y-274281D01*
X616137Y-274212D01*
X616144Y-274146D01*
Y-274143D01*
Y-274139D01*
X616141Y-274117D01*
X616137Y-274081D01*
X616126Y-274041D01*
X616112Y-273990D01*
X616086Y-273939D01*
X616053Y-273888D01*
X616010Y-273837D01*
X616002Y-273829D01*
X615984Y-273815D01*
X615959Y-273797D01*
X615919Y-273771D01*
X615868Y-273749D01*
X615809Y-273727D01*
X615740Y-273713D01*
X615664Y-273709D01*
X615642D01*
X615627Y-273713D01*
X615584Y-273717D01*
X615533Y-273727D01*
X615478Y-273742D01*
X615416Y-273767D01*
X615358Y-273800D01*
X615304Y-273844D01*
X615296Y-273851D01*
X615282Y-273869D01*
X615260Y-273899D01*
X615238Y-273942D01*
X615212Y-273993D01*
X615191Y-274059D01*
X615176Y-274131D01*
X615169Y-274215D01*
X614852Y-274183D01*
Y-274179D01*
X614856Y-274168D01*
Y-274150D01*
X614859Y-274124D01*
X614867Y-274095D01*
X614874Y-274062D01*
X614885Y-274022D01*
X614896Y-273982D01*
X614925Y-273895D01*
X614969Y-273808D01*
X614994Y-273764D01*
X615027Y-273720D01*
X615060Y-273680D01*
X615096Y-273644D01*
X615100Y-273640D01*
X615107Y-273637D01*
X615118Y-273626D01*
X615136Y-273615D01*
X615158Y-273600D01*
X615183Y-273586D01*
X615212Y-273567D01*
X615249Y-273549D01*
X615289Y-273531D01*
X615333Y-273513D01*
X615380Y-273498D01*
X615431Y-273484D01*
X615485Y-273473D01*
X615544Y-273462D01*
X615606Y-273458D01*
X615671Y-273454D01*
X615707D01*
X615733Y-273458D01*
D02*
G37*
G36*
X613327Y-275686D02*
X614568D01*
Y-275984D01*
X612992D01*
Y-273465D01*
X613327D01*
Y-275686D01*
D02*
G37*
G36*
X686221Y-324960D02*
X685052D01*
X685023Y-324956D01*
X684990D01*
X684914Y-324953D01*
X684834Y-324942D01*
X684746Y-324931D01*
X684666Y-324913D01*
X684626Y-324902D01*
X684593Y-324891D01*
X684590D01*
X684586Y-324887D01*
X684564Y-324876D01*
X684531Y-324862D01*
X684491Y-324836D01*
X684448Y-324803D01*
X684401Y-324760D01*
X684357Y-324709D01*
X684313Y-324650D01*
Y-324647D01*
X684309Y-324643D01*
X684295Y-324621D01*
X684280Y-324585D01*
X684259Y-324538D01*
X684240Y-324483D01*
X684222Y-324417D01*
X684211Y-324348D01*
X684208Y-324272D01*
Y-324268D01*
Y-324261D01*
Y-324246D01*
X684211Y-324228D01*
Y-324203D01*
X684215Y-324177D01*
X684229Y-324115D01*
X684251Y-324043D01*
X684280Y-323966D01*
X684324Y-323890D01*
X684353Y-323853D01*
X684382Y-323817D01*
X684386Y-323813D01*
X684390Y-323810D01*
X684401Y-323799D01*
X684415Y-323788D01*
X684433Y-323773D01*
X684455Y-323759D01*
X684484Y-323740D01*
X684513Y-323719D01*
X684550Y-323700D01*
X684590Y-323682D01*
X684633Y-323660D01*
X684681Y-323642D01*
X684735Y-323628D01*
X684790Y-323609D01*
X684852Y-323598D01*
X684917Y-323587D01*
X684910Y-323584D01*
X684896Y-323577D01*
X684874Y-323562D01*
X684845Y-323548D01*
X684779Y-323507D01*
X684746Y-323482D01*
X684717Y-323460D01*
X684710Y-323453D01*
X684692Y-323435D01*
X684663Y-323406D01*
X684626Y-323369D01*
X684586Y-323318D01*
X684539Y-323264D01*
X684491Y-323198D01*
X684441Y-323125D01*
X684007Y-322441D01*
X684422D01*
X684754Y-322965D01*
Y-322969D01*
X684761Y-322976D01*
X684768Y-322987D01*
X684779Y-323002D01*
X684804Y-323042D01*
X684837Y-323093D01*
X684877Y-323147D01*
X684917Y-323205D01*
X684957Y-323260D01*
X684994Y-323311D01*
X684998Y-323314D01*
X685008Y-323329D01*
X685027Y-323351D01*
X685052Y-323376D01*
X685107Y-323431D01*
X685136Y-323457D01*
X685165Y-323478D01*
X685169Y-323482D01*
X685176Y-323486D01*
X685190Y-323493D01*
X685212Y-323504D01*
X685234Y-323515D01*
X685259Y-323526D01*
X685318Y-323544D01*
X685321D01*
X685329Y-323548D01*
X685343D01*
X685361Y-323551D01*
X685387Y-323555D01*
X685416D01*
X685456Y-323558D01*
X685886D01*
Y-322441D01*
X686221D01*
Y-324960D01*
D02*
G37*
G36*
X682955Y-324410D02*
X682959Y-324407D01*
X682977Y-324392D01*
X682999Y-324370D01*
X683036Y-324345D01*
X683076Y-324312D01*
X683126Y-324275D01*
X683185Y-324235D01*
X683250Y-324195D01*
X683254D01*
X683257Y-324192D01*
X683279Y-324177D01*
X683316Y-324159D01*
X683359Y-324137D01*
X683410Y-324112D01*
X683465Y-324086D01*
X683520Y-324061D01*
X683574Y-324039D01*
Y-324337D01*
X683571D01*
X683563Y-324345D01*
X683549Y-324348D01*
X683531Y-324359D01*
X683509Y-324370D01*
X683483Y-324385D01*
X683421Y-324421D01*
X683349Y-324461D01*
X683276Y-324512D01*
X683199Y-324570D01*
X683123Y-324632D01*
X683119Y-324636D01*
X683116Y-324640D01*
X683105Y-324650D01*
X683090Y-324661D01*
X683057Y-324698D01*
X683014Y-324741D01*
X682970Y-324792D01*
X682923Y-324851D01*
X682883Y-324909D01*
X682846Y-324971D01*
X682646D01*
Y-322441D01*
X682955D01*
Y-324410D01*
D02*
G37*
G36*
X672835Y-325006D02*
X671866D01*
X671801Y-325003D01*
X671728Y-324999D01*
X671655Y-324992D01*
X671583Y-324981D01*
X671521Y-324970D01*
X671517D01*
X671510Y-324966D01*
X671499D01*
X671484Y-324959D01*
X671444Y-324948D01*
X671393Y-324930D01*
X671335Y-324904D01*
X671273Y-324871D01*
X671211Y-324835D01*
X671153Y-324788D01*
X671149Y-324784D01*
X671146Y-324781D01*
X671135Y-324769D01*
X671120Y-324759D01*
X671084Y-324722D01*
X671040Y-324671D01*
X670993Y-324609D01*
X670942Y-324537D01*
X670894Y-324453D01*
X670855Y-324358D01*
Y-324355D01*
X670851Y-324347D01*
X670844Y-324333D01*
X670840Y-324311D01*
X670829Y-324285D01*
X670822Y-324256D01*
X670815Y-324223D01*
X670803Y-324184D01*
X670793Y-324143D01*
X670785Y-324096D01*
X670767Y-323994D01*
X670756Y-323881D01*
X670753Y-323758D01*
Y-323754D01*
Y-323747D01*
Y-323728D01*
Y-323710D01*
X670756Y-323685D01*
Y-323656D01*
X670760Y-323587D01*
X670771Y-323506D01*
X670782Y-323423D01*
X670800Y-323335D01*
X670822Y-323248D01*
Y-323244D01*
X670825Y-323237D01*
X670829Y-323226D01*
X670833Y-323212D01*
X670847Y-323172D01*
X670869Y-323121D01*
X670891Y-323062D01*
X670920Y-323004D01*
X670956Y-322942D01*
X670993Y-322884D01*
X670997Y-322877D01*
X671011Y-322859D01*
X671033Y-322833D01*
X671062Y-322800D01*
X671095Y-322764D01*
X671135Y-322727D01*
X671175Y-322687D01*
X671222Y-322655D01*
X671229Y-322651D01*
X671244Y-322640D01*
X671269Y-322626D01*
X671306Y-322607D01*
X671349Y-322586D01*
X671400Y-322567D01*
X671459Y-322546D01*
X671524Y-322527D01*
X671531D01*
X671543Y-322524D01*
X671553Y-322520D01*
X671590Y-322516D01*
X671641Y-322509D01*
X671699Y-322502D01*
X671768Y-322495D01*
X671845Y-322491D01*
X671928Y-322487D01*
X672835D01*
Y-325006D01*
D02*
G37*
G36*
X669431Y-323092D02*
X670527D01*
Y-323375D01*
X669373Y-325006D01*
X669122D01*
Y-323375D01*
X668780D01*
Y-323092D01*
X669122D01*
Y-322487D01*
X669431D01*
Y-323092D01*
D02*
G37*
G36*
X672835Y-317569D02*
X671866D01*
X671801Y-317566D01*
X671728Y-317562D01*
X671655Y-317555D01*
X671583Y-317544D01*
X671521Y-317533D01*
X671517D01*
X671510Y-317529D01*
X671499D01*
X671484Y-317522D01*
X671444Y-317511D01*
X671393Y-317493D01*
X671335Y-317468D01*
X671273Y-317435D01*
X671211Y-317398D01*
X671153Y-317351D01*
X671149Y-317347D01*
X671146Y-317344D01*
X671135Y-317333D01*
X671120Y-317322D01*
X671084Y-317286D01*
X671040Y-317235D01*
X670993Y-317173D01*
X670942Y-317100D01*
X670894Y-317016D01*
X670855Y-316922D01*
Y-316918D01*
X670851Y-316911D01*
X670844Y-316896D01*
X670840Y-316874D01*
X670829Y-316849D01*
X670822Y-316820D01*
X670814Y-316787D01*
X670803Y-316747D01*
X670793Y-316707D01*
X670785Y-316659D01*
X670767Y-316558D01*
X670756Y-316445D01*
X670752Y-316321D01*
Y-316317D01*
Y-316310D01*
Y-316292D01*
Y-316274D01*
X670756Y-316248D01*
Y-316219D01*
X670760Y-316150D01*
X670771Y-316070D01*
X670782Y-315986D01*
X670800Y-315899D01*
X670822Y-315811D01*
Y-315808D01*
X670825Y-315800D01*
X670829Y-315790D01*
X670833Y-315775D01*
X670847Y-315735D01*
X670869Y-315684D01*
X670891Y-315626D01*
X670920Y-315567D01*
X670956Y-315506D01*
X670993Y-315447D01*
X670996Y-315440D01*
X671011Y-315422D01*
X671033Y-315396D01*
X671062Y-315364D01*
X671095Y-315327D01*
X671135Y-315291D01*
X671175Y-315251D01*
X671222Y-315218D01*
X671229Y-315214D01*
X671244Y-315203D01*
X671269Y-315189D01*
X671306Y-315171D01*
X671349Y-315149D01*
X671400Y-315131D01*
X671459Y-315109D01*
X671524Y-315091D01*
X671531D01*
X671542Y-315087D01*
X671553Y-315083D01*
X671590Y-315080D01*
X671641Y-315072D01*
X671699Y-315065D01*
X671768Y-315058D01*
X671844Y-315054D01*
X671928Y-315051D01*
X672835D01*
Y-317569D01*
D02*
G37*
G36*
X670465Y-315054D02*
Y-315069D01*
Y-315091D01*
X670461Y-315120D01*
X670458Y-315153D01*
X670450Y-315189D01*
X670443Y-315225D01*
X670429Y-315265D01*
Y-315269D01*
X670425Y-315273D01*
X670418Y-315295D01*
X670403Y-315327D01*
X670381Y-315371D01*
X670352Y-315422D01*
X670316Y-315480D01*
X670276Y-315538D01*
X670225Y-315600D01*
Y-315604D01*
X670218Y-315608D01*
X670199Y-315629D01*
X670166Y-315662D01*
X670119Y-315709D01*
X670065Y-315764D01*
X669995Y-315830D01*
X669912Y-315902D01*
X669821Y-315979D01*
X669817Y-315983D01*
X669803Y-315993D01*
X669781Y-316012D01*
X669755Y-316033D01*
X669722Y-316062D01*
X669682Y-316095D01*
X669642Y-316132D01*
X669595Y-316172D01*
X669504Y-316259D01*
X669413Y-316347D01*
X669369Y-316390D01*
X669329Y-316434D01*
X669293Y-316474D01*
X669264Y-316514D01*
Y-316517D01*
X669256Y-316521D01*
X669249Y-316532D01*
X669242Y-316547D01*
X669216Y-316587D01*
X669187Y-316634D01*
X669162Y-316692D01*
X669136Y-316754D01*
X669122Y-316823D01*
X669114Y-316889D01*
Y-316893D01*
Y-316896D01*
X669118Y-316918D01*
X669122Y-316954D01*
X669133Y-316994D01*
X669147Y-317045D01*
X669173Y-317096D01*
X669206Y-317147D01*
X669249Y-317198D01*
X669256Y-317206D01*
X669275Y-317220D01*
X669300Y-317238D01*
X669340Y-317264D01*
X669391Y-317286D01*
X669449Y-317307D01*
X669519Y-317322D01*
X669595Y-317326D01*
X669617D01*
X669631Y-317322D01*
X669675Y-317318D01*
X669726Y-317307D01*
X669781Y-317293D01*
X669842Y-317267D01*
X669901Y-317235D01*
X669955Y-317191D01*
X669963Y-317184D01*
X669977Y-317165D01*
X669999Y-317136D01*
X670021Y-317093D01*
X670046Y-317042D01*
X670068Y-316976D01*
X670083Y-316903D01*
X670090Y-316820D01*
X670407Y-316852D01*
Y-316856D01*
X670403Y-316867D01*
Y-316885D01*
X670400Y-316911D01*
X670392Y-316940D01*
X670385Y-316972D01*
X670374Y-317013D01*
X670363Y-317053D01*
X670334Y-317140D01*
X670290Y-317227D01*
X670265Y-317271D01*
X670232Y-317315D01*
X670199Y-317355D01*
X670163Y-317391D01*
X670159Y-317395D01*
X670152Y-317398D01*
X670141Y-317409D01*
X670123Y-317420D01*
X670101Y-317435D01*
X670076Y-317449D01*
X670046Y-317468D01*
X670010Y-317486D01*
X669970Y-317504D01*
X669926Y-317522D01*
X669879Y-317537D01*
X669828Y-317551D01*
X669773Y-317562D01*
X669715Y-317573D01*
X669653Y-317577D01*
X669588Y-317580D01*
X669551D01*
X669526Y-317577D01*
X669497Y-317573D01*
X669460Y-317569D01*
X669420Y-317562D01*
X669380Y-317555D01*
X669286Y-317529D01*
X669191Y-317493D01*
X669144Y-317471D01*
X669096Y-317446D01*
X669053Y-317413D01*
X669013Y-317377D01*
X669009Y-317373D01*
X669002Y-317369D01*
X668994Y-317355D01*
X668980Y-317340D01*
X668962Y-317322D01*
X668944Y-317297D01*
X668925Y-317271D01*
X668903Y-317238D01*
X668867Y-317169D01*
X668831Y-317082D01*
X668816Y-317038D01*
X668809Y-316987D01*
X668801Y-316936D01*
X668798Y-316881D01*
Y-316874D01*
Y-316856D01*
X668801Y-316827D01*
X668805Y-316787D01*
X668812Y-316743D01*
X668827Y-316692D01*
X668842Y-316638D01*
X668863Y-316583D01*
X668867Y-316576D01*
X668874Y-316558D01*
X668889Y-316529D01*
X668911Y-316488D01*
X668940Y-316445D01*
X668976Y-316390D01*
X669020Y-316336D01*
X669071Y-316274D01*
X669078Y-316266D01*
X669096Y-316245D01*
X669114Y-316226D01*
X669133Y-316208D01*
X669155Y-316186D01*
X669184Y-316157D01*
X669213Y-316128D01*
X669249Y-316095D01*
X669286Y-316059D01*
X669329Y-316019D01*
X669377Y-315979D01*
X669428Y-315932D01*
X669486Y-315884D01*
X669544Y-315833D01*
X669548Y-315830D01*
X669555Y-315822D01*
X669569Y-315811D01*
X669588Y-315797D01*
X669610Y-315775D01*
X669635Y-315753D01*
X669693Y-315706D01*
X669755Y-315651D01*
X669813Y-315597D01*
X669864Y-315549D01*
X669886Y-315531D01*
X669904Y-315513D01*
X669908Y-315509D01*
X669919Y-315498D01*
X669934Y-315484D01*
X669952Y-315462D01*
X669970Y-315437D01*
X669992Y-315411D01*
X670036Y-315349D01*
X668794D01*
Y-315051D01*
X670465D01*
Y-315054D01*
D02*
G37*
G36*
X667702Y-315011D02*
X667731Y-315014D01*
X667768Y-315021D01*
X667808Y-315029D01*
X667851Y-315040D01*
X667895Y-315054D01*
X667942Y-315069D01*
X667990Y-315091D01*
X668037Y-315116D01*
X668084Y-315145D01*
X668132Y-315182D01*
X668175Y-315222D01*
X668216Y-315265D01*
X668219Y-315269D01*
X668226Y-315280D01*
X668237Y-315298D01*
X668256Y-315327D01*
X668274Y-315360D01*
X668292Y-315404D01*
X668317Y-315455D01*
X668339Y-315513D01*
X668361Y-315578D01*
X668383Y-315655D01*
X668405Y-315739D01*
X668423Y-315833D01*
X668441Y-315935D01*
X668452Y-316044D01*
X668459Y-316164D01*
X668463Y-316292D01*
Y-316296D01*
Y-316310D01*
Y-316336D01*
Y-316365D01*
X668459Y-316405D01*
Y-316448D01*
X668456Y-316496D01*
X668452Y-316550D01*
X668441Y-316663D01*
X668423Y-316783D01*
X668401Y-316903D01*
X668387Y-316958D01*
X668372Y-317013D01*
Y-317016D01*
X668368Y-317023D01*
X668361Y-317038D01*
X668354Y-317056D01*
X668347Y-317082D01*
X668332Y-317107D01*
X668303Y-317169D01*
X668266Y-317235D01*
X668219Y-317304D01*
X668164Y-317373D01*
X668099Y-317431D01*
X668095D01*
X668092Y-317439D01*
X668081Y-317446D01*
X668066Y-317453D01*
X668048Y-317468D01*
X668026Y-317478D01*
X667972Y-317508D01*
X667906Y-317533D01*
X667830Y-317559D01*
X667739Y-317573D01*
X667640Y-317580D01*
X667608D01*
X667567Y-317577D01*
X667520Y-317569D01*
X667466Y-317559D01*
X667407Y-317544D01*
X667346Y-317526D01*
X667287Y-317497D01*
X667284D01*
X667280Y-317493D01*
X667262Y-317482D01*
X667233Y-317464D01*
X667196Y-317439D01*
X667156Y-317402D01*
X667112Y-317362D01*
X667072Y-317315D01*
X667032Y-317260D01*
X667029Y-317253D01*
X667014Y-317235D01*
X667000Y-317202D01*
X666974Y-317155D01*
X666952Y-317100D01*
X666923Y-317038D01*
X666898Y-316965D01*
X666876Y-316885D01*
Y-316881D01*
X666872Y-316874D01*
X666869Y-316863D01*
X666865Y-316845D01*
X666861Y-316823D01*
X666858Y-316798D01*
X666851Y-316765D01*
X666847Y-316729D01*
X666840Y-316689D01*
X666836Y-316645D01*
X666832Y-316594D01*
X666825Y-316543D01*
X666821Y-316485D01*
Y-316426D01*
X666818Y-316361D01*
Y-316292D01*
Y-316288D01*
Y-316274D01*
Y-316248D01*
Y-316219D01*
X666821Y-316179D01*
Y-316135D01*
X666825Y-316088D01*
X666829Y-316037D01*
X666840Y-315921D01*
X666858Y-315800D01*
X666880Y-315684D01*
X666894Y-315629D01*
X666912Y-315575D01*
Y-315571D01*
X666916Y-315564D01*
X666923Y-315549D01*
X666930Y-315531D01*
X666938Y-315506D01*
X666952Y-315480D01*
X666982Y-315418D01*
X667018Y-315353D01*
X667065Y-315280D01*
X667120Y-315214D01*
X667185Y-315153D01*
X667189D01*
X667193Y-315145D01*
X667204Y-315138D01*
X667218Y-315131D01*
X667236Y-315120D01*
X667254Y-315105D01*
X667309Y-315080D01*
X667375Y-315054D01*
X667451Y-315029D01*
X667542Y-315014D01*
X667640Y-315007D01*
X667677D01*
X667702Y-315011D01*
D02*
G37*
G36*
X686221Y-318267D02*
X685052D01*
X685023Y-318263D01*
X684990D01*
X684914Y-318260D01*
X684834Y-318249D01*
X684746Y-318238D01*
X684666Y-318219D01*
X684626Y-318209D01*
X684593Y-318198D01*
X684590D01*
X684586Y-318194D01*
X684564Y-318183D01*
X684531Y-318169D01*
X684491Y-318143D01*
X684448Y-318110D01*
X684401Y-318067D01*
X684357Y-318016D01*
X684313Y-317957D01*
Y-317954D01*
X684309Y-317950D01*
X684295Y-317928D01*
X684280Y-317892D01*
X684259Y-317845D01*
X684240Y-317790D01*
X684222Y-317724D01*
X684211Y-317655D01*
X684208Y-317579D01*
Y-317575D01*
Y-317568D01*
Y-317553D01*
X684211Y-317535D01*
Y-317510D01*
X684215Y-317484D01*
X684229Y-317422D01*
X684251Y-317350D01*
X684280Y-317273D01*
X684324Y-317197D01*
X684353Y-317160D01*
X684382Y-317124D01*
X684386Y-317120D01*
X684390Y-317117D01*
X684401Y-317106D01*
X684415Y-317095D01*
X684433Y-317080D01*
X684455Y-317066D01*
X684484Y-317048D01*
X684513Y-317026D01*
X684550Y-317007D01*
X684590Y-316989D01*
X684633Y-316967D01*
X684681Y-316949D01*
X684735Y-316935D01*
X684790Y-316916D01*
X684852Y-316905D01*
X684917Y-316895D01*
X684910Y-316891D01*
X684896Y-316884D01*
X684874Y-316869D01*
X684845Y-316855D01*
X684779Y-316814D01*
X684746Y-316789D01*
X684717Y-316767D01*
X684710Y-316760D01*
X684692Y-316742D01*
X684663Y-316713D01*
X684626Y-316676D01*
X684586Y-316625D01*
X684539Y-316571D01*
X684491Y-316505D01*
X684441Y-316432D01*
X684007Y-315748D01*
X684422D01*
X684754Y-316272D01*
Y-316276D01*
X684761Y-316283D01*
X684768Y-316294D01*
X684779Y-316308D01*
X684804Y-316349D01*
X684837Y-316400D01*
X684877Y-316454D01*
X684917Y-316512D01*
X684957Y-316567D01*
X684994Y-316618D01*
X684998Y-316622D01*
X685008Y-316636D01*
X685027Y-316658D01*
X685052Y-316684D01*
X685107Y-316738D01*
X685136Y-316763D01*
X685165Y-316785D01*
X685169Y-316789D01*
X685176Y-316793D01*
X685190Y-316800D01*
X685212Y-316811D01*
X685234Y-316822D01*
X685259Y-316833D01*
X685318Y-316851D01*
X685321D01*
X685329Y-316855D01*
X685343D01*
X685361Y-316858D01*
X685387Y-316862D01*
X685416D01*
X685456Y-316865D01*
X685886D01*
Y-315748D01*
X686221D01*
Y-318267D01*
D02*
G37*
G36*
X683436Y-315752D02*
Y-315762D01*
Y-315777D01*
X683432Y-315799D01*
Y-315828D01*
X683429Y-315864D01*
X683425Y-315904D01*
X683421Y-315948D01*
X683414Y-315999D01*
X683407Y-316050D01*
X683396Y-316112D01*
X683385Y-316174D01*
X683374Y-316239D01*
X683359Y-316312D01*
X683323Y-316461D01*
Y-316465D01*
X683319Y-316480D01*
X683312Y-316501D01*
X683301Y-316534D01*
X683290Y-316571D01*
X683276Y-316614D01*
X683261Y-316665D01*
X683239Y-316720D01*
X683217Y-316782D01*
X683196Y-316844D01*
X683141Y-316982D01*
X683076Y-317127D01*
X683003Y-317273D01*
X682999Y-317277D01*
X682992Y-317291D01*
X682981Y-317309D01*
X682966Y-317339D01*
X682948Y-317371D01*
X682923Y-317411D01*
X682897Y-317455D01*
X682868Y-317502D01*
X682799Y-317608D01*
X682726Y-317717D01*
X682642Y-317830D01*
X682555Y-317936D01*
X683789D01*
Y-318234D01*
X682158D01*
Y-317990D01*
X682162Y-317987D01*
X682169Y-317979D01*
X682184Y-317965D01*
X682198Y-317943D01*
X682220Y-317917D01*
X682249Y-317888D01*
X682278Y-317852D01*
X682311Y-317808D01*
X682344Y-317764D01*
X682384Y-317714D01*
X682424Y-317655D01*
X682464Y-317597D01*
X682508Y-317532D01*
X682551Y-317462D01*
X682595Y-317386D01*
X682639Y-317309D01*
X682642Y-317306D01*
X682650Y-317291D01*
X682661Y-317269D01*
X682679Y-317237D01*
X682697Y-317197D01*
X682719Y-317153D01*
X682744Y-317102D01*
X682770Y-317044D01*
X682799Y-316978D01*
X682832Y-316913D01*
X682861Y-316840D01*
X682890Y-316763D01*
X682948Y-316607D01*
X683003Y-316440D01*
Y-316436D01*
X683006Y-316425D01*
X683010Y-316407D01*
X683017Y-316385D01*
X683025Y-316356D01*
X683032Y-316319D01*
X683043Y-316279D01*
X683050Y-316236D01*
X683061Y-316185D01*
X683072Y-316130D01*
X683090Y-316014D01*
X683108Y-315886D01*
X683119Y-315748D01*
X683436D01*
Y-315752D01*
D02*
G37*
G36*
X681478D02*
Y-315762D01*
Y-315777D01*
X681474Y-315799D01*
Y-315828D01*
X681470Y-315864D01*
X681467Y-315904D01*
X681463Y-315948D01*
X681456Y-315999D01*
X681449Y-316050D01*
X681437Y-316112D01*
X681427Y-316174D01*
X681416Y-316239D01*
X681401Y-316312D01*
X681365Y-316461D01*
Y-316465D01*
X681361Y-316480D01*
X681354Y-316501D01*
X681343Y-316534D01*
X681332Y-316571D01*
X681317Y-316614D01*
X681303Y-316665D01*
X681281Y-316720D01*
X681259Y-316782D01*
X681237Y-316844D01*
X681183Y-316982D01*
X681117Y-317127D01*
X681044Y-317273D01*
X681041Y-317277D01*
X681034Y-317291D01*
X681023Y-317309D01*
X681008Y-317339D01*
X680990Y-317371D01*
X680964Y-317411D01*
X680939Y-317455D01*
X680910Y-317502D01*
X680841Y-317608D01*
X680768Y-317717D01*
X680684Y-317830D01*
X680597Y-317936D01*
X681831D01*
Y-318234D01*
X680200D01*
Y-317990D01*
X680204Y-317987D01*
X680211Y-317979D01*
X680225Y-317965D01*
X680240Y-317943D01*
X680262Y-317917D01*
X680291Y-317888D01*
X680320Y-317852D01*
X680353Y-317808D01*
X680386Y-317764D01*
X680426Y-317714D01*
X680466Y-317655D01*
X680506Y-317597D01*
X680549Y-317532D01*
X680593Y-317462D01*
X680637Y-317386D01*
X680680Y-317309D01*
X680684Y-317306D01*
X680691Y-317291D01*
X680702Y-317269D01*
X680721Y-317237D01*
X680739Y-317197D01*
X680760Y-317153D01*
X680786Y-317102D01*
X680812Y-317044D01*
X680841Y-316978D01*
X680873Y-316913D01*
X680902Y-316840D01*
X680932Y-316763D01*
X680990Y-316607D01*
X681044Y-316440D01*
Y-316436D01*
X681048Y-316425D01*
X681052Y-316407D01*
X681059Y-316385D01*
X681066Y-316356D01*
X681074Y-316319D01*
X681084Y-316279D01*
X681092Y-316236D01*
X681103Y-316185D01*
X681114Y-316130D01*
X681132Y-316014D01*
X681150Y-315886D01*
X681161Y-315748D01*
X681478D01*
Y-315752D01*
D02*
G37*
G36*
X693267Y-83564D02*
X693296Y-83567D01*
X693329Y-83575D01*
X693366Y-83582D01*
X693406Y-83589D01*
X693493Y-83618D01*
X693540Y-83640D01*
X693584Y-83662D01*
X693631Y-83691D01*
X693679Y-83724D01*
X693726Y-83760D01*
X693770Y-83804D01*
X693773Y-83808D01*
X693781Y-83815D01*
X693791Y-83829D01*
X693806Y-83848D01*
X693824Y-83869D01*
X693843Y-83899D01*
X693864Y-83931D01*
X693883Y-83971D01*
X693904Y-84011D01*
X693926Y-84059D01*
X693944Y-84106D01*
X693963Y-84161D01*
X693977Y-84219D01*
X693988Y-84281D01*
X693995Y-84343D01*
X693999Y-84412D01*
Y-84445D01*
X693995Y-84466D01*
X693992Y-84496D01*
X693988Y-84528D01*
X693981Y-84565D01*
X693973Y-84605D01*
X693952Y-84692D01*
X693915Y-84783D01*
X693893Y-84830D01*
X693868Y-84874D01*
X693835Y-84918D01*
X693802Y-84961D01*
X693799Y-84965D01*
X693791Y-84972D01*
X693781Y-84983D01*
X693766Y-84994D01*
X693748Y-85012D01*
X693722Y-85031D01*
X693697Y-85053D01*
X693664Y-85074D01*
X693628Y-85096D01*
X693591Y-85118D01*
X693504Y-85158D01*
X693402Y-85191D01*
X693347Y-85202D01*
X693289Y-85209D01*
X693249Y-84900D01*
X693253D01*
X693260Y-84896D01*
X693275Y-84892D01*
X693293Y-84889D01*
X693315Y-84885D01*
X693340Y-84878D01*
X693395Y-84860D01*
X693460Y-84834D01*
X693522Y-84801D01*
X693580Y-84765D01*
X693631Y-84721D01*
X693635Y-84714D01*
X693649Y-84699D01*
X693668Y-84670D01*
X693686Y-84634D01*
X693708Y-84590D01*
X693726Y-84536D01*
X693741Y-84474D01*
X693744Y-84408D01*
Y-84386D01*
X693741Y-84372D01*
X693737Y-84332D01*
X693726Y-84281D01*
X693708Y-84223D01*
X693682Y-84161D01*
X693646Y-84099D01*
X693595Y-84040D01*
X693588Y-84033D01*
X693566Y-84015D01*
X693533Y-83993D01*
X693489Y-83964D01*
X693435Y-83935D01*
X693373Y-83913D01*
X693300Y-83895D01*
X693220Y-83888D01*
X693216D01*
X693209D01*
X693198D01*
X693184Y-83891D01*
X693144Y-83895D01*
X693096Y-83906D01*
X693038Y-83920D01*
X692980Y-83946D01*
X692922Y-83982D01*
X692867Y-84030D01*
X692860Y-84037D01*
X692845Y-84055D01*
X692823Y-84084D01*
X692798Y-84124D01*
X692772Y-84175D01*
X692751Y-84237D01*
X692736Y-84306D01*
X692729Y-84383D01*
Y-84416D01*
X692732Y-84441D01*
X692736Y-84474D01*
X692743Y-84510D01*
X692751Y-84554D01*
X692761Y-84601D01*
X692488Y-84565D01*
Y-84547D01*
X692492Y-84532D01*
Y-84485D01*
X692485Y-84445D01*
X692478Y-84397D01*
X692467Y-84343D01*
X692448Y-84281D01*
X692423Y-84223D01*
X692390Y-84161D01*
Y-84157D01*
X692386Y-84153D01*
X692372Y-84135D01*
X692346Y-84110D01*
X692314Y-84081D01*
X692266Y-84052D01*
X692212Y-84026D01*
X692150Y-84008D01*
X692113Y-84000D01*
X692073D01*
X692070D01*
X692066D01*
X692044D01*
X692015Y-84008D01*
X691975Y-84015D01*
X691931Y-84030D01*
X691884Y-84048D01*
X691837Y-84077D01*
X691793Y-84117D01*
X691789Y-84121D01*
X691775Y-84139D01*
X691757Y-84164D01*
X691735Y-84197D01*
X691717Y-84241D01*
X691699Y-84292D01*
X691684Y-84350D01*
X691680Y-84416D01*
Y-84445D01*
X691688Y-84477D01*
X691695Y-84521D01*
X691709Y-84568D01*
X691728Y-84616D01*
X691757Y-84667D01*
X691793Y-84714D01*
X691797Y-84718D01*
X691815Y-84732D01*
X691841Y-84754D01*
X691877Y-84780D01*
X691924Y-84805D01*
X691982Y-84830D01*
X692052Y-84852D01*
X692132Y-84867D01*
X692077Y-85176D01*
X692073D01*
X692063Y-85173D01*
X692048Y-85169D01*
X692026Y-85165D01*
X692001Y-85158D01*
X691971Y-85147D01*
X691902Y-85125D01*
X691822Y-85089D01*
X691742Y-85045D01*
X691666Y-84991D01*
X691597Y-84921D01*
X691593Y-84918D01*
X691589Y-84911D01*
X691582Y-84900D01*
X691571Y-84885D01*
X691557Y-84867D01*
X691542Y-84841D01*
X691527Y-84816D01*
X691509Y-84783D01*
X691480Y-84710D01*
X691451Y-84627D01*
X691433Y-84528D01*
X691426Y-84477D01*
Y-84386D01*
X691429Y-84346D01*
X691436Y-84299D01*
X691447Y-84241D01*
X691466Y-84175D01*
X691487Y-84110D01*
X691516Y-84044D01*
Y-84040D01*
X691520Y-84037D01*
X691531Y-84015D01*
X691553Y-83982D01*
X691578Y-83946D01*
X691615Y-83902D01*
X691655Y-83859D01*
X691702Y-83815D01*
X691757Y-83779D01*
X691764Y-83775D01*
X691782Y-83764D01*
X691815Y-83749D01*
X691855Y-83731D01*
X691902Y-83713D01*
X691957Y-83698D01*
X692019Y-83688D01*
X692081Y-83684D01*
X692088D01*
X692110D01*
X692139Y-83688D01*
X692179Y-83695D01*
X692226Y-83706D01*
X692277Y-83724D01*
X692328Y-83746D01*
X692379Y-83775D01*
X692386Y-83779D01*
X692401Y-83789D01*
X692426Y-83811D01*
X692456Y-83840D01*
X692488Y-83877D01*
X692525Y-83920D01*
X692557Y-83971D01*
X692590Y-84033D01*
Y-84030D01*
X692594Y-84022D01*
X692598Y-84011D01*
X692601Y-83997D01*
X692616Y-83957D01*
X692638Y-83906D01*
X692667Y-83848D01*
X692703Y-83789D01*
X692751Y-83735D01*
X692805Y-83684D01*
X692812Y-83680D01*
X692834Y-83666D01*
X692871Y-83644D01*
X692918Y-83622D01*
X692976Y-83600D01*
X693045Y-83578D01*
X693125Y-83564D01*
X693213Y-83560D01*
X693216D01*
X693227D01*
X693246D01*
X693267Y-83564D01*
D02*
G37*
G36*
X693351Y-85871D02*
X693955D01*
Y-86181D01*
X693351D01*
Y-87277D01*
X693067D01*
X691436Y-86123D01*
Y-85871D01*
X693067D01*
Y-85529D01*
X693351D01*
Y-85871D01*
D02*
G37*
G36*
X693235Y-87593D02*
X693264D01*
X693333Y-87600D01*
X693413Y-87608D01*
X693497Y-87622D01*
X693573Y-87644D01*
X693646Y-87670D01*
X693649D01*
X693653Y-87673D01*
X693675Y-87684D01*
X693704Y-87702D01*
X693744Y-87728D01*
X693784Y-87764D01*
X693828Y-87804D01*
X693872Y-87855D01*
X693908Y-87914D01*
X693912Y-87921D01*
X693923Y-87943D01*
X693937Y-87975D01*
X693952Y-88023D01*
X693970Y-88081D01*
X693984Y-88147D01*
X693995Y-88219D01*
X693999Y-88299D01*
Y-88332D01*
X693995Y-88354D01*
X693992Y-88383D01*
X693988Y-88412D01*
X693973Y-88489D01*
X693952Y-88569D01*
X693919Y-88652D01*
X693897Y-88696D01*
X693872Y-88736D01*
X693843Y-88773D01*
X693810Y-88809D01*
X693806Y-88813D01*
X693802Y-88816D01*
X693788Y-88823D01*
X693773Y-88834D01*
X693755Y-88849D01*
X693730Y-88863D01*
X693701Y-88878D01*
X693668Y-88896D01*
X693631Y-88911D01*
X693588Y-88925D01*
X693544Y-88940D01*
X693493Y-88955D01*
X693438Y-88962D01*
X693377Y-88973D01*
X693315Y-88976D01*
X693246D01*
X693202Y-88674D01*
X693205D01*
X693213D01*
X693227D01*
X693249Y-88671D01*
X693271Y-88667D01*
X693296D01*
X693358Y-88656D01*
X693424Y-88645D01*
X693489Y-88623D01*
X693548Y-88601D01*
X693573Y-88587D01*
X693595Y-88569D01*
X693599Y-88565D01*
X693610Y-88551D01*
X693628Y-88529D01*
X693646Y-88499D01*
X693668Y-88459D01*
X693682Y-88416D01*
X693697Y-88361D01*
X693701Y-88303D01*
Y-88281D01*
X693697Y-88259D01*
X693693Y-88226D01*
X693686Y-88194D01*
X693679Y-88157D01*
X693664Y-88121D01*
X693646Y-88085D01*
X693642Y-88081D01*
X693635Y-88070D01*
X693620Y-88055D01*
X693606Y-88034D01*
X693580Y-88015D01*
X693555Y-87994D01*
X693526Y-87975D01*
X693489Y-87961D01*
X693486D01*
X693471Y-87954D01*
X693446Y-87950D01*
X693413Y-87943D01*
X693369Y-87935D01*
X693315Y-87932D01*
X693249Y-87924D01*
X693173D01*
X691436D01*
Y-87590D01*
X693154D01*
X693158D01*
X693169D01*
X693184D01*
X693205D01*
X693235Y-87593D01*
D02*
G37*
G36*
X685002Y-47140D02*
X685046D01*
X685093Y-47144D01*
X685144Y-47147D01*
X685260Y-47158D01*
X685381Y-47176D01*
X685497Y-47198D01*
X685552Y-47213D01*
X685606Y-47231D01*
X685610D01*
X685617Y-47235D01*
X685632Y-47242D01*
X685650Y-47249D01*
X685675Y-47256D01*
X685701Y-47271D01*
X685763Y-47300D01*
X685828Y-47337D01*
X685901Y-47384D01*
X685967Y-47438D01*
X686029Y-47504D01*
Y-47508D01*
X686036Y-47511D01*
X686043Y-47522D01*
X686050Y-47537D01*
X686061Y-47555D01*
X686076Y-47573D01*
X686101Y-47628D01*
X686127Y-47693D01*
X686152Y-47770D01*
X686167Y-47861D01*
X686174Y-47959D01*
Y-47995D01*
X686170Y-48021D01*
X686167Y-48050D01*
X686160Y-48086D01*
X686152Y-48126D01*
X686141Y-48170D01*
X686127Y-48214D01*
X686112Y-48261D01*
X686091Y-48308D01*
X686065Y-48356D01*
X686036Y-48403D01*
X685999Y-48450D01*
X685959Y-48494D01*
X685916Y-48534D01*
X685912Y-48538D01*
X685901Y-48545D01*
X685883Y-48556D01*
X685854Y-48574D01*
X685821Y-48592D01*
X685777Y-48610D01*
X685726Y-48636D01*
X685668Y-48658D01*
X685603Y-48680D01*
X685526Y-48702D01*
X685442Y-48723D01*
X685348Y-48742D01*
X685246Y-48760D01*
X685137Y-48771D01*
X685017Y-48778D01*
X684889Y-48782D01*
X684886D01*
X684871D01*
X684846D01*
X684817D01*
X684776Y-48778D01*
X684733D01*
X684685Y-48774D01*
X684631Y-48771D01*
X684518Y-48760D01*
X684398Y-48742D01*
X684278Y-48720D01*
X684223Y-48705D01*
X684168Y-48691D01*
X684165D01*
X684158Y-48687D01*
X684143Y-48680D01*
X684125Y-48672D01*
X684099Y-48665D01*
X684074Y-48651D01*
X684012Y-48621D01*
X683947Y-48585D01*
X683877Y-48538D01*
X683808Y-48483D01*
X683750Y-48418D01*
Y-48414D01*
X683743Y-48410D01*
X683735Y-48399D01*
X683728Y-48385D01*
X683713Y-48367D01*
X683703Y-48345D01*
X683673Y-48290D01*
X683648Y-48225D01*
X683623Y-48148D01*
X683608Y-48057D01*
X683601Y-47959D01*
Y-47926D01*
X683604Y-47886D01*
X683612Y-47839D01*
X683623Y-47784D01*
X683637Y-47726D01*
X683655Y-47664D01*
X683684Y-47606D01*
Y-47602D01*
X683688Y-47599D01*
X683699Y-47580D01*
X683717Y-47551D01*
X683743Y-47515D01*
X683779Y-47475D01*
X683819Y-47431D01*
X683866Y-47391D01*
X683921Y-47351D01*
X683928Y-47347D01*
X683947Y-47333D01*
X683979Y-47318D01*
X684027Y-47293D01*
X684081Y-47271D01*
X684143Y-47242D01*
X684216Y-47216D01*
X684296Y-47195D01*
X684300D01*
X684307Y-47191D01*
X684318Y-47187D01*
X684336Y-47184D01*
X684358Y-47180D01*
X684383Y-47176D01*
X684416Y-47169D01*
X684452Y-47165D01*
X684492Y-47158D01*
X684536Y-47155D01*
X684587Y-47151D01*
X684638Y-47144D01*
X684696Y-47140D01*
X684755D01*
X684820Y-47136D01*
X684889D01*
X684893D01*
X684907D01*
X684933D01*
X684962D01*
X685002Y-47140D01*
D02*
G37*
G36*
X686131Y-50784D02*
X686127D01*
X686112D01*
X686091D01*
X686061Y-50780D01*
X686029Y-50776D01*
X685992Y-50769D01*
X685956Y-50762D01*
X685916Y-50747D01*
X685912D01*
X685909Y-50744D01*
X685887Y-50736D01*
X685854Y-50722D01*
X685810Y-50700D01*
X685759Y-50671D01*
X685701Y-50634D01*
X685643Y-50594D01*
X685581Y-50543D01*
X685577D01*
X685574Y-50536D01*
X685552Y-50518D01*
X685519Y-50485D01*
X685472Y-50438D01*
X685417Y-50383D01*
X685352Y-50314D01*
X685279Y-50230D01*
X685202Y-50139D01*
X685199Y-50136D01*
X685188Y-50121D01*
X685170Y-50099D01*
X685148Y-50074D01*
X685119Y-50041D01*
X685086Y-50001D01*
X685049Y-49961D01*
X685009Y-49914D01*
X684922Y-49823D01*
X684835Y-49732D01*
X684791Y-49688D01*
X684747Y-49648D01*
X684707Y-49611D01*
X684667Y-49582D01*
X684664D01*
X684660Y-49575D01*
X684649Y-49568D01*
X684634Y-49561D01*
X684594Y-49535D01*
X684547Y-49506D01*
X684489Y-49481D01*
X684427Y-49455D01*
X684358Y-49440D01*
X684292Y-49433D01*
X684289D01*
X684285D01*
X684263Y-49437D01*
X684227Y-49440D01*
X684187Y-49451D01*
X684136Y-49466D01*
X684085Y-49491D01*
X684034Y-49524D01*
X683983Y-49568D01*
X683976Y-49575D01*
X683961Y-49593D01*
X683943Y-49619D01*
X683917Y-49659D01*
X683895Y-49710D01*
X683874Y-49768D01*
X683859Y-49837D01*
X683855Y-49914D01*
Y-49935D01*
X683859Y-49950D01*
X683863Y-49994D01*
X683874Y-50045D01*
X683888Y-50099D01*
X683914Y-50161D01*
X683947Y-50219D01*
X683990Y-50274D01*
X683997Y-50281D01*
X684016Y-50296D01*
X684045Y-50318D01*
X684089Y-50340D01*
X684139Y-50365D01*
X684205Y-50387D01*
X684278Y-50401D01*
X684362Y-50409D01*
X684329Y-50725D01*
X684325D01*
X684314Y-50722D01*
X684296D01*
X684270Y-50718D01*
X684241Y-50711D01*
X684209Y-50704D01*
X684168Y-50693D01*
X684129Y-50682D01*
X684041Y-50653D01*
X683954Y-50609D01*
X683910Y-50583D01*
X683866Y-50551D01*
X683826Y-50518D01*
X683790Y-50481D01*
X683786Y-50478D01*
X683783Y-50471D01*
X683772Y-50460D01*
X683761Y-50441D01*
X683746Y-50420D01*
X683732Y-50394D01*
X683713Y-50365D01*
X683695Y-50329D01*
X683677Y-50289D01*
X683659Y-50245D01*
X683644Y-50198D01*
X683630Y-50147D01*
X683619Y-50092D01*
X683608Y-50034D01*
X683604Y-49972D01*
X683601Y-49906D01*
Y-49870D01*
X683604Y-49845D01*
X683608Y-49815D01*
X683612Y-49779D01*
X683619Y-49739D01*
X683626Y-49699D01*
X683652Y-49604D01*
X683688Y-49510D01*
X683710Y-49462D01*
X683735Y-49415D01*
X683768Y-49371D01*
X683805Y-49331D01*
X683808Y-49328D01*
X683812Y-49320D01*
X683826Y-49313D01*
X683841Y-49299D01*
X683859Y-49280D01*
X683885Y-49262D01*
X683910Y-49244D01*
X683943Y-49222D01*
X684012Y-49186D01*
X684099Y-49149D01*
X684143Y-49135D01*
X684194Y-49127D01*
X684245Y-49120D01*
X684300Y-49117D01*
X684307D01*
X684325D01*
X684354Y-49120D01*
X684394Y-49124D01*
X684438Y-49131D01*
X684489Y-49146D01*
X684544Y-49160D01*
X684598Y-49182D01*
X684605Y-49186D01*
X684623Y-49193D01*
X684653Y-49207D01*
X684693Y-49229D01*
X684736Y-49258D01*
X684791Y-49295D01*
X684846Y-49338D01*
X684907Y-49389D01*
X684915Y-49397D01*
X684937Y-49415D01*
X684955Y-49433D01*
X684973Y-49451D01*
X684995Y-49473D01*
X685024Y-49502D01*
X685053Y-49531D01*
X685086Y-49568D01*
X685122Y-49604D01*
X685162Y-49648D01*
X685202Y-49695D01*
X685250Y-49746D01*
X685297Y-49804D01*
X685348Y-49863D01*
X685352Y-49866D01*
X685359Y-49874D01*
X685370Y-49888D01*
X685384Y-49906D01*
X685406Y-49928D01*
X685428Y-49954D01*
X685475Y-50012D01*
X685530Y-50074D01*
X685584Y-50132D01*
X685632Y-50183D01*
X685650Y-50205D01*
X685668Y-50223D01*
X685672Y-50227D01*
X685683Y-50238D01*
X685697Y-50252D01*
X685719Y-50270D01*
X685745Y-50289D01*
X685770Y-50310D01*
X685832Y-50354D01*
Y-49113D01*
X686131D01*
Y-50784D01*
D02*
G37*
G36*
X685162Y-51173D02*
X685199D01*
X685242Y-51177D01*
X685286Y-51180D01*
X685384Y-51191D01*
X685486Y-51206D01*
X685584Y-51228D01*
X685632Y-51242D01*
X685675Y-51257D01*
X685679D01*
X685686Y-51260D01*
X685697Y-51268D01*
X685712Y-51275D01*
X685752Y-51297D01*
X685803Y-51330D01*
X685861Y-51373D01*
X685919Y-51424D01*
X685981Y-51490D01*
X686036Y-51570D01*
Y-51573D01*
X686043Y-51581D01*
X686047Y-51592D01*
X686058Y-51610D01*
X686069Y-51632D01*
X686080Y-51661D01*
X686091Y-51690D01*
X686105Y-51726D01*
X686120Y-51766D01*
X686131Y-51810D01*
X686141Y-51857D01*
X686152Y-51912D01*
X686160Y-51967D01*
X686167Y-52025D01*
X686174Y-52156D01*
Y-52189D01*
X686170Y-52214D01*
Y-52243D01*
X686167Y-52280D01*
X686163Y-52320D01*
X686160Y-52360D01*
X686145Y-52451D01*
X686123Y-52549D01*
X686094Y-52644D01*
X686054Y-52735D01*
Y-52738D01*
X686047Y-52746D01*
X686039Y-52757D01*
X686032Y-52771D01*
X686003Y-52811D01*
X685963Y-52858D01*
X685912Y-52913D01*
X685854Y-52964D01*
X685781Y-53015D01*
X685701Y-53055D01*
X685697D01*
X685690Y-53059D01*
X685675Y-53062D01*
X685657Y-53070D01*
X685636Y-53077D01*
X685606Y-53084D01*
X685574Y-53095D01*
X685534Y-53102D01*
X685490Y-53110D01*
X685442Y-53120D01*
X685392Y-53128D01*
X685337Y-53135D01*
X685275Y-53142D01*
X685210Y-53146D01*
X685140Y-53150D01*
X685068D01*
X683612D01*
Y-52815D01*
X685068D01*
X685071D01*
X685082D01*
X685100D01*
X685122D01*
X685148Y-52811D01*
X685181D01*
X685250Y-52807D01*
X685330Y-52800D01*
X685410Y-52789D01*
X685486Y-52775D01*
X685519Y-52767D01*
X685552Y-52757D01*
X685559Y-52753D01*
X685577Y-52746D01*
X685603Y-52727D01*
X685639Y-52706D01*
X685675Y-52680D01*
X685715Y-52644D01*
X685756Y-52600D01*
X685788Y-52549D01*
X685792Y-52542D01*
X685803Y-52523D01*
X685814Y-52491D01*
X685828Y-52447D01*
X685847Y-52396D01*
X685857Y-52331D01*
X685868Y-52261D01*
X685872Y-52185D01*
Y-52149D01*
X685868Y-52127D01*
Y-52094D01*
X685865Y-52061D01*
X685850Y-51981D01*
X685832Y-51894D01*
X685803Y-51810D01*
X685763Y-51730D01*
X685737Y-51694D01*
X685708Y-51661D01*
X685705Y-51657D01*
X685701Y-51654D01*
X685690Y-51646D01*
X685675Y-51635D01*
X685654Y-51624D01*
X685632Y-51610D01*
X685599Y-51595D01*
X685566Y-51581D01*
X685526Y-51566D01*
X685479Y-51555D01*
X685424Y-51541D01*
X685366Y-51530D01*
X685301Y-51519D01*
X685231Y-51512D01*
X685151Y-51504D01*
X685068D01*
X683612D01*
Y-51169D01*
X685068D01*
X685071D01*
X685086D01*
X685104D01*
X685129D01*
X685162Y-51173D01*
D02*
G37*
G36*
X674960Y-105640D02*
X674661D01*
Y-104272D01*
X673882D01*
Y-105455D01*
X673584D01*
Y-104272D01*
X672441D01*
Y-103937D01*
X674960D01*
Y-105640D01*
D02*
G37*
G36*
Y-107049D02*
X674956Y-107075D01*
Y-107104D01*
X674949Y-107169D01*
X674942Y-107242D01*
X674927Y-107318D01*
X674909Y-107395D01*
X674883Y-107464D01*
Y-107468D01*
X674880Y-107471D01*
X674869Y-107493D01*
X674851Y-107526D01*
X674825Y-107562D01*
X674792Y-107606D01*
X674752Y-107653D01*
X674701Y-107697D01*
X674647Y-107737D01*
X674640Y-107741D01*
X674618Y-107752D01*
X674588Y-107770D01*
X674545Y-107788D01*
X674494Y-107806D01*
X674439Y-107825D01*
X674377Y-107835D01*
X674316Y-107839D01*
X674308D01*
X674290D01*
X674257Y-107835D01*
X674217Y-107828D01*
X674170Y-107817D01*
X674119Y-107799D01*
X674068Y-107777D01*
X674013Y-107748D01*
X674006Y-107744D01*
X673991Y-107734D01*
X673962Y-107712D01*
X673933Y-107683D01*
X673897Y-107646D01*
X673857Y-107602D01*
X673820Y-107548D01*
X673784Y-107486D01*
Y-107490D01*
X673780Y-107497D01*
X673777Y-107508D01*
X673770Y-107522D01*
X673755Y-107566D01*
X673729Y-107617D01*
X673697Y-107672D01*
X673657Y-107734D01*
X673609Y-107788D01*
X673551Y-107839D01*
X673544Y-107843D01*
X673522Y-107857D01*
X673489Y-107879D01*
X673446Y-107901D01*
X673387Y-107923D01*
X673325Y-107945D01*
X673253Y-107959D01*
X673173Y-107963D01*
X673169D01*
X673165D01*
X673143D01*
X673107Y-107959D01*
X673063Y-107952D01*
X673012Y-107945D01*
X672958Y-107930D01*
X672899Y-107912D01*
X672841Y-107886D01*
X672834Y-107883D01*
X672816Y-107872D01*
X672790Y-107857D01*
X672754Y-107835D01*
X672718Y-107806D01*
X672678Y-107777D01*
X672637Y-107741D01*
X672605Y-107701D01*
X672601Y-107697D01*
X672590Y-107683D01*
X672576Y-107657D01*
X672561Y-107624D01*
X672539Y-107584D01*
X672517Y-107537D01*
X672499Y-107486D01*
X672481Y-107424D01*
Y-107417D01*
X672474Y-107395D01*
X672470Y-107359D01*
X672463Y-107311D01*
X672456Y-107253D01*
X672448Y-107184D01*
X672444Y-107107D01*
X672441Y-107020D01*
Y-106059D01*
X674960D01*
Y-107049D01*
D02*
G37*
G36*
X674337Y-108534D02*
X674345Y-108542D01*
X674348Y-108556D01*
X674359Y-108574D01*
X674370Y-108596D01*
X674385Y-108622D01*
X674421Y-108684D01*
X674461Y-108756D01*
X674512Y-108829D01*
X674570Y-108906D01*
X674632Y-108982D01*
X674636Y-108986D01*
X674640Y-108989D01*
X674650Y-109000D01*
X674661Y-109015D01*
X674698Y-109047D01*
X674741Y-109091D01*
X674792Y-109135D01*
X674851Y-109182D01*
X674909Y-109222D01*
X674971Y-109259D01*
Y-109459D01*
X672441D01*
Y-109149D01*
X674410D01*
X674406Y-109146D01*
X674392Y-109128D01*
X674370Y-109106D01*
X674345Y-109069D01*
X674312Y-109029D01*
X674275Y-108978D01*
X674235Y-108920D01*
X674195Y-108855D01*
Y-108851D01*
X674192Y-108847D01*
X674177Y-108826D01*
X674159Y-108789D01*
X674137Y-108745D01*
X674112Y-108694D01*
X674086Y-108640D01*
X674061Y-108585D01*
X674039Y-108531D01*
X674337D01*
Y-108534D01*
D02*
G37*
G36*
X660955Y-109892D02*
X660981D01*
X661010Y-109896D01*
X661079Y-109911D01*
X661156Y-109929D01*
X661236Y-109958D01*
X661316Y-109998D01*
X661356Y-110023D01*
X661392Y-110053D01*
X661396Y-110056D01*
X661400Y-110060D01*
X661411Y-110071D01*
X661421Y-110082D01*
X661436Y-110100D01*
X661454Y-110122D01*
X661490Y-110173D01*
X661527Y-110238D01*
X661563Y-110318D01*
X661592Y-110409D01*
X661614Y-110515D01*
X661316Y-110540D01*
Y-110537D01*
X661312Y-110529D01*
Y-110522D01*
X661309Y-110508D01*
X661298Y-110468D01*
X661283Y-110424D01*
X661265Y-110373D01*
X661239Y-110322D01*
X661210Y-110275D01*
X661174Y-110235D01*
X661170Y-110231D01*
X661156Y-110220D01*
X661130Y-110205D01*
X661101Y-110191D01*
X661061Y-110173D01*
X661014Y-110158D01*
X660959Y-110147D01*
X660901Y-110144D01*
X660875D01*
X660850Y-110147D01*
X660817Y-110151D01*
X660777Y-110158D01*
X660737Y-110169D01*
X660693Y-110184D01*
X660653Y-110205D01*
X660650Y-110209D01*
X660635Y-110216D01*
X660613Y-110231D01*
X660592Y-110253D01*
X660562Y-110278D01*
X660533Y-110307D01*
X660504Y-110340D01*
X660475Y-110380D01*
X660471Y-110384D01*
X660464Y-110402D01*
X660450Y-110427D01*
X660435Y-110460D01*
X660417Y-110504D01*
X660398Y-110555D01*
X660380Y-110613D01*
X660362Y-110679D01*
Y-110682D01*
X660358Y-110686D01*
Y-110697D01*
X660355Y-110711D01*
X660348Y-110748D01*
X660337Y-110795D01*
X660329Y-110853D01*
X660322Y-110915D01*
X660319Y-110984D01*
X660315Y-111057D01*
Y-111061D01*
Y-111072D01*
Y-111090D01*
Y-111119D01*
X660319Y-111112D01*
X660333Y-111094D01*
X660355Y-111068D01*
X660380Y-111032D01*
X660417Y-110995D01*
X660460Y-110955D01*
X660511Y-110915D01*
X660570Y-110879D01*
X660577Y-110875D01*
X660599Y-110864D01*
X660632Y-110850D01*
X660672Y-110835D01*
X660726Y-110817D01*
X660784Y-110802D01*
X660850Y-110792D01*
X660919Y-110788D01*
X660948D01*
X660970Y-110792D01*
X660999Y-110795D01*
X661028Y-110799D01*
X661065Y-110806D01*
X661101Y-110817D01*
X661185Y-110843D01*
X661229Y-110861D01*
X661272Y-110882D01*
X661319Y-110908D01*
X661363Y-110941D01*
X661407Y-110974D01*
X661447Y-111014D01*
X661450Y-111017D01*
X661458Y-111024D01*
X661465Y-111035D01*
X661480Y-111054D01*
X661498Y-111079D01*
X661516Y-111105D01*
X661534Y-111137D01*
X661552Y-111174D01*
X661574Y-111214D01*
X661592Y-111257D01*
X661611Y-111308D01*
X661629Y-111359D01*
X661643Y-111418D01*
X661651Y-111479D01*
X661658Y-111541D01*
X661662Y-111610D01*
Y-111614D01*
Y-111629D01*
Y-111647D01*
X661658Y-111672D01*
X661654Y-111705D01*
X661651Y-111745D01*
X661643Y-111785D01*
X661632Y-111833D01*
X661607Y-111927D01*
X661589Y-111978D01*
X661567Y-112033D01*
X661542Y-112084D01*
X661509Y-112131D01*
X661476Y-112182D01*
X661436Y-112226D01*
X661432Y-112229D01*
X661425Y-112237D01*
X661414Y-112248D01*
X661396Y-112262D01*
X661374Y-112280D01*
X661345Y-112302D01*
X661316Y-112320D01*
X661279Y-112346D01*
X661243Y-112368D01*
X661199Y-112386D01*
X661101Y-112426D01*
X661050Y-112440D01*
X660992Y-112451D01*
X660934Y-112459D01*
X660872Y-112462D01*
X660846D01*
X660828Y-112459D01*
X660810D01*
X660784Y-112455D01*
X660722Y-112444D01*
X660653Y-112429D01*
X660577Y-112404D01*
X660500Y-112371D01*
X660424Y-112328D01*
X660420D01*
X660417Y-112320D01*
X660406Y-112313D01*
X660391Y-112302D01*
X660355Y-112273D01*
X660308Y-112233D01*
X660260Y-112178D01*
X660206Y-112113D01*
X660158Y-112036D01*
X660115Y-111949D01*
Y-111945D01*
X660111Y-111938D01*
X660104Y-111924D01*
X660096Y-111905D01*
X660089Y-111880D01*
X660078Y-111847D01*
X660071Y-111811D01*
X660060Y-111771D01*
X660049Y-111723D01*
X660038Y-111669D01*
X660031Y-111610D01*
X660024Y-111549D01*
X660016Y-111479D01*
X660009Y-111407D01*
X660005Y-111327D01*
Y-111243D01*
Y-111239D01*
Y-111221D01*
Y-111196D01*
Y-111163D01*
X660009Y-111123D01*
Y-111075D01*
X660013Y-111021D01*
X660020Y-110966D01*
X660031Y-110843D01*
X660049Y-110711D01*
X660075Y-110588D01*
X660093Y-110526D01*
X660111Y-110471D01*
Y-110468D01*
X660115Y-110460D01*
X660122Y-110446D01*
X660129Y-110424D01*
X660140Y-110402D01*
X660155Y-110373D01*
X660191Y-110311D01*
X660235Y-110242D01*
X660286Y-110169D01*
X660351Y-110100D01*
X660424Y-110038D01*
X660428D01*
X660435Y-110031D01*
X660446Y-110023D01*
X660460Y-110016D01*
X660482Y-110005D01*
X660504Y-109991D01*
X660533Y-109976D01*
X660562Y-109965D01*
X660632Y-109936D01*
X660715Y-109911D01*
X660806Y-109896D01*
X660908Y-109889D01*
X660937D01*
X660955Y-109892D01*
D02*
G37*
G36*
X663059D02*
X663092D01*
X663132Y-109896D01*
X663176Y-109903D01*
X663227Y-109911D01*
X663332Y-109929D01*
X663442Y-109958D01*
X663551Y-109998D01*
X663602Y-110023D01*
X663653Y-110053D01*
X663656Y-110056D01*
X663664Y-110060D01*
X663678Y-110071D01*
X663693Y-110085D01*
X663715Y-110100D01*
X663740Y-110122D01*
X663769Y-110147D01*
X663798Y-110176D01*
X663827Y-110209D01*
X663860Y-110242D01*
X663926Y-110326D01*
X663988Y-110424D01*
X664042Y-110533D01*
Y-110537D01*
X664049Y-110548D01*
X664053Y-110566D01*
X664064Y-110588D01*
X664071Y-110617D01*
X664082Y-110653D01*
X664097Y-110693D01*
X664108Y-110737D01*
X664119Y-110784D01*
X664133Y-110839D01*
X664151Y-110952D01*
X664166Y-111079D01*
X664173Y-111210D01*
Y-111214D01*
Y-111228D01*
Y-111250D01*
X664170Y-111276D01*
Y-111312D01*
X664166Y-111348D01*
X664162Y-111396D01*
X664155Y-111443D01*
X664137Y-111549D01*
X664111Y-111665D01*
X664075Y-111782D01*
X664024Y-111894D01*
X664020Y-111898D01*
X664017Y-111909D01*
X664009Y-111924D01*
X663995Y-111942D01*
X663980Y-111967D01*
X663962Y-111996D01*
X663915Y-112062D01*
X663853Y-112135D01*
X663780Y-112207D01*
X663696Y-112280D01*
X663598Y-112342D01*
X663594Y-112346D01*
X663584Y-112349D01*
X663569Y-112357D01*
X663551Y-112368D01*
X663522Y-112379D01*
X663493Y-112390D01*
X663456Y-112404D01*
X663416Y-112419D01*
X663372Y-112433D01*
X663325Y-112448D01*
X663223Y-112470D01*
X663107Y-112488D01*
X662987Y-112495D01*
X662950D01*
X662925Y-112491D01*
X662892Y-112488D01*
X662852Y-112484D01*
X662812Y-112480D01*
X662765Y-112470D01*
X662666Y-112448D01*
X662557Y-112415D01*
X662502Y-112393D01*
X662452Y-112368D01*
X662401Y-112335D01*
X662350Y-112302D01*
X662346Y-112299D01*
X662339Y-112295D01*
X662324Y-112284D01*
X662306Y-112266D01*
X662288Y-112248D01*
X662262Y-112222D01*
X662237Y-112193D01*
X662208Y-112164D01*
X662179Y-112127D01*
X662149Y-112084D01*
X662117Y-112040D01*
X662087Y-111993D01*
X662062Y-111938D01*
X662033Y-111883D01*
X662011Y-111825D01*
X661989Y-111760D01*
X662317Y-111683D01*
Y-111687D01*
X662321Y-111694D01*
X662328Y-111709D01*
X662335Y-111727D01*
X662342Y-111749D01*
X662353Y-111778D01*
X662382Y-111836D01*
X662419Y-111902D01*
X662462Y-111967D01*
X662517Y-112029D01*
X662575Y-112084D01*
X662582Y-112091D01*
X662604Y-112106D01*
X662641Y-112124D01*
X662688Y-112149D01*
X662750Y-112171D01*
X662819Y-112193D01*
X662903Y-112207D01*
X662994Y-112211D01*
X663023D01*
X663041Y-112207D01*
X663067D01*
X663096Y-112204D01*
X663165Y-112193D01*
X663241Y-112178D01*
X663321Y-112153D01*
X663405Y-112117D01*
X663482Y-112069D01*
X663485D01*
X663489Y-112062D01*
X663514Y-112044D01*
X663547Y-112015D01*
X663587Y-111971D01*
X663634Y-111916D01*
X663678Y-111854D01*
X663718Y-111778D01*
X663755Y-111694D01*
Y-111691D01*
X663758Y-111683D01*
X663762Y-111672D01*
X663765Y-111654D01*
X663773Y-111632D01*
X663780Y-111607D01*
X663791Y-111545D01*
X663806Y-111472D01*
X663820Y-111392D01*
X663827Y-111305D01*
X663831Y-111210D01*
Y-111206D01*
Y-111196D01*
Y-111177D01*
Y-111155D01*
X663827Y-111130D01*
Y-111097D01*
X663824Y-111061D01*
X663820Y-111021D01*
X663809Y-110933D01*
X663791Y-110839D01*
X663769Y-110744D01*
X663740Y-110650D01*
Y-110646D01*
X663736Y-110639D01*
X663729Y-110628D01*
X663722Y-110609D01*
X663700Y-110566D01*
X663667Y-110515D01*
X663627Y-110457D01*
X663576Y-110395D01*
X663518Y-110340D01*
X663449Y-110289D01*
X663445D01*
X663438Y-110286D01*
X663427Y-110278D01*
X663413Y-110271D01*
X663394Y-110264D01*
X663372Y-110253D01*
X663321Y-110231D01*
X663256Y-110209D01*
X663183Y-110191D01*
X663103Y-110176D01*
X663019Y-110173D01*
X662994D01*
X662972Y-110176D01*
X662947D01*
X662921Y-110180D01*
X662856Y-110195D01*
X662779Y-110213D01*
X662703Y-110242D01*
X662623Y-110282D01*
X662582Y-110304D01*
X662546Y-110333D01*
X662542Y-110336D01*
X662539Y-110340D01*
X662528Y-110351D01*
X662513Y-110362D01*
X662499Y-110380D01*
X662481Y-110402D01*
X662459Y-110424D01*
X662441Y-110453D01*
X662419Y-110486D01*
X662393Y-110522D01*
X662371Y-110559D01*
X662350Y-110602D01*
X662331Y-110650D01*
X662313Y-110701D01*
X662295Y-110755D01*
X662280Y-110813D01*
X661946Y-110730D01*
Y-110726D01*
X661949Y-110711D01*
X661957Y-110690D01*
X661967Y-110661D01*
X661978Y-110628D01*
X661993Y-110588D01*
X662011Y-110544D01*
X662033Y-110497D01*
X662084Y-110395D01*
X662149Y-110293D01*
X662189Y-110242D01*
X662229Y-110191D01*
X662273Y-110147D01*
X662324Y-110104D01*
X662328Y-110100D01*
X662335Y-110093D01*
X662353Y-110085D01*
X662371Y-110071D01*
X662401Y-110053D01*
X662430Y-110034D01*
X662470Y-110016D01*
X662510Y-109998D01*
X662557Y-109976D01*
X662608Y-109958D01*
X662663Y-109940D01*
X662721Y-109922D01*
X662783Y-109907D01*
X662848Y-109900D01*
X662917Y-109892D01*
X662990Y-109889D01*
X663030D01*
X663059Y-109892D01*
D02*
G37*
G36*
X658943D02*
X658972Y-109896D01*
X659008Y-109903D01*
X659048Y-109911D01*
X659092Y-109922D01*
X659135Y-109936D01*
X659183Y-109951D01*
X659230Y-109973D01*
X659277Y-109998D01*
X659325Y-110027D01*
X659372Y-110064D01*
X659416Y-110104D01*
X659456Y-110147D01*
X659459Y-110151D01*
X659467Y-110162D01*
X659478Y-110180D01*
X659496Y-110209D01*
X659514Y-110242D01*
X659532Y-110286D01*
X659558Y-110336D01*
X659580Y-110395D01*
X659601Y-110460D01*
X659623Y-110537D01*
X659645Y-110620D01*
X659663Y-110715D01*
X659682Y-110817D01*
X659692Y-110926D01*
X659700Y-111046D01*
X659703Y-111174D01*
Y-111177D01*
Y-111192D01*
Y-111217D01*
Y-111247D01*
X659700Y-111287D01*
Y-111330D01*
X659696Y-111378D01*
X659692Y-111432D01*
X659682Y-111545D01*
X659663Y-111665D01*
X659641Y-111785D01*
X659627Y-111840D01*
X659612Y-111894D01*
Y-111898D01*
X659609Y-111905D01*
X659601Y-111920D01*
X659594Y-111938D01*
X659587Y-111964D01*
X659572Y-111989D01*
X659543Y-112051D01*
X659507Y-112117D01*
X659459Y-112186D01*
X659405Y-112255D01*
X659339Y-112313D01*
X659336D01*
X659332Y-112320D01*
X659321Y-112328D01*
X659306Y-112335D01*
X659288Y-112349D01*
X659267Y-112360D01*
X659212Y-112390D01*
X659146Y-112415D01*
X659070Y-112440D01*
X658979Y-112455D01*
X658881Y-112462D01*
X658848D01*
X658808Y-112459D01*
X658760Y-112451D01*
X658706Y-112440D01*
X658648Y-112426D01*
X658586Y-112408D01*
X658528Y-112379D01*
X658524D01*
X658520Y-112375D01*
X658502Y-112364D01*
X658473Y-112346D01*
X658437Y-112320D01*
X658397Y-112284D01*
X658353Y-112244D01*
X658313Y-112197D01*
X658273Y-112142D01*
X658269Y-112135D01*
X658255Y-112117D01*
X658240Y-112084D01*
X658215Y-112036D01*
X658193Y-111982D01*
X658164Y-111920D01*
X658138Y-111847D01*
X658116Y-111767D01*
Y-111763D01*
X658113Y-111756D01*
X658109Y-111745D01*
X658105Y-111727D01*
X658102Y-111705D01*
X658098Y-111680D01*
X658091Y-111647D01*
X658087Y-111610D01*
X658080Y-111571D01*
X658076Y-111527D01*
X658073Y-111476D01*
X658065Y-111425D01*
X658062Y-111367D01*
Y-111308D01*
X658058Y-111243D01*
Y-111174D01*
Y-111170D01*
Y-111155D01*
Y-111130D01*
Y-111101D01*
X658062Y-111061D01*
Y-111017D01*
X658065Y-110970D01*
X658069Y-110919D01*
X658080Y-110802D01*
X658098Y-110682D01*
X658120Y-110566D01*
X658135Y-110511D01*
X658153Y-110457D01*
Y-110453D01*
X658156Y-110446D01*
X658164Y-110431D01*
X658171Y-110413D01*
X658178Y-110388D01*
X658193Y-110362D01*
X658222Y-110300D01*
X658258Y-110235D01*
X658306Y-110162D01*
X658360Y-110096D01*
X658426Y-110034D01*
X658429D01*
X658433Y-110027D01*
X658444Y-110020D01*
X658458Y-110013D01*
X658477Y-110002D01*
X658495Y-109987D01*
X658549Y-109962D01*
X658615Y-109936D01*
X658691Y-109911D01*
X658782Y-109896D01*
X658881Y-109889D01*
X658917D01*
X658943Y-109892D01*
D02*
G37*
G36*
X694949Y-63539D02*
X694982Y-63543D01*
X695022Y-63547D01*
X695062Y-63550D01*
X695109Y-63561D01*
X695208Y-63583D01*
X695317Y-63616D01*
X695371Y-63638D01*
X695423Y-63663D01*
X695473Y-63696D01*
X695524Y-63728D01*
X695528Y-63732D01*
X695535Y-63736D01*
X695550Y-63747D01*
X695568Y-63765D01*
X695586Y-63783D01*
X695612Y-63809D01*
X695637Y-63838D01*
X695666Y-63867D01*
X695695Y-63903D01*
X695725Y-63947D01*
X695757Y-63990D01*
X695787Y-64038D01*
X695812Y-64092D01*
X695841Y-64147D01*
X695863Y-64205D01*
X695885Y-64271D01*
X695557Y-64347D01*
Y-64344D01*
X695553Y-64336D01*
X695546Y-64322D01*
X695539Y-64304D01*
X695532Y-64282D01*
X695521Y-64253D01*
X695492Y-64194D01*
X695455Y-64129D01*
X695411Y-64063D01*
X695357Y-64002D01*
X695299Y-63947D01*
X695291Y-63940D01*
X695270Y-63925D01*
X695233Y-63907D01*
X695186Y-63881D01*
X695124Y-63859D01*
X695055Y-63838D01*
X694971Y-63823D01*
X694880Y-63819D01*
X694851D01*
X694833Y-63823D01*
X694807D01*
X694778Y-63827D01*
X694709Y-63838D01*
X694633Y-63852D01*
X694553Y-63878D01*
X694469Y-63914D01*
X694392Y-63961D01*
X694389D01*
X694385Y-63969D01*
X694360Y-63987D01*
X694327Y-64016D01*
X694287Y-64060D01*
X694240Y-64114D01*
X694196Y-64176D01*
X694156Y-64253D01*
X694119Y-64336D01*
Y-64340D01*
X694116Y-64347D01*
X694112Y-64358D01*
X694108Y-64376D01*
X694101Y-64398D01*
X694094Y-64424D01*
X694083Y-64486D01*
X694068Y-64558D01*
X694054Y-64639D01*
X694046Y-64726D01*
X694043Y-64820D01*
Y-64824D01*
Y-64835D01*
Y-64853D01*
Y-64875D01*
X694046Y-64900D01*
Y-64933D01*
X694050Y-64970D01*
X694054Y-65010D01*
X694065Y-65097D01*
X694083Y-65192D01*
X694105Y-65286D01*
X694134Y-65381D01*
Y-65385D01*
X694137Y-65392D01*
X694145Y-65403D01*
X694152Y-65421D01*
X694174Y-65465D01*
X694207Y-65516D01*
X694247Y-65574D01*
X694298Y-65636D01*
X694356Y-65690D01*
X694425Y-65741D01*
X694429D01*
X694436Y-65745D01*
X694447Y-65752D01*
X694461Y-65760D01*
X694480Y-65767D01*
X694501Y-65778D01*
X694553Y-65800D01*
X694618Y-65821D01*
X694691Y-65840D01*
X694771Y-65854D01*
X694855Y-65858D01*
X694880D01*
X694902Y-65854D01*
X694927D01*
X694953Y-65851D01*
X695018Y-65836D01*
X695095Y-65818D01*
X695171Y-65789D01*
X695251Y-65749D01*
X695291Y-65727D01*
X695328Y-65698D01*
X695331Y-65694D01*
X695335Y-65690D01*
X695346Y-65680D01*
X695361Y-65669D01*
X695375Y-65650D01*
X695393Y-65628D01*
X695415Y-65607D01*
X695433Y-65578D01*
X695455Y-65545D01*
X695481Y-65508D01*
X695503Y-65472D01*
X695524Y-65428D01*
X695543Y-65381D01*
X695561Y-65330D01*
X695579Y-65276D01*
X695594Y-65217D01*
X695928Y-65301D01*
Y-65305D01*
X695925Y-65319D01*
X695918Y-65341D01*
X695907Y-65370D01*
X695896Y-65403D01*
X695881Y-65443D01*
X695863Y-65487D01*
X695841Y-65534D01*
X695790Y-65636D01*
X695725Y-65738D01*
X695684Y-65789D01*
X695645Y-65840D01*
X695601Y-65883D01*
X695550Y-65927D01*
X695546Y-65931D01*
X695539Y-65938D01*
X695521Y-65945D01*
X695503Y-65960D01*
X695473Y-65978D01*
X695444Y-65996D01*
X695404Y-66014D01*
X695364Y-66033D01*
X695317Y-66054D01*
X695266Y-66073D01*
X695211Y-66091D01*
X695153Y-66109D01*
X695091Y-66124D01*
X695026Y-66131D01*
X694956Y-66138D01*
X694884Y-66142D01*
X694844D01*
X694815Y-66138D01*
X694782D01*
X694742Y-66135D01*
X694698Y-66127D01*
X694647Y-66120D01*
X694542Y-66102D01*
X694432Y-66073D01*
X694323Y-66033D01*
X694272Y-66007D01*
X694221Y-65978D01*
X694218Y-65974D01*
X694210Y-65971D01*
X694196Y-65960D01*
X694181Y-65945D01*
X694159Y-65931D01*
X694134Y-65909D01*
X694105Y-65883D01*
X694076Y-65854D01*
X694046Y-65821D01*
X694014Y-65789D01*
X693948Y-65705D01*
X693886Y-65607D01*
X693832Y-65497D01*
Y-65494D01*
X693824Y-65483D01*
X693821Y-65465D01*
X693810Y-65443D01*
X693803Y-65414D01*
X693792Y-65377D01*
X693777Y-65337D01*
X693766Y-65294D01*
X693755Y-65246D01*
X693741Y-65192D01*
X693723Y-65079D01*
X693708Y-64951D01*
X693701Y-64820D01*
Y-64817D01*
Y-64802D01*
Y-64780D01*
X693704Y-64755D01*
Y-64719D01*
X693708Y-64682D01*
X693712Y-64635D01*
X693719Y-64587D01*
X693737Y-64482D01*
X693763Y-64366D01*
X693799Y-64249D01*
X693850Y-64136D01*
X693854Y-64132D01*
X693857Y-64122D01*
X693864Y-64107D01*
X693879Y-64089D01*
X693894Y-64063D01*
X693912Y-64034D01*
X693959Y-63969D01*
X694021Y-63896D01*
X694094Y-63823D01*
X694178Y-63750D01*
X694276Y-63688D01*
X694279Y-63685D01*
X694290Y-63681D01*
X694305Y-63674D01*
X694323Y-63663D01*
X694352Y-63652D01*
X694381Y-63641D01*
X694418Y-63626D01*
X694458Y-63612D01*
X694501Y-63597D01*
X694549Y-63583D01*
X694651Y-63561D01*
X694767Y-63543D01*
X694887Y-63535D01*
X694924D01*
X694949Y-63539D01*
D02*
G37*
G36*
X699004Y-63572D02*
X699022D01*
X699048Y-63576D01*
X699110Y-63586D01*
X699179Y-63601D01*
X699255Y-63626D01*
X699332Y-63659D01*
X699408Y-63703D01*
X699412D01*
X699415Y-63710D01*
X699427Y-63718D01*
X699441Y-63728D01*
X699477Y-63758D01*
X699525Y-63798D01*
X699572Y-63852D01*
X699627Y-63918D01*
X699674Y-63994D01*
X699718Y-64082D01*
Y-64085D01*
X699721Y-64092D01*
X699729Y-64107D01*
X699736Y-64125D01*
X699743Y-64151D01*
X699754Y-64183D01*
X699761Y-64220D01*
X699772Y-64260D01*
X699783Y-64307D01*
X699794Y-64362D01*
X699801Y-64420D01*
X699809Y-64482D01*
X699816Y-64551D01*
X699823Y-64624D01*
X699827Y-64704D01*
Y-64788D01*
Y-64791D01*
Y-64810D01*
Y-64835D01*
Y-64868D01*
X699823Y-64908D01*
Y-64955D01*
X699820Y-65010D01*
X699812Y-65064D01*
X699801Y-65188D01*
X699783Y-65319D01*
X699758Y-65443D01*
X699740Y-65505D01*
X699721Y-65559D01*
Y-65563D01*
X699718Y-65570D01*
X699710Y-65585D01*
X699703Y-65607D01*
X699692Y-65628D01*
X699678Y-65658D01*
X699641Y-65719D01*
X699598Y-65789D01*
X699547Y-65861D01*
X699481Y-65931D01*
X699408Y-65992D01*
X699405D01*
X699397Y-66000D01*
X699386Y-66007D01*
X699372Y-66014D01*
X699350Y-66025D01*
X699328Y-66040D01*
X699299Y-66054D01*
X699270Y-66065D01*
X699201Y-66094D01*
X699117Y-66120D01*
X699026Y-66135D01*
X698924Y-66142D01*
X698895D01*
X698877Y-66138D01*
X698851D01*
X698822Y-66135D01*
X698753Y-66120D01*
X698677Y-66102D01*
X698596Y-66073D01*
X698517Y-66033D01*
X698476Y-66007D01*
X698440Y-65978D01*
X698436Y-65974D01*
X698433Y-65971D01*
X698422Y-65960D01*
X698411Y-65949D01*
X698396Y-65931D01*
X698378Y-65909D01*
X698342Y-65858D01*
X698305Y-65792D01*
X698269Y-65712D01*
X698240Y-65621D01*
X698218Y-65516D01*
X698517Y-65490D01*
Y-65494D01*
X698520Y-65501D01*
Y-65508D01*
X698524Y-65523D01*
X698535Y-65563D01*
X698549Y-65607D01*
X698567Y-65658D01*
X698593Y-65709D01*
X698622Y-65756D01*
X698658Y-65796D01*
X698662Y-65800D01*
X698677Y-65811D01*
X698702Y-65825D01*
X698731Y-65840D01*
X698771Y-65858D01*
X698819Y-65872D01*
X698873Y-65883D01*
X698931Y-65887D01*
X698957D01*
X698982Y-65883D01*
X699015Y-65880D01*
X699055Y-65872D01*
X699095Y-65861D01*
X699139Y-65847D01*
X699179Y-65825D01*
X699183Y-65821D01*
X699197Y-65814D01*
X699219Y-65800D01*
X699241Y-65778D01*
X699270Y-65752D01*
X699299Y-65723D01*
X699328Y-65690D01*
X699357Y-65650D01*
X699361Y-65647D01*
X699368Y-65628D01*
X699383Y-65603D01*
X699397Y-65570D01*
X699415Y-65527D01*
X699434Y-65476D01*
X699452Y-65417D01*
X699470Y-65352D01*
Y-65348D01*
X699474Y-65345D01*
Y-65334D01*
X699477Y-65319D01*
X699485Y-65283D01*
X699496Y-65235D01*
X699503Y-65177D01*
X699510Y-65115D01*
X699514Y-65046D01*
X699517Y-64973D01*
Y-64970D01*
Y-64959D01*
Y-64941D01*
Y-64912D01*
X699514Y-64919D01*
X699499Y-64937D01*
X699477Y-64962D01*
X699452Y-64999D01*
X699415Y-65035D01*
X699372Y-65075D01*
X699321Y-65115D01*
X699263Y-65152D01*
X699255Y-65155D01*
X699233Y-65166D01*
X699201Y-65181D01*
X699161Y-65195D01*
X699106Y-65214D01*
X699048Y-65228D01*
X698982Y-65239D01*
X698913Y-65243D01*
X698884D01*
X698862Y-65239D01*
X698833Y-65235D01*
X698804Y-65232D01*
X698768Y-65224D01*
X698731Y-65214D01*
X698647Y-65188D01*
X698604Y-65170D01*
X698560Y-65148D01*
X698513Y-65123D01*
X698469Y-65090D01*
X698425Y-65057D01*
X698385Y-65017D01*
X698382Y-65013D01*
X698375Y-65006D01*
X698367Y-64995D01*
X698353Y-64977D01*
X698335Y-64951D01*
X698316Y-64926D01*
X698298Y-64893D01*
X698280Y-64857D01*
X698258Y-64817D01*
X698240Y-64773D01*
X698222Y-64722D01*
X698203Y-64671D01*
X698189Y-64613D01*
X698182Y-64551D01*
X698174Y-64489D01*
X698171Y-64420D01*
Y-64416D01*
Y-64402D01*
Y-64384D01*
X698174Y-64358D01*
X698178Y-64325D01*
X698182Y-64285D01*
X698189Y-64245D01*
X698200Y-64198D01*
X698225Y-64103D01*
X698244Y-64052D01*
X698265Y-63998D01*
X698291Y-63947D01*
X698323Y-63899D01*
X698356Y-63849D01*
X698396Y-63805D01*
X698400Y-63801D01*
X698407Y-63794D01*
X698418Y-63783D01*
X698436Y-63769D01*
X698458Y-63750D01*
X698487Y-63728D01*
X698517Y-63710D01*
X698553Y-63685D01*
X698589Y-63663D01*
X698633Y-63645D01*
X698731Y-63605D01*
X698782Y-63590D01*
X698840Y-63579D01*
X698899Y-63572D01*
X698960Y-63568D01*
X698986D01*
X699004Y-63572D01*
D02*
G37*
G36*
X697086D02*
X697115Y-63576D01*
X697148Y-63579D01*
X697184Y-63583D01*
X697221Y-63594D01*
X697308Y-63616D01*
X697395Y-63648D01*
X697439Y-63670D01*
X697483Y-63696D01*
X697523Y-63728D01*
X697563Y-63761D01*
X697566Y-63765D01*
X697570Y-63769D01*
X697581Y-63779D01*
X697596Y-63794D01*
X697610Y-63816D01*
X697628Y-63838D01*
X697665Y-63892D01*
X697701Y-63961D01*
X697734Y-64042D01*
X697759Y-64132D01*
X697763Y-64180D01*
X697767Y-64231D01*
Y-64234D01*
Y-64238D01*
Y-64260D01*
X697763Y-64293D01*
X697756Y-64333D01*
X697745Y-64384D01*
X697727Y-64435D01*
X697705Y-64486D01*
X697672Y-64536D01*
X697668Y-64544D01*
X697654Y-64558D01*
X697632Y-64580D01*
X697603Y-64609D01*
X697563Y-64642D01*
X697515Y-64675D01*
X697461Y-64708D01*
X697395Y-64737D01*
X697399D01*
X697406Y-64740D01*
X697417Y-64744D01*
X697432Y-64751D01*
X697475Y-64770D01*
X697526Y-64795D01*
X697581Y-64831D01*
X697639Y-64871D01*
X697694Y-64922D01*
X697745Y-64981D01*
Y-64984D01*
X697748Y-64988D01*
X697763Y-65010D01*
X697785Y-65046D01*
X697807Y-65093D01*
X697828Y-65152D01*
X697850Y-65221D01*
X697865Y-65297D01*
X697868Y-65381D01*
Y-65385D01*
Y-65396D01*
Y-65414D01*
X697865Y-65436D01*
X697861Y-65461D01*
X697858Y-65494D01*
X697850Y-65530D01*
X697839Y-65570D01*
X697814Y-65654D01*
X697796Y-65701D01*
X697770Y-65745D01*
X697745Y-65792D01*
X697716Y-65836D01*
X697679Y-65880D01*
X697639Y-65923D01*
X697636Y-65927D01*
X697628Y-65934D01*
X697617Y-65945D01*
X697599Y-65956D01*
X697574Y-65974D01*
X697548Y-65992D01*
X697515Y-66011D01*
X697479Y-66033D01*
X697439Y-66054D01*
X697392Y-66073D01*
X697341Y-66091D01*
X697290Y-66109D01*
X697231Y-66120D01*
X697170Y-66131D01*
X697108Y-66138D01*
X697039Y-66142D01*
X697002D01*
X696977Y-66138D01*
X696944Y-66135D01*
X696908Y-66131D01*
X696868Y-66124D01*
X696824Y-66113D01*
X696726Y-66087D01*
X696675Y-66069D01*
X696627Y-66051D01*
X696576Y-66025D01*
X696525Y-65996D01*
X696478Y-65963D01*
X696434Y-65923D01*
X696431Y-65920D01*
X696423Y-65912D01*
X696413Y-65901D01*
X696398Y-65883D01*
X696383Y-65861D01*
X696362Y-65836D01*
X696343Y-65807D01*
X696321Y-65771D01*
X696300Y-65734D01*
X696281Y-65690D01*
X696245Y-65599D01*
X696231Y-65545D01*
X696220Y-65490D01*
X696212Y-65432D01*
X696209Y-65374D01*
Y-65370D01*
Y-65363D01*
Y-65348D01*
X696212Y-65334D01*
Y-65312D01*
X696216Y-65286D01*
X696223Y-65228D01*
X696238Y-65163D01*
X696260Y-65097D01*
X696292Y-65028D01*
X696333Y-64962D01*
Y-64959D01*
X696340Y-64955D01*
X696354Y-64937D01*
X696383Y-64908D01*
X696423Y-64871D01*
X696474Y-64835D01*
X696536Y-64795D01*
X696605Y-64762D01*
X696689Y-64737D01*
X696686D01*
X696682Y-64733D01*
X696671Y-64729D01*
X696656Y-64722D01*
X696624Y-64708D01*
X696580Y-64686D01*
X696533Y-64657D01*
X696485Y-64620D01*
X696442Y-64580D01*
X696402Y-64536D01*
X696398Y-64529D01*
X696387Y-64515D01*
X696373Y-64486D01*
X696358Y-64449D01*
X696340Y-64402D01*
X696325Y-64347D01*
X696314Y-64285D01*
X696311Y-64220D01*
Y-64216D01*
Y-64209D01*
Y-64194D01*
X696314Y-64173D01*
X696318Y-64151D01*
X696321Y-64122D01*
X696336Y-64060D01*
X696358Y-63987D01*
X696394Y-63911D01*
X696416Y-63870D01*
X696442Y-63830D01*
X696474Y-63794D01*
X696507Y-63758D01*
X696511Y-63754D01*
X696518Y-63750D01*
X696529Y-63739D01*
X696544Y-63728D01*
X696562Y-63714D01*
X696587Y-63699D01*
X696616Y-63681D01*
X696645Y-63663D01*
X696682Y-63645D01*
X696722Y-63626D01*
X696766Y-63612D01*
X696813Y-63597D01*
X696915Y-63576D01*
X696973Y-63572D01*
X697031Y-63568D01*
X697064D01*
X697086Y-63572D01*
D02*
G37*
G36*
X664393Y-94492D02*
X664422D01*
X664454Y-94495D01*
X664491Y-94503D01*
X664535Y-94514D01*
X664578Y-94525D01*
X664629Y-94539D01*
X664680Y-94557D01*
X664731Y-94579D01*
X664786Y-94608D01*
X664837Y-94641D01*
X664888Y-94677D01*
X664938Y-94721D01*
X664986Y-94772D01*
X664990Y-94776D01*
X664997Y-94787D01*
X665008Y-94801D01*
X665022Y-94827D01*
X665044Y-94859D01*
X665062Y-94896D01*
X665084Y-94943D01*
X665106Y-94994D01*
X665132Y-95056D01*
X665153Y-95125D01*
X665171Y-95202D01*
X665190Y-95285D01*
X665208Y-95380D01*
X665219Y-95482D01*
X665226Y-95591D01*
X665230Y-95707D01*
Y-95711D01*
Y-95715D01*
Y-95726D01*
Y-95740D01*
X665226Y-95777D01*
Y-95828D01*
X665223Y-95886D01*
X665215Y-95955D01*
X665208Y-96031D01*
X665197Y-96115D01*
X665182Y-96199D01*
X665164Y-96290D01*
X665142Y-96377D01*
X665117Y-96465D01*
X665084Y-96548D01*
X665048Y-96628D01*
X665008Y-96705D01*
X664960Y-96770D01*
X664957Y-96774D01*
X664949Y-96781D01*
X664935Y-96796D01*
X664917Y-96818D01*
X664895Y-96840D01*
X664866Y-96861D01*
X664829Y-96890D01*
X664793Y-96916D01*
X664749Y-96942D01*
X664702Y-96971D01*
X664647Y-96992D01*
X664593Y-97018D01*
X664531Y-97036D01*
X664465Y-97051D01*
X664396Y-97058D01*
X664323Y-97062D01*
X664294D01*
X664272Y-97058D01*
X664247D01*
X664218Y-97054D01*
X664149Y-97040D01*
X664072Y-97022D01*
X663992Y-96992D01*
X663912Y-96949D01*
X663872Y-96923D01*
X663836Y-96894D01*
X663832Y-96890D01*
X663828Y-96887D01*
X663817Y-96876D01*
X663806Y-96865D01*
X663788Y-96847D01*
X663774Y-96825D01*
X663734Y-96774D01*
X663694Y-96709D01*
X663657Y-96628D01*
X663624Y-96538D01*
X663603Y-96435D01*
X663912Y-96410D01*
Y-96414D01*
X663916Y-96417D01*
X663919Y-96439D01*
X663930Y-96472D01*
X663945Y-96512D01*
X663959Y-96556D01*
X663981Y-96599D01*
X664007Y-96639D01*
X664032Y-96672D01*
X664040Y-96679D01*
X664054Y-96694D01*
X664080Y-96716D01*
X664116Y-96741D01*
X664163Y-96763D01*
X664214Y-96785D01*
X664276Y-96799D01*
X664342Y-96807D01*
X664367D01*
X664396Y-96803D01*
X664429Y-96796D01*
X664473Y-96785D01*
X664516Y-96770D01*
X664560Y-96752D01*
X664604Y-96723D01*
X664611Y-96719D01*
X664629Y-96705D01*
X664655Y-96679D01*
X664687Y-96643D01*
X664724Y-96599D01*
X664764Y-96548D01*
X664800Y-96483D01*
X664837Y-96410D01*
Y-96406D01*
X664840Y-96399D01*
X664844Y-96388D01*
X664851Y-96374D01*
X664855Y-96352D01*
X664862Y-96326D01*
X664869Y-96297D01*
X664877Y-96261D01*
X664888Y-96221D01*
X664895Y-96177D01*
X664902Y-96130D01*
X664906Y-96079D01*
X664913Y-96021D01*
X664917Y-95962D01*
X664920Y-95897D01*
Y-95831D01*
X664917Y-95835D01*
X664902Y-95857D01*
X664877Y-95886D01*
X664844Y-95922D01*
X664808Y-95966D01*
X664760Y-96006D01*
X664709Y-96046D01*
X664651Y-96083D01*
X664647D01*
X664644Y-96086D01*
X664622Y-96097D01*
X664589Y-96108D01*
X664545Y-96126D01*
X664494Y-96141D01*
X664436Y-96152D01*
X664374Y-96162D01*
X664309Y-96166D01*
X664280D01*
X664258Y-96162D01*
X664229Y-96159D01*
X664200Y-96155D01*
X664163Y-96148D01*
X664127Y-96137D01*
X664043Y-96112D01*
X663999Y-96093D01*
X663956Y-96068D01*
X663912Y-96042D01*
X663865Y-96013D01*
X663821Y-95977D01*
X663781Y-95937D01*
X663777Y-95933D01*
X663770Y-95926D01*
X663759Y-95915D01*
X663748Y-95897D01*
X663730Y-95871D01*
X663712Y-95846D01*
X663694Y-95813D01*
X663672Y-95777D01*
X663650Y-95737D01*
X663632Y-95693D01*
X663614Y-95642D01*
X663595Y-95591D01*
X663585Y-95537D01*
X663574Y-95475D01*
X663566Y-95413D01*
X663563Y-95347D01*
Y-95344D01*
Y-95336D01*
Y-95325D01*
Y-95307D01*
X663566Y-95285D01*
Y-95263D01*
X663577Y-95205D01*
X663588Y-95136D01*
X663606Y-95063D01*
X663632Y-94983D01*
X663668Y-94907D01*
Y-94903D01*
X663672Y-94899D01*
X663679Y-94889D01*
X663686Y-94874D01*
X663708Y-94838D01*
X663741Y-94790D01*
X663781Y-94739D01*
X663828Y-94688D01*
X663887Y-94637D01*
X663948Y-94594D01*
X663952D01*
X663956Y-94590D01*
X663967Y-94583D01*
X663981Y-94579D01*
X664018Y-94561D01*
X664065Y-94543D01*
X664127Y-94521D01*
X664196Y-94506D01*
X664272Y-94492D01*
X664356Y-94488D01*
X664374D01*
X664393Y-94492D01*
D02*
G37*
G36*
X668571D02*
X668604D01*
X668644Y-94495D01*
X668688Y-94503D01*
X668739Y-94510D01*
X668844Y-94528D01*
X668953Y-94557D01*
X669063Y-94597D01*
X669114Y-94623D01*
X669165Y-94652D01*
X669168Y-94656D01*
X669175Y-94659D01*
X669190Y-94670D01*
X669205Y-94685D01*
X669227Y-94699D01*
X669252Y-94721D01*
X669281Y-94747D01*
X669310Y-94776D01*
X669339Y-94809D01*
X669372Y-94841D01*
X669438Y-94925D01*
X669499Y-95023D01*
X669554Y-95132D01*
Y-95136D01*
X669561Y-95147D01*
X669565Y-95165D01*
X669576Y-95187D01*
X669583Y-95216D01*
X669594Y-95253D01*
X669609Y-95293D01*
X669620Y-95336D01*
X669630Y-95384D01*
X669645Y-95438D01*
X669663Y-95551D01*
X669678Y-95678D01*
X669685Y-95810D01*
Y-95813D01*
Y-95828D01*
Y-95850D01*
X669682Y-95875D01*
Y-95911D01*
X669678Y-95948D01*
X669674Y-95995D01*
X669667Y-96042D01*
X669649Y-96148D01*
X669623Y-96264D01*
X669587Y-96381D01*
X669536Y-96494D01*
X669532Y-96497D01*
X669529Y-96508D01*
X669521Y-96523D01*
X669507Y-96541D01*
X669492Y-96567D01*
X669474Y-96596D01*
X669427Y-96661D01*
X669365Y-96734D01*
X669292Y-96807D01*
X669208Y-96880D01*
X669110Y-96942D01*
X669106Y-96945D01*
X669095Y-96949D01*
X669081Y-96956D01*
X669063Y-96967D01*
X669033Y-96978D01*
X669004Y-96989D01*
X668968Y-97003D01*
X668928Y-97018D01*
X668884Y-97032D01*
X668837Y-97047D01*
X668735Y-97069D01*
X668619Y-97087D01*
X668498Y-97094D01*
X668462D01*
X668437Y-97091D01*
X668404Y-97087D01*
X668364Y-97083D01*
X668324Y-97080D01*
X668276Y-97069D01*
X668178Y-97047D01*
X668069Y-97014D01*
X668014Y-96992D01*
X667963Y-96967D01*
X667912Y-96934D01*
X667861Y-96902D01*
X667858Y-96898D01*
X667850Y-96894D01*
X667836Y-96883D01*
X667818Y-96865D01*
X667800Y-96847D01*
X667774Y-96821D01*
X667749Y-96792D01*
X667720Y-96763D01*
X667690Y-96727D01*
X667661Y-96683D01*
X667628Y-96639D01*
X667599Y-96592D01*
X667574Y-96538D01*
X667545Y-96483D01*
X667523Y-96425D01*
X667501Y-96359D01*
X667829Y-96283D01*
Y-96286D01*
X667832Y-96294D01*
X667840Y-96308D01*
X667847Y-96326D01*
X667854Y-96348D01*
X667865Y-96377D01*
X667894Y-96435D01*
X667931Y-96501D01*
X667974Y-96567D01*
X668029Y-96628D01*
X668087Y-96683D01*
X668094Y-96690D01*
X668116Y-96705D01*
X668153Y-96723D01*
X668200Y-96749D01*
X668262Y-96770D01*
X668331Y-96792D01*
X668415Y-96807D01*
X668506Y-96811D01*
X668535D01*
X668553Y-96807D01*
X668578D01*
X668608Y-96803D01*
X668677Y-96792D01*
X668753Y-96778D01*
X668833Y-96752D01*
X668917Y-96716D01*
X668994Y-96668D01*
X668997D01*
X669001Y-96661D01*
X669026Y-96643D01*
X669059Y-96614D01*
X669099Y-96570D01*
X669146Y-96516D01*
X669190Y-96454D01*
X669230Y-96377D01*
X669267Y-96294D01*
Y-96290D01*
X669270Y-96283D01*
X669274Y-96272D01*
X669277Y-96254D01*
X669285Y-96232D01*
X669292Y-96206D01*
X669303Y-96144D01*
X669317Y-96071D01*
X669332Y-95991D01*
X669339Y-95904D01*
X669343Y-95810D01*
Y-95806D01*
Y-95795D01*
Y-95777D01*
Y-95755D01*
X669339Y-95729D01*
Y-95697D01*
X669336Y-95660D01*
X669332Y-95620D01*
X669321Y-95533D01*
X669303Y-95438D01*
X669281Y-95344D01*
X669252Y-95249D01*
Y-95245D01*
X669248Y-95238D01*
X669241Y-95227D01*
X669234Y-95209D01*
X669212Y-95165D01*
X669179Y-95114D01*
X669139Y-95056D01*
X669088Y-94994D01*
X669030Y-94940D01*
X668961Y-94889D01*
X668957D01*
X668950Y-94885D01*
X668939Y-94878D01*
X668924Y-94870D01*
X668906Y-94863D01*
X668884Y-94852D01*
X668833Y-94830D01*
X668768Y-94809D01*
X668695Y-94790D01*
X668615Y-94776D01*
X668531Y-94772D01*
X668506D01*
X668484Y-94776D01*
X668458D01*
X668433Y-94779D01*
X668367Y-94794D01*
X668291Y-94812D01*
X668215Y-94841D01*
X668134Y-94881D01*
X668094Y-94903D01*
X668058Y-94932D01*
X668054Y-94936D01*
X668051Y-94940D01*
X668040Y-94950D01*
X668025Y-94961D01*
X668011Y-94980D01*
X667992Y-95001D01*
X667971Y-95023D01*
X667952Y-95052D01*
X667931Y-95085D01*
X667905Y-95122D01*
X667883Y-95158D01*
X667861Y-95202D01*
X667843Y-95249D01*
X667825Y-95300D01*
X667807Y-95354D01*
X667792Y-95413D01*
X667457Y-95329D01*
Y-95325D01*
X667461Y-95311D01*
X667468Y-95289D01*
X667479Y-95260D01*
X667490Y-95227D01*
X667505Y-95187D01*
X667523Y-95143D01*
X667545Y-95096D01*
X667596Y-94994D01*
X667661Y-94892D01*
X667701Y-94841D01*
X667741Y-94790D01*
X667785Y-94747D01*
X667836Y-94703D01*
X667840Y-94699D01*
X667847Y-94692D01*
X667865Y-94685D01*
X667883Y-94670D01*
X667912Y-94652D01*
X667942Y-94634D01*
X667982Y-94616D01*
X668022Y-94597D01*
X668069Y-94576D01*
X668120Y-94557D01*
X668175Y-94539D01*
X668233Y-94521D01*
X668295Y-94506D01*
X668360Y-94499D01*
X668429Y-94492D01*
X668502Y-94488D01*
X668542D01*
X668571Y-94492D01*
D02*
G37*
G36*
X666409D02*
X666442Y-94495D01*
X666478Y-94499D01*
X666518Y-94506D01*
X666562Y-94517D01*
X666660Y-94543D01*
X666711Y-94561D01*
X666758Y-94579D01*
X666810Y-94605D01*
X666860Y-94634D01*
X666908Y-94666D01*
X666952Y-94706D01*
X666955Y-94710D01*
X666962Y-94718D01*
X666973Y-94728D01*
X666988Y-94747D01*
X667002Y-94768D01*
X667024Y-94794D01*
X667042Y-94823D01*
X667064Y-94859D01*
X667086Y-94896D01*
X667104Y-94940D01*
X667141Y-95030D01*
X667155Y-95085D01*
X667166Y-95140D01*
X667173Y-95198D01*
X667177Y-95256D01*
Y-95260D01*
Y-95267D01*
Y-95282D01*
X667173Y-95296D01*
Y-95318D01*
X667170Y-95344D01*
X667163Y-95402D01*
X667148Y-95467D01*
X667126Y-95533D01*
X667093Y-95602D01*
X667053Y-95667D01*
Y-95671D01*
X667046Y-95675D01*
X667031Y-95693D01*
X667002Y-95722D01*
X666962Y-95758D01*
X666911Y-95795D01*
X666850Y-95835D01*
X666780Y-95868D01*
X666697Y-95893D01*
X666700D01*
X666704Y-95897D01*
X666715Y-95900D01*
X666729Y-95908D01*
X666762Y-95922D01*
X666806Y-95944D01*
X666853Y-95973D01*
X666900Y-96010D01*
X666944Y-96050D01*
X666984Y-96093D01*
X666988Y-96101D01*
X666999Y-96115D01*
X667013Y-96144D01*
X667028Y-96181D01*
X667046Y-96228D01*
X667061Y-96283D01*
X667072Y-96345D01*
X667075Y-96410D01*
Y-96414D01*
Y-96421D01*
Y-96435D01*
X667072Y-96457D01*
X667068Y-96479D01*
X667064Y-96508D01*
X667050Y-96570D01*
X667028Y-96643D01*
X666992Y-96719D01*
X666970Y-96759D01*
X666944Y-96799D01*
X666911Y-96836D01*
X666879Y-96872D01*
X666875Y-96876D01*
X666868Y-96880D01*
X666857Y-96890D01*
X666842Y-96902D01*
X666824Y-96916D01*
X666799Y-96931D01*
X666769Y-96949D01*
X666740Y-96967D01*
X666704Y-96985D01*
X666664Y-97003D01*
X666620Y-97018D01*
X666573Y-97032D01*
X666471Y-97054D01*
X666413Y-97058D01*
X666355Y-97062D01*
X666322D01*
X666300Y-97058D01*
X666271Y-97054D01*
X666238Y-97051D01*
X666202Y-97047D01*
X666165Y-97036D01*
X666078Y-97014D01*
X665990Y-96982D01*
X665947Y-96960D01*
X665903Y-96934D01*
X665863Y-96902D01*
X665823Y-96869D01*
X665819Y-96865D01*
X665816Y-96861D01*
X665805Y-96851D01*
X665790Y-96836D01*
X665776Y-96814D01*
X665758Y-96792D01*
X665721Y-96738D01*
X665685Y-96668D01*
X665652Y-96588D01*
X665626Y-96497D01*
X665623Y-96450D01*
X665619Y-96399D01*
Y-96395D01*
Y-96392D01*
Y-96370D01*
X665623Y-96337D01*
X665630Y-96297D01*
X665641Y-96246D01*
X665659Y-96195D01*
X665681Y-96144D01*
X665714Y-96093D01*
X665718Y-96086D01*
X665732Y-96071D01*
X665754Y-96050D01*
X665783Y-96021D01*
X665823Y-95988D01*
X665870Y-95955D01*
X665925Y-95922D01*
X665990Y-95893D01*
X665987D01*
X665980Y-95890D01*
X665969Y-95886D01*
X665954Y-95879D01*
X665910Y-95860D01*
X665860Y-95835D01*
X665805Y-95798D01*
X665747Y-95758D01*
X665692Y-95707D01*
X665641Y-95649D01*
Y-95646D01*
X665637Y-95642D01*
X665623Y-95620D01*
X665601Y-95584D01*
X665579Y-95537D01*
X665557Y-95478D01*
X665535Y-95409D01*
X665521Y-95333D01*
X665517Y-95249D01*
Y-95245D01*
Y-95234D01*
Y-95216D01*
X665521Y-95194D01*
X665525Y-95169D01*
X665528Y-95136D01*
X665535Y-95100D01*
X665546Y-95060D01*
X665572Y-94976D01*
X665590Y-94929D01*
X665616Y-94885D01*
X665641Y-94838D01*
X665670Y-94794D01*
X665707Y-94750D01*
X665747Y-94706D01*
X665750Y-94703D01*
X665758Y-94696D01*
X665768Y-94685D01*
X665787Y-94674D01*
X665812Y-94656D01*
X665838Y-94637D01*
X665870Y-94619D01*
X665907Y-94597D01*
X665947Y-94576D01*
X665994Y-94557D01*
X666045Y-94539D01*
X666096Y-94521D01*
X666154Y-94510D01*
X666216Y-94499D01*
X666278Y-94492D01*
X666347Y-94488D01*
X666384D01*
X666409Y-94492D01*
D02*
G37*
G36*
X679484Y-26564D02*
X677515D01*
X677518Y-26568D01*
X677533Y-26586D01*
X677555Y-26608D01*
X677580Y-26645D01*
X677613Y-26685D01*
X677649Y-26736D01*
X677689Y-26794D01*
X677729Y-26859D01*
Y-26863D01*
X677733Y-26867D01*
X677748Y-26888D01*
X677766Y-26925D01*
X677788Y-26969D01*
X677813Y-27020D01*
X677839Y-27074D01*
X677864Y-27129D01*
X677886Y-27183D01*
X677588D01*
Y-27180D01*
X677580Y-27172D01*
X677577Y-27158D01*
X677566Y-27140D01*
X677555Y-27118D01*
X677540Y-27092D01*
X677504Y-27030D01*
X677464Y-26958D01*
X677413Y-26885D01*
X677354Y-26808D01*
X677293Y-26732D01*
X677289Y-26728D01*
X677285Y-26725D01*
X677274Y-26714D01*
X677263Y-26699D01*
X677227Y-26666D01*
X677183Y-26623D01*
X677133Y-26579D01*
X677074Y-26532D01*
X677016Y-26492D01*
X676954Y-26455D01*
Y-26255D01*
X679484D01*
Y-26564D01*
D02*
G37*
G36*
X678294Y-27726D02*
X678341D01*
X678396Y-27729D01*
X678450Y-27737D01*
X678574Y-27747D01*
X678705Y-27766D01*
X678829Y-27791D01*
X678891Y-27809D01*
X678945Y-27828D01*
X678949D01*
X678956Y-27831D01*
X678971Y-27839D01*
X678993Y-27846D01*
X679014Y-27857D01*
X679043Y-27871D01*
X679105Y-27908D01*
X679175Y-27951D01*
X679247Y-28002D01*
X679317Y-28068D01*
X679378Y-28141D01*
Y-28144D01*
X679386Y-28152D01*
X679393Y-28162D01*
X679400Y-28177D01*
X679411Y-28199D01*
X679426Y-28221D01*
X679440Y-28250D01*
X679451Y-28279D01*
X679480Y-28348D01*
X679506Y-28432D01*
X679520Y-28523D01*
X679528Y-28625D01*
Y-28654D01*
X679524Y-28672D01*
Y-28697D01*
X679520Y-28727D01*
X679506Y-28796D01*
X679488Y-28872D01*
X679458Y-28952D01*
X679418Y-29032D01*
X679393Y-29072D01*
X679364Y-29109D01*
X679360Y-29112D01*
X679356Y-29116D01*
X679346Y-29127D01*
X679335Y-29138D01*
X679317Y-29153D01*
X679295Y-29171D01*
X679244Y-29207D01*
X679178Y-29243D01*
X679098Y-29280D01*
X679007Y-29309D01*
X678901Y-29331D01*
X678876Y-29032D01*
X678880D01*
X678887Y-29029D01*
X678894D01*
X678909Y-29025D01*
X678949Y-29014D01*
X678993Y-29000D01*
X679043Y-28981D01*
X679094Y-28956D01*
X679142Y-28927D01*
X679182Y-28890D01*
X679185Y-28887D01*
X679196Y-28872D01*
X679211Y-28847D01*
X679225Y-28818D01*
X679244Y-28778D01*
X679258Y-28730D01*
X679269Y-28676D01*
X679273Y-28617D01*
Y-28592D01*
X679269Y-28567D01*
X679265Y-28534D01*
X679258Y-28494D01*
X679247Y-28454D01*
X679233Y-28410D01*
X679211Y-28370D01*
X679207Y-28366D01*
X679200Y-28352D01*
X679185Y-28330D01*
X679164Y-28308D01*
X679138Y-28279D01*
X679109Y-28250D01*
X679076Y-28221D01*
X679036Y-28192D01*
X679033Y-28188D01*
X679014Y-28181D01*
X678989Y-28166D01*
X678956Y-28152D01*
X678912Y-28133D01*
X678862Y-28115D01*
X678803Y-28097D01*
X678738Y-28079D01*
X678734D01*
X678730Y-28075D01*
X678720D01*
X678705Y-28071D01*
X678669Y-28064D01*
X678621Y-28053D01*
X678563Y-28046D01*
X678501Y-28039D01*
X678432Y-28035D01*
X678359Y-28031D01*
X678356D01*
X678345D01*
X678326D01*
X678297D01*
X678305Y-28035D01*
X678323Y-28050D01*
X678348Y-28071D01*
X678385Y-28097D01*
X678421Y-28133D01*
X678461Y-28177D01*
X678501Y-28228D01*
X678538Y-28286D01*
X678541Y-28293D01*
X678552Y-28315D01*
X678567Y-28348D01*
X678581Y-28388D01*
X678599Y-28443D01*
X678614Y-28501D01*
X678625Y-28567D01*
X678628Y-28636D01*
Y-28665D01*
X678625Y-28687D01*
X678621Y-28716D01*
X678618Y-28745D01*
X678610Y-28781D01*
X678599Y-28818D01*
X678574Y-28901D01*
X678556Y-28945D01*
X678534Y-28989D01*
X678508Y-29036D01*
X678476Y-29080D01*
X678443Y-29123D01*
X678403Y-29163D01*
X678399Y-29167D01*
X678392Y-29174D01*
X678381Y-29182D01*
X678363Y-29196D01*
X678337Y-29214D01*
X678312Y-29233D01*
X678279Y-29251D01*
X678243Y-29269D01*
X678203Y-29291D01*
X678159Y-29309D01*
X678108Y-29327D01*
X678057Y-29345D01*
X677999Y-29360D01*
X677937Y-29367D01*
X677875Y-29375D01*
X677806Y-29378D01*
X677802D01*
X677788D01*
X677770D01*
X677744Y-29375D01*
X677711Y-29371D01*
X677671Y-29367D01*
X677631Y-29360D01*
X677584Y-29349D01*
X677489Y-29324D01*
X677438Y-29305D01*
X677384Y-29284D01*
X677333Y-29258D01*
X677285Y-29225D01*
X677234Y-29193D01*
X677191Y-29153D01*
X677187Y-29149D01*
X677180Y-29142D01*
X677169Y-29131D01*
X677154Y-29112D01*
X677136Y-29091D01*
X677114Y-29061D01*
X677096Y-29032D01*
X677071Y-28996D01*
X677049Y-28960D01*
X677031Y-28916D01*
X676991Y-28818D01*
X676976Y-28767D01*
X676965Y-28708D01*
X676958Y-28650D01*
X676954Y-28588D01*
Y-28563D01*
X676958Y-28545D01*
Y-28526D01*
X676961Y-28501D01*
X676972Y-28439D01*
X676987Y-28370D01*
X677012Y-28293D01*
X677045Y-28217D01*
X677089Y-28141D01*
Y-28137D01*
X677096Y-28133D01*
X677103Y-28122D01*
X677114Y-28108D01*
X677143Y-28071D01*
X677183Y-28024D01*
X677238Y-27977D01*
X677304Y-27922D01*
X677380Y-27875D01*
X677467Y-27831D01*
X677471D01*
X677478Y-27828D01*
X677493Y-27820D01*
X677511Y-27813D01*
X677536Y-27806D01*
X677569Y-27795D01*
X677606Y-27788D01*
X677646Y-27777D01*
X677693Y-27766D01*
X677748Y-27755D01*
X677806Y-27747D01*
X677868Y-27740D01*
X677937Y-27733D01*
X678010Y-27726D01*
X678090Y-27722D01*
X678173D01*
X678177D01*
X678195D01*
X678221D01*
X678254D01*
X678294Y-27726D01*
D02*
G37*
G36*
X678705Y-29666D02*
X678727Y-29673D01*
X678756Y-29684D01*
X678789Y-29695D01*
X678829Y-29709D01*
X678872Y-29728D01*
X678920Y-29750D01*
X679022Y-29800D01*
X679124Y-29866D01*
X679175Y-29906D01*
X679225Y-29946D01*
X679269Y-29990D01*
X679313Y-30041D01*
X679317Y-30044D01*
X679324Y-30052D01*
X679331Y-30070D01*
X679346Y-30088D01*
X679364Y-30117D01*
X679382Y-30146D01*
X679400Y-30186D01*
X679418Y-30226D01*
X679440Y-30274D01*
X679458Y-30325D01*
X679477Y-30379D01*
X679495Y-30437D01*
X679509Y-30499D01*
X679517Y-30565D01*
X679524Y-30634D01*
X679528Y-30707D01*
Y-30747D01*
X679524Y-30776D01*
Y-30809D01*
X679520Y-30849D01*
X679513Y-30892D01*
X679506Y-30943D01*
X679488Y-31049D01*
X679458Y-31158D01*
X679418Y-31267D01*
X679393Y-31318D01*
X679364Y-31369D01*
X679360Y-31373D01*
X679356Y-31380D01*
X679346Y-31395D01*
X679331Y-31409D01*
X679317Y-31431D01*
X679295Y-31457D01*
X679269Y-31486D01*
X679240Y-31515D01*
X679207Y-31544D01*
X679175Y-31577D01*
X679091Y-31642D01*
X678993Y-31704D01*
X678883Y-31759D01*
X678880D01*
X678869Y-31766D01*
X678851Y-31770D01*
X678829Y-31781D01*
X678800Y-31788D01*
X678763Y-31799D01*
X678723Y-31813D01*
X678680Y-31824D01*
X678632Y-31835D01*
X678578Y-31850D01*
X678465Y-31868D01*
X678337Y-31883D01*
X678206Y-31890D01*
X678203D01*
X678188D01*
X678166D01*
X678141Y-31886D01*
X678104D01*
X678068Y-31883D01*
X678021Y-31879D01*
X677973Y-31872D01*
X677868Y-31853D01*
X677751Y-31828D01*
X677635Y-31791D01*
X677522Y-31741D01*
X677518Y-31737D01*
X677507Y-31733D01*
X677493Y-31726D01*
X677475Y-31711D01*
X677449Y-31697D01*
X677420Y-31679D01*
X677354Y-31631D01*
X677282Y-31569D01*
X677209Y-31497D01*
X677136Y-31413D01*
X677074Y-31315D01*
X677071Y-31311D01*
X677067Y-31300D01*
X677060Y-31286D01*
X677049Y-31267D01*
X677038Y-31238D01*
X677027Y-31209D01*
X677012Y-31173D01*
X676998Y-31133D01*
X676983Y-31089D01*
X676969Y-31042D01*
X676947Y-30940D01*
X676929Y-30823D01*
X676921Y-30703D01*
Y-30667D01*
X676925Y-30641D01*
X676929Y-30608D01*
X676932Y-30569D01*
X676936Y-30528D01*
X676947Y-30481D01*
X676969Y-30383D01*
X677001Y-30274D01*
X677023Y-30219D01*
X677049Y-30168D01*
X677081Y-30117D01*
X677114Y-30066D01*
X677118Y-30062D01*
X677122Y-30055D01*
X677133Y-30041D01*
X677151Y-30022D01*
X677169Y-30004D01*
X677194Y-29979D01*
X677223Y-29953D01*
X677253Y-29924D01*
X677289Y-29895D01*
X677333Y-29866D01*
X677376Y-29833D01*
X677424Y-29804D01*
X677478Y-29779D01*
X677533Y-29750D01*
X677591Y-29728D01*
X677657Y-29706D01*
X677733Y-30033D01*
X677729D01*
X677722Y-30037D01*
X677708Y-30044D01*
X677689Y-30052D01*
X677668Y-30059D01*
X677638Y-30070D01*
X677580Y-30099D01*
X677515Y-30135D01*
X677449Y-30179D01*
X677387Y-30234D01*
X677333Y-30292D01*
X677325Y-30299D01*
X677311Y-30321D01*
X677293Y-30357D01*
X677267Y-30405D01*
X677245Y-30467D01*
X677223Y-30536D01*
X677209Y-30619D01*
X677205Y-30710D01*
Y-30740D01*
X677209Y-30758D01*
Y-30783D01*
X677213Y-30812D01*
X677223Y-30882D01*
X677238Y-30958D01*
X677263Y-31038D01*
X677300Y-31122D01*
X677347Y-31198D01*
Y-31202D01*
X677354Y-31205D01*
X677373Y-31231D01*
X677402Y-31264D01*
X677446Y-31304D01*
X677500Y-31351D01*
X677562Y-31395D01*
X677638Y-31435D01*
X677722Y-31471D01*
X677726D01*
X677733Y-31475D01*
X677744Y-31479D01*
X677762Y-31482D01*
X677784Y-31489D01*
X677809Y-31497D01*
X677871Y-31508D01*
X677944Y-31522D01*
X678024Y-31537D01*
X678112Y-31544D01*
X678206Y-31548D01*
X678210D01*
X678221D01*
X678239D01*
X678261D01*
X678286Y-31544D01*
X678319D01*
X678356Y-31540D01*
X678396Y-31537D01*
X678483Y-31526D01*
X678578Y-31508D01*
X678672Y-31486D01*
X678767Y-31457D01*
X678770D01*
X678778Y-31453D01*
X678789Y-31446D01*
X678807Y-31438D01*
X678851Y-31417D01*
X678901Y-31384D01*
X678960Y-31344D01*
X679022Y-31293D01*
X679076Y-31235D01*
X679127Y-31165D01*
Y-31162D01*
X679131Y-31155D01*
X679138Y-31144D01*
X679145Y-31129D01*
X679153Y-31111D01*
X679164Y-31089D01*
X679185Y-31038D01*
X679207Y-30972D01*
X679225Y-30900D01*
X679240Y-30820D01*
X679244Y-30736D01*
Y-30710D01*
X679240Y-30689D01*
Y-30663D01*
X679236Y-30638D01*
X679222Y-30572D01*
X679204Y-30496D01*
X679175Y-30419D01*
X679135Y-30339D01*
X679113Y-30299D01*
X679083Y-30263D01*
X679080Y-30259D01*
X679076Y-30255D01*
X679065Y-30244D01*
X679054Y-30230D01*
X679036Y-30215D01*
X679014Y-30197D01*
X678993Y-30175D01*
X678963Y-30157D01*
X678931Y-30135D01*
X678894Y-30110D01*
X678858Y-30088D01*
X678814Y-30066D01*
X678767Y-30048D01*
X678716Y-30030D01*
X678661Y-30012D01*
X678603Y-29997D01*
X678687Y-29662D01*
X678690D01*
X678705Y-29666D01*
D02*
G37*
G36*
X694051Y-33505D02*
X694047D01*
X694033D01*
X694011D01*
X693982Y-33501D01*
X693949Y-33498D01*
X693913Y-33490D01*
X693876Y-33483D01*
X693836Y-33468D01*
X693832D01*
X693829Y-33465D01*
X693807Y-33457D01*
X693774Y-33443D01*
X693730Y-33421D01*
X693680Y-33392D01*
X693621Y-33356D01*
X693563Y-33316D01*
X693501Y-33264D01*
X693498D01*
X693494Y-33257D01*
X693472Y-33239D01*
X693439Y-33206D01*
X693392Y-33159D01*
X693337Y-33104D01*
X693272Y-33035D01*
X693199Y-32952D01*
X693123Y-32860D01*
X693119Y-32857D01*
X693108Y-32842D01*
X693090Y-32820D01*
X693068Y-32795D01*
X693039Y-32762D01*
X693006Y-32722D01*
X692970Y-32682D01*
X692930Y-32635D01*
X692842Y-32544D01*
X692755Y-32453D01*
X692711Y-32409D01*
X692668Y-32369D01*
X692628Y-32333D01*
X692588Y-32304D01*
X692584D01*
X692580Y-32296D01*
X692569Y-32289D01*
X692555Y-32282D01*
X692515Y-32256D01*
X692467Y-32227D01*
X692409Y-32202D01*
X692347Y-32176D01*
X692278Y-32162D01*
X692213Y-32154D01*
X692209D01*
X692205D01*
X692183Y-32158D01*
X692147Y-32162D01*
X692107Y-32173D01*
X692056Y-32187D01*
X692005Y-32213D01*
X691954Y-32245D01*
X691903Y-32289D01*
X691896Y-32296D01*
X691881Y-32315D01*
X691863Y-32340D01*
X691838Y-32380D01*
X691816Y-32431D01*
X691794Y-32489D01*
X691780Y-32558D01*
X691776Y-32635D01*
Y-32657D01*
X691780Y-32671D01*
X691783Y-32715D01*
X691794Y-32766D01*
X691809Y-32820D01*
X691834Y-32882D01*
X691867Y-32941D01*
X691911Y-32995D01*
X691918Y-33002D01*
X691936Y-33017D01*
X691965Y-33039D01*
X692009Y-33061D01*
X692060Y-33086D01*
X692125Y-33108D01*
X692198Y-33123D01*
X692282Y-33130D01*
X692249Y-33446D01*
X692245D01*
X692235Y-33443D01*
X692216D01*
X692191Y-33439D01*
X692162Y-33432D01*
X692129Y-33425D01*
X692089Y-33414D01*
X692049Y-33403D01*
X691961Y-33374D01*
X691874Y-33330D01*
X691830Y-33305D01*
X691787Y-33272D01*
X691747Y-33239D01*
X691710Y-33203D01*
X691707Y-33199D01*
X691703Y-33192D01*
X691692Y-33181D01*
X691681Y-33163D01*
X691667Y-33141D01*
X691652Y-33115D01*
X691634Y-33086D01*
X691616Y-33050D01*
X691598Y-33010D01*
X691579Y-32966D01*
X691565Y-32919D01*
X691550Y-32868D01*
X691539Y-32813D01*
X691528Y-32755D01*
X691525Y-32693D01*
X691521Y-32627D01*
Y-32591D01*
X691525Y-32566D01*
X691528Y-32537D01*
X691532Y-32500D01*
X691539Y-32460D01*
X691546Y-32420D01*
X691572Y-32325D01*
X691608Y-32231D01*
X691630Y-32183D01*
X691656Y-32136D01*
X691688Y-32092D01*
X691725Y-32052D01*
X691728Y-32049D01*
X691732Y-32041D01*
X691747Y-32034D01*
X691761Y-32020D01*
X691780Y-32001D01*
X691805Y-31983D01*
X691830Y-31965D01*
X691863Y-31943D01*
X691932Y-31907D01*
X692020Y-31870D01*
X692063Y-31856D01*
X692114Y-31849D01*
X692165Y-31841D01*
X692220Y-31838D01*
X692227D01*
X692245D01*
X692275Y-31841D01*
X692315Y-31845D01*
X692358Y-31852D01*
X692409Y-31867D01*
X692464Y-31881D01*
X692518Y-31903D01*
X692526Y-31907D01*
X692544Y-31914D01*
X692573Y-31929D01*
X692613Y-31951D01*
X692657Y-31980D01*
X692711Y-32016D01*
X692766Y-32060D01*
X692828Y-32111D01*
X692835Y-32118D01*
X692857Y-32136D01*
X692875Y-32154D01*
X692893Y-32173D01*
X692915Y-32194D01*
X692944Y-32223D01*
X692973Y-32253D01*
X693006Y-32289D01*
X693043Y-32325D01*
X693083Y-32369D01*
X693123Y-32416D01*
X693170Y-32467D01*
X693217Y-32526D01*
X693268Y-32584D01*
X693272Y-32588D01*
X693279Y-32595D01*
X693290Y-32609D01*
X693305Y-32627D01*
X693327Y-32649D01*
X693348Y-32675D01*
X693396Y-32733D01*
X693450Y-32795D01*
X693505Y-32853D01*
X693552Y-32904D01*
X693570Y-32926D01*
X693589Y-32944D01*
X693592Y-32948D01*
X693603Y-32959D01*
X693618Y-32973D01*
X693640Y-32991D01*
X693665Y-33010D01*
X693690Y-33032D01*
X693752Y-33075D01*
Y-31834D01*
X694051D01*
Y-33505D01*
D02*
G37*
G36*
X692861Y-33767D02*
X692908D01*
X692963Y-33770D01*
X693017Y-33778D01*
X693141Y-33789D01*
X693272Y-33807D01*
X693396Y-33832D01*
X693458Y-33851D01*
X693512Y-33869D01*
X693516D01*
X693523Y-33872D01*
X693538Y-33880D01*
X693559Y-33887D01*
X693581Y-33898D01*
X693610Y-33912D01*
X693672Y-33949D01*
X693741Y-33992D01*
X693814Y-34043D01*
X693883Y-34109D01*
X693945Y-34182D01*
Y-34185D01*
X693953Y-34193D01*
X693960Y-34204D01*
X693967Y-34218D01*
X693978Y-34240D01*
X693993Y-34262D01*
X694007Y-34291D01*
X694018Y-34320D01*
X694047Y-34389D01*
X694073Y-34473D01*
X694087Y-34564D01*
X694095Y-34666D01*
Y-34695D01*
X694091Y-34713D01*
Y-34739D01*
X694087Y-34768D01*
X694073Y-34837D01*
X694055Y-34913D01*
X694025Y-34993D01*
X693985Y-35074D01*
X693960Y-35114D01*
X693931Y-35150D01*
X693927Y-35154D01*
X693923Y-35157D01*
X693913Y-35168D01*
X693902Y-35179D01*
X693883Y-35194D01*
X693862Y-35212D01*
X693811Y-35248D01*
X693745Y-35285D01*
X693665Y-35321D01*
X693574Y-35350D01*
X693468Y-35372D01*
X693443Y-35074D01*
X693447D01*
X693454Y-35070D01*
X693461D01*
X693476Y-35066D01*
X693516Y-35055D01*
X693559Y-35041D01*
X693610Y-35023D01*
X693661Y-34997D01*
X693709Y-34968D01*
X693749Y-34932D01*
X693752Y-34928D01*
X693763Y-34913D01*
X693778Y-34888D01*
X693792Y-34859D01*
X693811Y-34819D01*
X693825Y-34771D01*
X693836Y-34717D01*
X693840Y-34659D01*
Y-34633D01*
X693836Y-34608D01*
X693832Y-34575D01*
X693825Y-34535D01*
X693814Y-34495D01*
X693800Y-34451D01*
X693778Y-34411D01*
X693774Y-34407D01*
X693767Y-34393D01*
X693752Y-34371D01*
X693730Y-34349D01*
X693705Y-34320D01*
X693676Y-34291D01*
X693643Y-34262D01*
X693603Y-34233D01*
X693600Y-34229D01*
X693581Y-34222D01*
X693556Y-34207D01*
X693523Y-34193D01*
X693479Y-34174D01*
X693428Y-34156D01*
X693370Y-34138D01*
X693305Y-34120D01*
X693301D01*
X693297Y-34116D01*
X693286D01*
X693272Y-34113D01*
X693235Y-34105D01*
X693188Y-34094D01*
X693130Y-34087D01*
X693068Y-34080D01*
X692999Y-34076D01*
X692926Y-34073D01*
X692922D01*
X692911D01*
X692893D01*
X692864D01*
X692872Y-34076D01*
X692890Y-34091D01*
X692915Y-34113D01*
X692952Y-34138D01*
X692988Y-34174D01*
X693028Y-34218D01*
X693068Y-34269D01*
X693104Y-34327D01*
X693108Y-34335D01*
X693119Y-34356D01*
X693134Y-34389D01*
X693148Y-34429D01*
X693166Y-34484D01*
X693181Y-34542D01*
X693192Y-34608D01*
X693195Y-34677D01*
Y-34706D01*
X693192Y-34728D01*
X693188Y-34757D01*
X693185Y-34786D01*
X693177Y-34822D01*
X693166Y-34859D01*
X693141Y-34943D01*
X693123Y-34986D01*
X693101Y-35030D01*
X693075Y-35077D01*
X693043Y-35121D01*
X693010Y-35165D01*
X692970Y-35205D01*
X692966Y-35208D01*
X692959Y-35216D01*
X692948Y-35223D01*
X692930Y-35237D01*
X692904Y-35256D01*
X692879Y-35274D01*
X692846Y-35292D01*
X692810Y-35310D01*
X692770Y-35332D01*
X692726Y-35350D01*
X692675Y-35368D01*
X692624Y-35387D01*
X692566Y-35401D01*
X692504Y-35408D01*
X692442Y-35416D01*
X692373Y-35419D01*
X692369D01*
X692355D01*
X692336D01*
X692311Y-35416D01*
X692278Y-35412D01*
X692238Y-35408D01*
X692198Y-35401D01*
X692151Y-35390D01*
X692056Y-35365D01*
X692005Y-35347D01*
X691951Y-35325D01*
X691900Y-35299D01*
X691852Y-35267D01*
X691801Y-35234D01*
X691758Y-35194D01*
X691754Y-35190D01*
X691747Y-35183D01*
X691736Y-35172D01*
X691721Y-35154D01*
X691703Y-35132D01*
X691681Y-35103D01*
X691663Y-35074D01*
X691638Y-35037D01*
X691616Y-35001D01*
X691598Y-34957D01*
X691557Y-34859D01*
X691543Y-34808D01*
X691532Y-34750D01*
X691525Y-34691D01*
X691521Y-34629D01*
Y-34604D01*
X691525Y-34586D01*
Y-34568D01*
X691528Y-34542D01*
X691539Y-34480D01*
X691554Y-34411D01*
X691579Y-34335D01*
X691612Y-34258D01*
X691656Y-34182D01*
Y-34178D01*
X691663Y-34174D01*
X691670Y-34164D01*
X691681Y-34149D01*
X691710Y-34113D01*
X691750Y-34065D01*
X691805Y-34018D01*
X691870Y-33963D01*
X691947Y-33916D01*
X692034Y-33872D01*
X692038D01*
X692045Y-33869D01*
X692060Y-33862D01*
X692078Y-33854D01*
X692103Y-33847D01*
X692136Y-33836D01*
X692173Y-33829D01*
X692213Y-33818D01*
X692260Y-33807D01*
X692315Y-33796D01*
X692373Y-33789D01*
X692435Y-33781D01*
X692504Y-33774D01*
X692577Y-33767D01*
X692657Y-33763D01*
X692740D01*
X692744D01*
X692762D01*
X692788D01*
X692821D01*
X692861Y-33767D01*
D02*
G37*
G36*
X693272Y-35707D02*
X693294Y-35714D01*
X693323Y-35725D01*
X693356Y-35736D01*
X693396Y-35751D01*
X693439Y-35769D01*
X693487Y-35791D01*
X693589Y-35842D01*
X693690Y-35907D01*
X693741Y-35947D01*
X693792Y-35987D01*
X693836Y-36031D01*
X693880Y-36082D01*
X693883Y-36086D01*
X693891Y-36093D01*
X693898Y-36111D01*
X693913Y-36129D01*
X693931Y-36158D01*
X693949Y-36187D01*
X693967Y-36228D01*
X693985Y-36268D01*
X694007Y-36315D01*
X694025Y-36366D01*
X694044Y-36420D01*
X694062Y-36479D01*
X694076Y-36540D01*
X694084Y-36606D01*
X694091Y-36675D01*
X694095Y-36748D01*
Y-36788D01*
X694091Y-36817D01*
Y-36850D01*
X694087Y-36890D01*
X694080Y-36934D01*
X694073Y-36985D01*
X694055Y-37090D01*
X694025Y-37199D01*
X693985Y-37309D01*
X693960Y-37359D01*
X693931Y-37411D01*
X693927Y-37414D01*
X693923Y-37421D01*
X693913Y-37436D01*
X693898Y-37451D01*
X693883Y-37472D01*
X693862Y-37498D01*
X693836Y-37527D01*
X693807Y-37556D01*
X693774Y-37585D01*
X693741Y-37618D01*
X693658Y-37683D01*
X693559Y-37745D01*
X693450Y-37800D01*
X693447D01*
X693436Y-37807D01*
X693418Y-37811D01*
X693396Y-37822D01*
X693366Y-37829D01*
X693330Y-37840D01*
X693290Y-37855D01*
X693246Y-37865D01*
X693199Y-37876D01*
X693145Y-37891D01*
X693032Y-37909D01*
X692904Y-37924D01*
X692773Y-37931D01*
X692770D01*
X692755D01*
X692733D01*
X692708Y-37927D01*
X692671D01*
X692635Y-37924D01*
X692588Y-37920D01*
X692540Y-37913D01*
X692435Y-37895D01*
X692318Y-37869D01*
X692202Y-37833D01*
X692089Y-37782D01*
X692085Y-37778D01*
X692074Y-37775D01*
X692060Y-37767D01*
X692042Y-37753D01*
X692016Y-37738D01*
X691987Y-37720D01*
X691921Y-37673D01*
X691849Y-37611D01*
X691776Y-37538D01*
X691703Y-37454D01*
X691641Y-37356D01*
X691638Y-37352D01*
X691634Y-37341D01*
X691627Y-37327D01*
X691616Y-37309D01*
X691605Y-37279D01*
X691594Y-37250D01*
X691579Y-37214D01*
X691565Y-37174D01*
X691550Y-37130D01*
X691536Y-37083D01*
X691514Y-36981D01*
X691496Y-36865D01*
X691488Y-36744D01*
Y-36708D01*
X691492Y-36683D01*
X691496Y-36650D01*
X691499Y-36610D01*
X691503Y-36570D01*
X691514Y-36522D01*
X691536Y-36424D01*
X691568Y-36315D01*
X691590Y-36260D01*
X691616Y-36209D01*
X691648Y-36158D01*
X691681Y-36107D01*
X691685Y-36104D01*
X691688Y-36096D01*
X691699Y-36082D01*
X691718Y-36064D01*
X691736Y-36046D01*
X691761Y-36020D01*
X691790Y-35994D01*
X691819Y-35965D01*
X691856Y-35936D01*
X691900Y-35907D01*
X691943Y-35874D01*
X691991Y-35845D01*
X692045Y-35820D01*
X692100Y-35791D01*
X692158Y-35769D01*
X692224Y-35747D01*
X692300Y-36075D01*
X692296D01*
X692289Y-36078D01*
X692275Y-36086D01*
X692256Y-36093D01*
X692235Y-36100D01*
X692205Y-36111D01*
X692147Y-36140D01*
X692082Y-36176D01*
X692016Y-36220D01*
X691954Y-36275D01*
X691900Y-36333D01*
X691892Y-36340D01*
X691878Y-36362D01*
X691860Y-36399D01*
X691834Y-36446D01*
X691812Y-36508D01*
X691790Y-36577D01*
X691776Y-36661D01*
X691772Y-36752D01*
Y-36781D01*
X691776Y-36799D01*
Y-36824D01*
X691780Y-36854D01*
X691790Y-36923D01*
X691805Y-36999D01*
X691830Y-37079D01*
X691867Y-37163D01*
X691914Y-37239D01*
Y-37243D01*
X691921Y-37247D01*
X691940Y-37272D01*
X691969Y-37305D01*
X692012Y-37345D01*
X692067Y-37392D01*
X692129Y-37436D01*
X692205Y-37476D01*
X692289Y-37512D01*
X692293D01*
X692300Y-37516D01*
X692311Y-37520D01*
X692329Y-37523D01*
X692351Y-37531D01*
X692376Y-37538D01*
X692438Y-37549D01*
X692511Y-37563D01*
X692591Y-37578D01*
X692679Y-37585D01*
X692773Y-37589D01*
X692777D01*
X692788D01*
X692806D01*
X692828D01*
X692853Y-37585D01*
X692886D01*
X692922Y-37582D01*
X692963Y-37578D01*
X693050Y-37567D01*
X693145Y-37549D01*
X693239Y-37527D01*
X693334Y-37498D01*
X693337D01*
X693345Y-37494D01*
X693356Y-37487D01*
X693374Y-37480D01*
X693418Y-37458D01*
X693468Y-37425D01*
X693527Y-37385D01*
X693589Y-37334D01*
X693643Y-37276D01*
X693694Y-37207D01*
Y-37203D01*
X693698Y-37196D01*
X693705Y-37185D01*
X693712Y-37170D01*
X693720Y-37152D01*
X693730Y-37130D01*
X693752Y-37079D01*
X693774Y-37014D01*
X693792Y-36941D01*
X693807Y-36861D01*
X693811Y-36777D01*
Y-36752D01*
X693807Y-36730D01*
Y-36704D01*
X693803Y-36679D01*
X693789Y-36613D01*
X693771Y-36537D01*
X693741Y-36460D01*
X693701Y-36380D01*
X693680Y-36340D01*
X693650Y-36304D01*
X693647Y-36300D01*
X693643Y-36297D01*
X693632Y-36286D01*
X693621Y-36271D01*
X693603Y-36257D01*
X693581Y-36238D01*
X693559Y-36217D01*
X693530Y-36198D01*
X693498Y-36176D01*
X693461Y-36151D01*
X693425Y-36129D01*
X693381Y-36107D01*
X693334Y-36089D01*
X693283Y-36071D01*
X693228Y-36053D01*
X693170Y-36038D01*
X693254Y-35703D01*
X693257D01*
X693272Y-35707D01*
D02*
G37*
G36*
X619106Y-92201D02*
Y-92204D01*
Y-92219D01*
Y-92237D01*
Y-92263D01*
X619102Y-92295D01*
Y-92332D01*
X619099Y-92375D01*
X619095Y-92419D01*
X619084Y-92517D01*
X619070Y-92619D01*
X619048Y-92717D01*
X619033Y-92765D01*
X619019Y-92809D01*
Y-92812D01*
X619015Y-92819D01*
X619008Y-92830D01*
X619000Y-92845D01*
X618979Y-92885D01*
X618946Y-92936D01*
X618902Y-92994D01*
X618851Y-93052D01*
X618786Y-93114D01*
X618706Y-93169D01*
X618702D01*
X618695Y-93176D01*
X618684Y-93180D01*
X618666Y-93191D01*
X618644Y-93202D01*
X618615Y-93212D01*
X618586Y-93223D01*
X618549Y-93238D01*
X618509Y-93252D01*
X618466Y-93264D01*
X618418Y-93274D01*
X618364Y-93285D01*
X618309Y-93293D01*
X618251Y-93300D01*
X618120Y-93307D01*
X618087D01*
X618061Y-93304D01*
X618032D01*
X617996Y-93300D01*
X617956Y-93296D01*
X617916Y-93293D01*
X617825Y-93278D01*
X617727Y-93256D01*
X617632Y-93227D01*
X617541Y-93187D01*
X617537D01*
X617530Y-93180D01*
X617519Y-93173D01*
X617505Y-93165D01*
X617464Y-93136D01*
X617417Y-93096D01*
X617362Y-93045D01*
X617312Y-92987D01*
X617261Y-92914D01*
X617221Y-92834D01*
Y-92830D01*
X617217Y-92823D01*
X617213Y-92809D01*
X617206Y-92790D01*
X617199Y-92768D01*
X617192Y-92739D01*
X617180Y-92707D01*
X617173Y-92667D01*
X617166Y-92623D01*
X617155Y-92576D01*
X617148Y-92524D01*
X617140Y-92470D01*
X617133Y-92408D01*
X617130Y-92343D01*
X617126Y-92273D01*
Y-92201D01*
Y-90745D01*
X617461D01*
Y-92201D01*
Y-92204D01*
Y-92215D01*
Y-92233D01*
Y-92255D01*
X617464Y-92281D01*
Y-92313D01*
X617468Y-92383D01*
X617475Y-92463D01*
X617486Y-92543D01*
X617501Y-92619D01*
X617508Y-92652D01*
X617519Y-92685D01*
X617523Y-92692D01*
X617530Y-92710D01*
X617548Y-92736D01*
X617570Y-92772D01*
X617595Y-92809D01*
X617632Y-92848D01*
X617676Y-92888D01*
X617727Y-92921D01*
X617734Y-92925D01*
X617752Y-92936D01*
X617785Y-92947D01*
X617829Y-92961D01*
X617879Y-92980D01*
X617945Y-92990D01*
X618014Y-93001D01*
X618090Y-93005D01*
X618127D01*
X618149Y-93001D01*
X618182D01*
X618214Y-92998D01*
X618294Y-92983D01*
X618382Y-92965D01*
X618466Y-92936D01*
X618545Y-92896D01*
X618582Y-92870D01*
X618615Y-92841D01*
X618618Y-92838D01*
X618622Y-92834D01*
X618629Y-92823D01*
X618640Y-92809D01*
X618651Y-92787D01*
X618666Y-92765D01*
X618680Y-92732D01*
X618695Y-92699D01*
X618709Y-92659D01*
X618720Y-92612D01*
X618735Y-92557D01*
X618746Y-92499D01*
X618757Y-92434D01*
X618764Y-92364D01*
X618771Y-92284D01*
Y-92201D01*
Y-90745D01*
X619106D01*
Y-92201D01*
D02*
G37*
G36*
X622659Y-93264D02*
X622349D01*
Y-91294D01*
X622346Y-91298D01*
X622328Y-91312D01*
X622306Y-91334D01*
X622269Y-91360D01*
X622229Y-91392D01*
X622178Y-91429D01*
X622120Y-91469D01*
X622054Y-91509D01*
X622051D01*
X622047Y-91513D01*
X622025Y-91527D01*
X621989Y-91545D01*
X621945Y-91567D01*
X621894Y-91593D01*
X621840Y-91618D01*
X621785Y-91644D01*
X621731Y-91666D01*
Y-91367D01*
X621734D01*
X621741Y-91360D01*
X621756Y-91356D01*
X621774Y-91345D01*
X621796Y-91334D01*
X621821Y-91320D01*
X621883Y-91283D01*
X621956Y-91243D01*
X622029Y-91192D01*
X622106Y-91134D01*
X622182Y-91072D01*
X622186Y-91069D01*
X622189Y-91065D01*
X622200Y-91054D01*
X622215Y-91043D01*
X622247Y-91007D01*
X622291Y-90963D01*
X622335Y-90912D01*
X622382Y-90854D01*
X622422Y-90795D01*
X622459Y-90734D01*
X622659D01*
Y-93264D01*
D02*
G37*
G36*
X620431Y-90737D02*
X620460Y-90741D01*
X620497Y-90745D01*
X620537Y-90752D01*
X620577Y-90759D01*
X620671Y-90785D01*
X620766Y-90821D01*
X620813Y-90843D01*
X620861Y-90868D01*
X620904Y-90901D01*
X620944Y-90938D01*
X620948Y-90941D01*
X620955Y-90945D01*
X620962Y-90959D01*
X620977Y-90974D01*
X620995Y-90992D01*
X621013Y-91018D01*
X621032Y-91043D01*
X621054Y-91076D01*
X621090Y-91145D01*
X621126Y-91232D01*
X621141Y-91276D01*
X621148Y-91327D01*
X621155Y-91378D01*
X621159Y-91432D01*
Y-91440D01*
Y-91458D01*
X621155Y-91487D01*
X621152Y-91527D01*
X621144Y-91571D01*
X621130Y-91622D01*
X621115Y-91676D01*
X621094Y-91731D01*
X621090Y-91738D01*
X621083Y-91756D01*
X621068Y-91786D01*
X621046Y-91826D01*
X621017Y-91869D01*
X620981Y-91924D01*
X620937Y-91979D01*
X620886Y-92040D01*
X620879Y-92048D01*
X620861Y-92070D01*
X620842Y-92088D01*
X620824Y-92106D01*
X620802Y-92128D01*
X620773Y-92157D01*
X620744Y-92186D01*
X620708Y-92219D01*
X620671Y-92255D01*
X620628Y-92295D01*
X620580Y-92335D01*
X620529Y-92383D01*
X620471Y-92430D01*
X620413Y-92481D01*
X620409Y-92484D01*
X620402Y-92492D01*
X620387Y-92503D01*
X620369Y-92517D01*
X620347Y-92539D01*
X620322Y-92561D01*
X620264Y-92608D01*
X620202Y-92663D01*
X620144Y-92717D01*
X620092Y-92765D01*
X620071Y-92783D01*
X620052Y-92801D01*
X620049Y-92805D01*
X620038Y-92816D01*
X620023Y-92830D01*
X620005Y-92852D01*
X619987Y-92878D01*
X619965Y-92903D01*
X619921Y-92965D01*
X621163D01*
Y-93264D01*
X619492D01*
Y-93260D01*
Y-93245D01*
Y-93223D01*
X619496Y-93194D01*
X619499Y-93161D01*
X619507Y-93125D01*
X619514Y-93089D01*
X619528Y-93049D01*
Y-93045D01*
X619532Y-93041D01*
X619539Y-93020D01*
X619554Y-92987D01*
X619576Y-92943D01*
X619605Y-92892D01*
X619641Y-92834D01*
X619681Y-92776D01*
X619732Y-92714D01*
Y-92710D01*
X619739Y-92707D01*
X619758Y-92685D01*
X619790Y-92652D01*
X619838Y-92605D01*
X619892Y-92550D01*
X619962Y-92484D01*
X620045Y-92412D01*
X620136Y-92335D01*
X620140Y-92332D01*
X620154Y-92321D01*
X620176Y-92303D01*
X620202Y-92281D01*
X620234Y-92251D01*
X620274Y-92219D01*
X620315Y-92182D01*
X620362Y-92142D01*
X620453Y-92055D01*
X620544Y-91968D01*
X620588Y-91924D01*
X620628Y-91880D01*
X620664Y-91840D01*
X620693Y-91800D01*
Y-91796D01*
X620700Y-91793D01*
X620708Y-91782D01*
X620715Y-91767D01*
X620741Y-91727D01*
X620770Y-91680D01*
X620795Y-91622D01*
X620821Y-91560D01*
X620835Y-91491D01*
X620842Y-91425D01*
Y-91422D01*
Y-91418D01*
X620839Y-91396D01*
X620835Y-91360D01*
X620824Y-91320D01*
X620810Y-91269D01*
X620784Y-91218D01*
X620751Y-91167D01*
X620708Y-91116D01*
X620700Y-91109D01*
X620682Y-91094D01*
X620657Y-91076D01*
X620617Y-91050D01*
X620566Y-91028D01*
X620507Y-91007D01*
X620438Y-90992D01*
X620362Y-90988D01*
X620340D01*
X620326Y-90992D01*
X620282Y-90996D01*
X620231Y-91007D01*
X620176Y-91021D01*
X620114Y-91047D01*
X620056Y-91079D01*
X620002Y-91123D01*
X619994Y-91130D01*
X619980Y-91149D01*
X619958Y-91178D01*
X619936Y-91221D01*
X619910Y-91272D01*
X619889Y-91338D01*
X619874Y-91411D01*
X619867Y-91494D01*
X619550Y-91462D01*
Y-91458D01*
X619554Y-91447D01*
Y-91429D01*
X619558Y-91403D01*
X619565Y-91374D01*
X619572Y-91342D01*
X619583Y-91302D01*
X619594Y-91262D01*
X619623Y-91174D01*
X619667Y-91087D01*
X619692Y-91043D01*
X619725Y-90999D01*
X619758Y-90959D01*
X619794Y-90923D01*
X619798Y-90919D01*
X619805Y-90916D01*
X619816Y-90905D01*
X619834Y-90894D01*
X619856Y-90879D01*
X619881Y-90865D01*
X619910Y-90847D01*
X619947Y-90828D01*
X619987Y-90810D01*
X620031Y-90792D01*
X620078Y-90777D01*
X620129Y-90763D01*
X620184Y-90752D01*
X620242Y-90741D01*
X620304Y-90737D01*
X620369Y-90734D01*
X620406D01*
X620431Y-90737D01*
D02*
G37*
G36*
X628807Y-90705D02*
X628840Y-90708D01*
X628880Y-90712D01*
X628920Y-90715D01*
X628968Y-90726D01*
X629066Y-90748D01*
X629175Y-90781D01*
X629230Y-90803D01*
X629281Y-90828D01*
X629332Y-90861D01*
X629383Y-90894D01*
X629386Y-90898D01*
X629394Y-90901D01*
X629408Y-90912D01*
X629426Y-90930D01*
X629445Y-90948D01*
X629470Y-90974D01*
X629495Y-91003D01*
X629525Y-91032D01*
X629554Y-91069D01*
X629583Y-91112D01*
X629616Y-91156D01*
X629645Y-91203D01*
X629670Y-91258D01*
X629699Y-91312D01*
X629721Y-91371D01*
X629743Y-91436D01*
X629415Y-91513D01*
Y-91509D01*
X629412Y-91502D01*
X629404Y-91487D01*
X629397Y-91469D01*
X629390Y-91447D01*
X629379Y-91418D01*
X629350Y-91360D01*
X629314Y-91294D01*
X629270Y-91229D01*
X629215Y-91167D01*
X629157Y-91112D01*
X629150Y-91105D01*
X629128Y-91090D01*
X629091Y-91072D01*
X629044Y-91047D01*
X628982Y-91025D01*
X628913Y-91003D01*
X628829Y-90988D01*
X628738Y-90985D01*
X628709D01*
X628691Y-90988D01*
X628666D01*
X628636Y-90992D01*
X628567Y-91003D01*
X628491Y-91018D01*
X628411Y-91043D01*
X628327Y-91079D01*
X628251Y-91127D01*
X628247D01*
X628243Y-91134D01*
X628218Y-91152D01*
X628185Y-91181D01*
X628145Y-91225D01*
X628098Y-91280D01*
X628054Y-91342D01*
X628014Y-91418D01*
X627978Y-91502D01*
Y-91505D01*
X627974Y-91513D01*
X627970Y-91523D01*
X627967Y-91542D01*
X627959Y-91564D01*
X627952Y-91589D01*
X627941Y-91651D01*
X627927Y-91724D01*
X627912Y-91804D01*
X627905Y-91891D01*
X627901Y-91986D01*
Y-91989D01*
Y-92000D01*
Y-92019D01*
Y-92040D01*
X627905Y-92066D01*
Y-92099D01*
X627908Y-92135D01*
X627912Y-92175D01*
X627923Y-92263D01*
X627941Y-92357D01*
X627963Y-92452D01*
X627992Y-92546D01*
Y-92550D01*
X627996Y-92557D01*
X628003Y-92568D01*
X628010Y-92586D01*
X628032Y-92630D01*
X628065Y-92681D01*
X628105Y-92739D01*
X628156Y-92801D01*
X628214Y-92856D01*
X628283Y-92907D01*
X628287D01*
X628294Y-92910D01*
X628305Y-92918D01*
X628320Y-92925D01*
X628338Y-92932D01*
X628360Y-92943D01*
X628411Y-92965D01*
X628476Y-92987D01*
X628549Y-93005D01*
X628629Y-93020D01*
X628713Y-93023D01*
X628738D01*
X628760Y-93020D01*
X628786D01*
X628811Y-93016D01*
X628877Y-93001D01*
X628953Y-92983D01*
X629030Y-92954D01*
X629110Y-92914D01*
X629150Y-92892D01*
X629186Y-92863D01*
X629190Y-92859D01*
X629193Y-92856D01*
X629204Y-92845D01*
X629219Y-92834D01*
X629233Y-92816D01*
X629252Y-92794D01*
X629273Y-92772D01*
X629292Y-92743D01*
X629314Y-92710D01*
X629339Y-92674D01*
X629361Y-92637D01*
X629383Y-92594D01*
X629401Y-92546D01*
X629419Y-92495D01*
X629437Y-92441D01*
X629452Y-92383D01*
X629787Y-92466D01*
Y-92470D01*
X629783Y-92484D01*
X629776Y-92506D01*
X629765Y-92536D01*
X629754Y-92568D01*
X629739Y-92608D01*
X629721Y-92652D01*
X629699Y-92699D01*
X629648Y-92801D01*
X629583Y-92903D01*
X629543Y-92954D01*
X629503Y-93005D01*
X629459Y-93049D01*
X629408Y-93092D01*
X629404Y-93096D01*
X629397Y-93103D01*
X629379Y-93111D01*
X629361Y-93125D01*
X629332Y-93143D01*
X629303Y-93161D01*
X629262Y-93180D01*
X629222Y-93198D01*
X629175Y-93220D01*
X629124Y-93238D01*
X629070Y-93256D01*
X629011Y-93274D01*
X628949Y-93289D01*
X628884Y-93296D01*
X628815Y-93304D01*
X628742Y-93307D01*
X628702D01*
X628673Y-93304D01*
X628640D01*
X628600Y-93300D01*
X628556Y-93293D01*
X628505Y-93285D01*
X628400Y-93267D01*
X628291Y-93238D01*
X628182Y-93198D01*
X628130Y-93173D01*
X628080Y-93143D01*
X628076Y-93140D01*
X628069Y-93136D01*
X628054Y-93125D01*
X628040Y-93111D01*
X628018Y-93096D01*
X627992Y-93074D01*
X627963Y-93049D01*
X627934Y-93020D01*
X627905Y-92987D01*
X627872Y-92954D01*
X627807Y-92870D01*
X627745Y-92772D01*
X627690Y-92663D01*
Y-92659D01*
X627683Y-92648D01*
X627679Y-92630D01*
X627668Y-92608D01*
X627661Y-92579D01*
X627650Y-92543D01*
X627635Y-92503D01*
X627625Y-92459D01*
X627614Y-92412D01*
X627599Y-92357D01*
X627581Y-92244D01*
X627566Y-92117D01*
X627559Y-91986D01*
Y-91982D01*
Y-91968D01*
Y-91946D01*
X627563Y-91920D01*
Y-91884D01*
X627566Y-91847D01*
X627570Y-91800D01*
X627577Y-91753D01*
X627595Y-91647D01*
X627621Y-91531D01*
X627657Y-91414D01*
X627708Y-91302D01*
X627712Y-91298D01*
X627715Y-91287D01*
X627723Y-91272D01*
X627737Y-91254D01*
X627752Y-91229D01*
X627770Y-91200D01*
X627817Y-91134D01*
X627879Y-91061D01*
X627952Y-90988D01*
X628036Y-90916D01*
X628134Y-90854D01*
X628138Y-90850D01*
X628149Y-90847D01*
X628163Y-90839D01*
X628182Y-90828D01*
X628211Y-90817D01*
X628240Y-90807D01*
X628276Y-90792D01*
X628316Y-90777D01*
X628360Y-90763D01*
X628407Y-90748D01*
X628509Y-90726D01*
X628625Y-90708D01*
X628746Y-90701D01*
X628782D01*
X628807Y-90705D01*
D02*
G37*
G36*
X630904Y-90737D02*
X630922D01*
X630948Y-90741D01*
X631010Y-90752D01*
X631079Y-90766D01*
X631155Y-90792D01*
X631232Y-90825D01*
X631308Y-90868D01*
X631312D01*
X631316Y-90876D01*
X631326Y-90883D01*
X631341Y-90894D01*
X631377Y-90923D01*
X631425Y-90963D01*
X631472Y-91018D01*
X631527Y-91083D01*
X631574Y-91159D01*
X631618Y-91247D01*
Y-91250D01*
X631621Y-91258D01*
X631629Y-91272D01*
X631636Y-91291D01*
X631643Y-91316D01*
X631654Y-91349D01*
X631661Y-91385D01*
X631672Y-91425D01*
X631683Y-91473D01*
X631694Y-91527D01*
X631701Y-91585D01*
X631709Y-91647D01*
X631716Y-91716D01*
X631723Y-91789D01*
X631727Y-91869D01*
Y-91953D01*
Y-91957D01*
Y-91975D01*
Y-92000D01*
Y-92033D01*
X631723Y-92073D01*
Y-92120D01*
X631719Y-92175D01*
X631712Y-92230D01*
X631701Y-92353D01*
X631683Y-92484D01*
X631658Y-92608D01*
X631639Y-92670D01*
X631621Y-92725D01*
Y-92728D01*
X631618Y-92736D01*
X631610Y-92750D01*
X631603Y-92772D01*
X631592Y-92794D01*
X631578Y-92823D01*
X631541Y-92885D01*
X631497Y-92954D01*
X631447Y-93027D01*
X631381Y-93096D01*
X631308Y-93158D01*
X631305D01*
X631297Y-93165D01*
X631286Y-93173D01*
X631272Y-93180D01*
X631250Y-93191D01*
X631228Y-93205D01*
X631199Y-93220D01*
X631170Y-93231D01*
X631101Y-93260D01*
X631017Y-93285D01*
X630926Y-93300D01*
X630824Y-93307D01*
X630795D01*
X630777Y-93304D01*
X630751D01*
X630722Y-93300D01*
X630653Y-93285D01*
X630577Y-93267D01*
X630497Y-93238D01*
X630416Y-93198D01*
X630376Y-93173D01*
X630340Y-93143D01*
X630336Y-93140D01*
X630333Y-93136D01*
X630322Y-93125D01*
X630311Y-93114D01*
X630296Y-93096D01*
X630278Y-93074D01*
X630242Y-93023D01*
X630205Y-92958D01*
X630169Y-92878D01*
X630140Y-92787D01*
X630118Y-92681D01*
X630416Y-92656D01*
Y-92659D01*
X630420Y-92667D01*
Y-92674D01*
X630424Y-92688D01*
X630435Y-92728D01*
X630449Y-92772D01*
X630467Y-92823D01*
X630493Y-92874D01*
X630522Y-92921D01*
X630558Y-92961D01*
X630562Y-92965D01*
X630577Y-92976D01*
X630602Y-92990D01*
X630631Y-93005D01*
X630671Y-93023D01*
X630719Y-93038D01*
X630773Y-93049D01*
X630831Y-93052D01*
X630857D01*
X630882Y-93049D01*
X630915Y-93045D01*
X630955Y-93038D01*
X630995Y-93027D01*
X631039Y-93012D01*
X631079Y-92990D01*
X631082Y-92987D01*
X631097Y-92980D01*
X631119Y-92965D01*
X631141Y-92943D01*
X631170Y-92918D01*
X631199Y-92888D01*
X631228Y-92856D01*
X631257Y-92816D01*
X631261Y-92812D01*
X631268Y-92794D01*
X631283Y-92768D01*
X631297Y-92736D01*
X631316Y-92692D01*
X631334Y-92641D01*
X631352Y-92583D01*
X631370Y-92517D01*
Y-92514D01*
X631374Y-92510D01*
Y-92499D01*
X631377Y-92484D01*
X631385Y-92448D01*
X631396Y-92401D01*
X631403Y-92343D01*
X631410Y-92281D01*
X631414Y-92212D01*
X631417Y-92139D01*
Y-92135D01*
Y-92124D01*
Y-92106D01*
Y-92077D01*
X631414Y-92084D01*
X631399Y-92102D01*
X631377Y-92128D01*
X631352Y-92164D01*
X631316Y-92201D01*
X631272Y-92241D01*
X631221Y-92281D01*
X631163Y-92317D01*
X631155Y-92321D01*
X631134Y-92332D01*
X631101Y-92346D01*
X631061Y-92361D01*
X631006Y-92379D01*
X630948Y-92393D01*
X630882Y-92404D01*
X630813Y-92408D01*
X630784D01*
X630762Y-92404D01*
X630733Y-92401D01*
X630704Y-92397D01*
X630668Y-92390D01*
X630631Y-92379D01*
X630548Y-92353D01*
X630504Y-92335D01*
X630460Y-92313D01*
X630413Y-92288D01*
X630369Y-92255D01*
X630325Y-92222D01*
X630285Y-92182D01*
X630282Y-92179D01*
X630274Y-92172D01*
X630267Y-92160D01*
X630253Y-92142D01*
X630234Y-92117D01*
X630216Y-92091D01*
X630198Y-92059D01*
X630180Y-92022D01*
X630158Y-91982D01*
X630140Y-91939D01*
X630122Y-91887D01*
X630103Y-91837D01*
X630089Y-91778D01*
X630082Y-91716D01*
X630074Y-91655D01*
X630071Y-91585D01*
Y-91582D01*
Y-91567D01*
Y-91549D01*
X630074Y-91523D01*
X630078Y-91491D01*
X630082Y-91451D01*
X630089Y-91411D01*
X630100Y-91363D01*
X630125Y-91269D01*
X630143Y-91218D01*
X630165Y-91163D01*
X630191Y-91112D01*
X630224Y-91065D01*
X630256Y-91014D01*
X630296Y-90970D01*
X630300Y-90967D01*
X630307Y-90959D01*
X630318Y-90948D01*
X630336Y-90934D01*
X630358Y-90916D01*
X630387Y-90894D01*
X630416Y-90876D01*
X630453Y-90850D01*
X630489Y-90828D01*
X630533Y-90810D01*
X630631Y-90770D01*
X630682Y-90755D01*
X630740Y-90745D01*
X630799Y-90737D01*
X630861Y-90734D01*
X630886D01*
X630904Y-90737D01*
D02*
G37*
G36*
X633328Y-92375D02*
X633671D01*
Y-92659D01*
X633328D01*
Y-93264D01*
X633019D01*
Y-92659D01*
X631923D01*
Y-92375D01*
X633077Y-90745D01*
X633328D01*
Y-92375D01*
D02*
G37*
G36*
X586232Y-92201D02*
Y-92204D01*
Y-92219D01*
Y-92237D01*
Y-92263D01*
X586228Y-92295D01*
Y-92332D01*
X586225Y-92375D01*
X586221Y-92419D01*
X586210Y-92517D01*
X586196Y-92619D01*
X586174Y-92717D01*
X586159Y-92765D01*
X586145Y-92809D01*
Y-92812D01*
X586141Y-92819D01*
X586134Y-92830D01*
X586127Y-92845D01*
X586105Y-92885D01*
X586072Y-92936D01*
X586028Y-92994D01*
X585977Y-93052D01*
X585912Y-93114D01*
X585832Y-93169D01*
X585828D01*
X585821Y-93176D01*
X585810Y-93180D01*
X585792Y-93191D01*
X585770Y-93202D01*
X585741Y-93212D01*
X585712Y-93223D01*
X585675Y-93238D01*
X585635Y-93252D01*
X585591Y-93264D01*
X585544Y-93274D01*
X585490Y-93285D01*
X585435Y-93293D01*
X585377Y-93300D01*
X585246Y-93307D01*
X585213D01*
X585187Y-93304D01*
X585158D01*
X585122Y-93300D01*
X585082Y-93296D01*
X585042Y-93293D01*
X584951Y-93278D01*
X584853Y-93256D01*
X584758Y-93227D01*
X584667Y-93187D01*
X584663D01*
X584656Y-93180D01*
X584645Y-93173D01*
X584630Y-93165D01*
X584590Y-93136D01*
X584543Y-93096D01*
X584488Y-93045D01*
X584438Y-92987D01*
X584387Y-92914D01*
X584347Y-92834D01*
Y-92830D01*
X584343Y-92823D01*
X584339Y-92809D01*
X584332Y-92790D01*
X584325Y-92768D01*
X584317Y-92739D01*
X584306Y-92707D01*
X584299Y-92667D01*
X584292Y-92623D01*
X584281Y-92576D01*
X584274Y-92524D01*
X584267Y-92470D01*
X584259Y-92408D01*
X584256Y-92343D01*
X584252Y-92273D01*
Y-92201D01*
Y-90745D01*
X584587D01*
Y-92201D01*
Y-92204D01*
Y-92215D01*
Y-92233D01*
Y-92255D01*
X584590Y-92281D01*
Y-92313D01*
X584594Y-92383D01*
X584601Y-92463D01*
X584612Y-92543D01*
X584627Y-92619D01*
X584634Y-92652D01*
X584645Y-92685D01*
X584649Y-92692D01*
X584656Y-92710D01*
X584674Y-92736D01*
X584696Y-92772D01*
X584722Y-92809D01*
X584758Y-92848D01*
X584802Y-92888D01*
X584853Y-92921D01*
X584860Y-92925D01*
X584878Y-92936D01*
X584911Y-92947D01*
X584954Y-92961D01*
X585005Y-92980D01*
X585071Y-92990D01*
X585140Y-93001D01*
X585217Y-93005D01*
X585253D01*
X585275Y-93001D01*
X585308D01*
X585340Y-92998D01*
X585420Y-92983D01*
X585508Y-92965D01*
X585591Y-92936D01*
X585672Y-92896D01*
X585708Y-92870D01*
X585741Y-92841D01*
X585744Y-92838D01*
X585748Y-92834D01*
X585755Y-92823D01*
X585766Y-92809D01*
X585777Y-92787D01*
X585792Y-92765D01*
X585806Y-92732D01*
X585821Y-92699D01*
X585835Y-92659D01*
X585846Y-92612D01*
X585861Y-92557D01*
X585872Y-92499D01*
X585883Y-92434D01*
X585890Y-92364D01*
X585897Y-92284D01*
Y-92201D01*
Y-90745D01*
X586232D01*
Y-92201D01*
D02*
G37*
G36*
X589515Y-90737D02*
X589544Y-90741D01*
X589581Y-90745D01*
X589621Y-90752D01*
X589661Y-90759D01*
X589756Y-90785D01*
X589850Y-90821D01*
X589898Y-90843D01*
X589945Y-90868D01*
X589989Y-90901D01*
X590029Y-90938D01*
X590032Y-90941D01*
X590039Y-90945D01*
X590047Y-90959D01*
X590061Y-90974D01*
X590080Y-90992D01*
X590098Y-91018D01*
X590116Y-91043D01*
X590138Y-91076D01*
X590174Y-91145D01*
X590211Y-91232D01*
X590225Y-91276D01*
X590232Y-91327D01*
X590240Y-91378D01*
X590243Y-91432D01*
Y-91440D01*
Y-91458D01*
X590240Y-91487D01*
X590236Y-91527D01*
X590229Y-91571D01*
X590214Y-91622D01*
X590200Y-91676D01*
X590178Y-91731D01*
X590174Y-91738D01*
X590167Y-91756D01*
X590152Y-91786D01*
X590131Y-91826D01*
X590101Y-91869D01*
X590065Y-91924D01*
X590021Y-91979D01*
X589970Y-92040D01*
X589963Y-92048D01*
X589945Y-92070D01*
X589927Y-92088D01*
X589909Y-92106D01*
X589887Y-92128D01*
X589857Y-92157D01*
X589828Y-92186D01*
X589792Y-92219D01*
X589756Y-92255D01*
X589712Y-92295D01*
X589665Y-92335D01*
X589614Y-92383D01*
X589555Y-92430D01*
X589497Y-92481D01*
X589494Y-92484D01*
X589486Y-92492D01*
X589472Y-92503D01*
X589454Y-92517D01*
X589432Y-92539D01*
X589406Y-92561D01*
X589348Y-92608D01*
X589286Y-92663D01*
X589228Y-92717D01*
X589177Y-92765D01*
X589155Y-92783D01*
X589137Y-92801D01*
X589133Y-92805D01*
X589122Y-92816D01*
X589108Y-92830D01*
X589089Y-92852D01*
X589071Y-92878D01*
X589049Y-92903D01*
X589006Y-92965D01*
X590247D01*
Y-93264D01*
X588576D01*
Y-93260D01*
Y-93245D01*
Y-93223D01*
X588580Y-93194D01*
X588584Y-93161D01*
X588591Y-93125D01*
X588598Y-93089D01*
X588613Y-93049D01*
Y-93045D01*
X588616Y-93041D01*
X588624Y-93020D01*
X588638Y-92987D01*
X588660Y-92943D01*
X588689Y-92892D01*
X588726Y-92834D01*
X588765Y-92776D01*
X588816Y-92714D01*
Y-92710D01*
X588824Y-92707D01*
X588842Y-92685D01*
X588875Y-92652D01*
X588922Y-92605D01*
X588977Y-92550D01*
X589046Y-92484D01*
X589129Y-92412D01*
X589221Y-92335D01*
X589224Y-92332D01*
X589239Y-92321D01*
X589261Y-92303D01*
X589286Y-92281D01*
X589319Y-92251D01*
X589359Y-92219D01*
X589399Y-92182D01*
X589446Y-92142D01*
X589537Y-92055D01*
X589628Y-91968D01*
X589672Y-91924D01*
X589712Y-91880D01*
X589748Y-91840D01*
X589777Y-91800D01*
Y-91796D01*
X589785Y-91793D01*
X589792Y-91782D01*
X589799Y-91767D01*
X589825Y-91727D01*
X589854Y-91680D01*
X589879Y-91622D01*
X589905Y-91560D01*
X589919Y-91491D01*
X589927Y-91425D01*
Y-91422D01*
Y-91418D01*
X589923Y-91396D01*
X589919Y-91360D01*
X589909Y-91320D01*
X589894Y-91269D01*
X589868Y-91218D01*
X589836Y-91167D01*
X589792Y-91116D01*
X589785Y-91109D01*
X589767Y-91094D01*
X589741Y-91076D01*
X589701Y-91050D01*
X589650Y-91028D01*
X589592Y-91007D01*
X589523Y-90992D01*
X589446Y-90988D01*
X589424D01*
X589410Y-90992D01*
X589366Y-90996D01*
X589315Y-91007D01*
X589261Y-91021D01*
X589199Y-91047D01*
X589140Y-91079D01*
X589086Y-91123D01*
X589079Y-91130D01*
X589064Y-91149D01*
X589042Y-91178D01*
X589020Y-91221D01*
X588995Y-91272D01*
X588973Y-91338D01*
X588958Y-91411D01*
X588951Y-91494D01*
X588634Y-91462D01*
Y-91458D01*
X588638Y-91447D01*
Y-91429D01*
X588642Y-91403D01*
X588649Y-91374D01*
X588656Y-91342D01*
X588667Y-91302D01*
X588678Y-91262D01*
X588707Y-91174D01*
X588751Y-91087D01*
X588776Y-91043D01*
X588809Y-90999D01*
X588842Y-90959D01*
X588878Y-90923D01*
X588882Y-90919D01*
X588889Y-90916D01*
X588900Y-90905D01*
X588918Y-90894D01*
X588940Y-90879D01*
X588966Y-90865D01*
X588995Y-90847D01*
X589031Y-90828D01*
X589071Y-90810D01*
X589115Y-90792D01*
X589162Y-90777D01*
X589213Y-90763D01*
X589268Y-90752D01*
X589326Y-90741D01*
X589388Y-90737D01*
X589454Y-90734D01*
X589490D01*
X589515Y-90737D01*
D02*
G37*
G36*
X587557D02*
X587586Y-90741D01*
X587623Y-90745D01*
X587663Y-90752D01*
X587703Y-90759D01*
X587797Y-90785D01*
X587892Y-90821D01*
X587939Y-90843D01*
X587987Y-90868D01*
X588030Y-90901D01*
X588070Y-90938D01*
X588074Y-90941D01*
X588081Y-90945D01*
X588089Y-90959D01*
X588103Y-90974D01*
X588121Y-90992D01*
X588139Y-91018D01*
X588158Y-91043D01*
X588179Y-91076D01*
X588216Y-91145D01*
X588252Y-91232D01*
X588267Y-91276D01*
X588274Y-91327D01*
X588281Y-91378D01*
X588285Y-91432D01*
Y-91440D01*
Y-91458D01*
X588281Y-91487D01*
X588278Y-91527D01*
X588271Y-91571D01*
X588256Y-91622D01*
X588241Y-91676D01*
X588219Y-91731D01*
X588216Y-91738D01*
X588209Y-91756D01*
X588194Y-91786D01*
X588172Y-91826D01*
X588143Y-91869D01*
X588107Y-91924D01*
X588063Y-91979D01*
X588012Y-92040D01*
X588005Y-92048D01*
X587987Y-92070D01*
X587968Y-92088D01*
X587950Y-92106D01*
X587928Y-92128D01*
X587899Y-92157D01*
X587870Y-92186D01*
X587834Y-92219D01*
X587797Y-92255D01*
X587754Y-92295D01*
X587706Y-92335D01*
X587655Y-92383D01*
X587597Y-92430D01*
X587539Y-92481D01*
X587535Y-92484D01*
X587528Y-92492D01*
X587513Y-92503D01*
X587495Y-92517D01*
X587473Y-92539D01*
X587448Y-92561D01*
X587390Y-92608D01*
X587328Y-92663D01*
X587269Y-92717D01*
X587219Y-92765D01*
X587197Y-92783D01*
X587179Y-92801D01*
X587175Y-92805D01*
X587164Y-92816D01*
X587149Y-92830D01*
X587131Y-92852D01*
X587113Y-92878D01*
X587091Y-92903D01*
X587047Y-92965D01*
X588289D01*
Y-93264D01*
X586618D01*
Y-93260D01*
Y-93245D01*
Y-93223D01*
X586622Y-93194D01*
X586625Y-93161D01*
X586632Y-93125D01*
X586640Y-93089D01*
X586654Y-93049D01*
Y-93045D01*
X586658Y-93041D01*
X586665Y-93020D01*
X586680Y-92987D01*
X586702Y-92943D01*
X586731Y-92892D01*
X586767Y-92834D01*
X586807Y-92776D01*
X586858Y-92714D01*
Y-92710D01*
X586865Y-92707D01*
X586884Y-92685D01*
X586916Y-92652D01*
X586964Y-92605D01*
X587018Y-92550D01*
X587087Y-92484D01*
X587171Y-92412D01*
X587262Y-92335D01*
X587266Y-92332D01*
X587280Y-92321D01*
X587302Y-92303D01*
X587328Y-92281D01*
X587360Y-92251D01*
X587400Y-92219D01*
X587441Y-92182D01*
X587488Y-92142D01*
X587579Y-92055D01*
X587670Y-91968D01*
X587714Y-91924D01*
X587754Y-91880D01*
X587790Y-91840D01*
X587819Y-91800D01*
Y-91796D01*
X587826Y-91793D01*
X587834Y-91782D01*
X587841Y-91767D01*
X587866Y-91727D01*
X587896Y-91680D01*
X587921Y-91622D01*
X587947Y-91560D01*
X587961Y-91491D01*
X587968Y-91425D01*
Y-91422D01*
Y-91418D01*
X587965Y-91396D01*
X587961Y-91360D01*
X587950Y-91320D01*
X587936Y-91269D01*
X587910Y-91218D01*
X587877Y-91167D01*
X587834Y-91116D01*
X587826Y-91109D01*
X587808Y-91094D01*
X587783Y-91076D01*
X587743Y-91050D01*
X587692Y-91028D01*
X587634Y-91007D01*
X587564Y-90992D01*
X587488Y-90988D01*
X587466D01*
X587452Y-90992D01*
X587408Y-90996D01*
X587357Y-91007D01*
X587302Y-91021D01*
X587240Y-91047D01*
X587182Y-91079D01*
X587127Y-91123D01*
X587120Y-91130D01*
X587106Y-91149D01*
X587084Y-91178D01*
X587062Y-91221D01*
X587037Y-91272D01*
X587015Y-91338D01*
X587000Y-91411D01*
X586993Y-91494D01*
X586676Y-91462D01*
Y-91458D01*
X586680Y-91447D01*
Y-91429D01*
X586683Y-91403D01*
X586691Y-91374D01*
X586698Y-91342D01*
X586709Y-91302D01*
X586720Y-91262D01*
X586749Y-91174D01*
X586793Y-91087D01*
X586818Y-91043D01*
X586851Y-90999D01*
X586884Y-90959D01*
X586920Y-90923D01*
X586924Y-90919D01*
X586931Y-90916D01*
X586942Y-90905D01*
X586960Y-90894D01*
X586982Y-90879D01*
X587007Y-90865D01*
X587037Y-90847D01*
X587073Y-90828D01*
X587113Y-90810D01*
X587157Y-90792D01*
X587204Y-90777D01*
X587255Y-90763D01*
X587310Y-90752D01*
X587368Y-90741D01*
X587430Y-90737D01*
X587495Y-90734D01*
X587532D01*
X587557Y-90737D01*
D02*
G37*
G36*
X596407Y-85989D02*
X596436Y-85993D01*
X596469Y-85996D01*
X596509Y-86004D01*
X596549Y-86011D01*
X596643Y-86033D01*
X596742Y-86069D01*
X596793Y-86091D01*
X596840Y-86120D01*
X596891Y-86149D01*
X596938Y-86186D01*
X596942Y-86189D01*
X596953Y-86197D01*
X596968Y-86211D01*
X596986Y-86229D01*
X597008Y-86255D01*
X597037Y-86284D01*
X597062Y-86320D01*
X597091Y-86360D01*
X597120Y-86404D01*
X597146Y-86455D01*
X597171Y-86510D01*
X597197Y-86568D01*
X597215Y-86630D01*
X597230Y-86699D01*
X597240Y-86772D01*
X597244Y-86848D01*
Y-86881D01*
X597240Y-86906D01*
X597237Y-86935D01*
X597233Y-86968D01*
X597230Y-87008D01*
X597219Y-87048D01*
X597197Y-87139D01*
X597164Y-87230D01*
X597142Y-87278D01*
X597117Y-87325D01*
X597088Y-87369D01*
X597055Y-87412D01*
X597051Y-87416D01*
X597048Y-87423D01*
X597033Y-87430D01*
X597018Y-87445D01*
X597000Y-87463D01*
X596978Y-87481D01*
X596949Y-87503D01*
X596916Y-87521D01*
X596884Y-87543D01*
X596844Y-87565D01*
X596756Y-87605D01*
X596654Y-87638D01*
X596600Y-87649D01*
X596542Y-87656D01*
X596516Y-87332D01*
X596520D01*
X596527D01*
X596538Y-87328D01*
X596556Y-87325D01*
X596596Y-87314D01*
X596651Y-87299D01*
X596705Y-87278D01*
X596767Y-87248D01*
X596822Y-87212D01*
X596873Y-87168D01*
X596876Y-87161D01*
X596891Y-87147D01*
X596909Y-87117D01*
X596931Y-87077D01*
X596953Y-87034D01*
X596971Y-86979D01*
X596986Y-86917D01*
X596989Y-86848D01*
Y-86826D01*
X596986Y-86812D01*
X596982Y-86768D01*
X596968Y-86717D01*
X596949Y-86655D01*
X596920Y-86593D01*
X596876Y-86528D01*
X596851Y-86499D01*
X596822Y-86470D01*
X596818Y-86466D01*
X596815Y-86462D01*
X596804Y-86455D01*
X596793Y-86444D01*
X596753Y-86418D01*
X596702Y-86389D01*
X596640Y-86364D01*
X596563Y-86338D01*
X596472Y-86320D01*
X596425Y-86313D01*
X596374D01*
X596371D01*
X596363D01*
X596349D01*
X596330Y-86317D01*
X596309D01*
X596283Y-86320D01*
X596225Y-86331D01*
X596156Y-86349D01*
X596087Y-86375D01*
X596021Y-86411D01*
X595959Y-86462D01*
X595956D01*
X595952Y-86470D01*
X595934Y-86488D01*
X595908Y-86520D01*
X595879Y-86564D01*
X595854Y-86622D01*
X595828Y-86688D01*
X595810Y-86764D01*
X595803Y-86808D01*
Y-86877D01*
X595806Y-86906D01*
X595810Y-86943D01*
X595821Y-86986D01*
X595832Y-87030D01*
X595850Y-87077D01*
X595872Y-87125D01*
X595876Y-87128D01*
X595883Y-87143D01*
X595901Y-87165D01*
X595919Y-87194D01*
X595945Y-87223D01*
X595977Y-87252D01*
X596010Y-87285D01*
X596050Y-87310D01*
X596010Y-87602D01*
X594714Y-87358D01*
Y-86106D01*
X595009D01*
Y-87114D01*
X595690Y-87248D01*
X595686Y-87245D01*
X595683Y-87238D01*
X595675Y-87227D01*
X595664Y-87208D01*
X595653Y-87186D01*
X595639Y-87161D01*
X595610Y-87103D01*
X595581Y-87030D01*
X595555Y-86950D01*
X595537Y-86863D01*
X595530Y-86819D01*
Y-86739D01*
X595533Y-86717D01*
X595537Y-86688D01*
X595541Y-86655D01*
X595548Y-86619D01*
X595559Y-86579D01*
X595584Y-86491D01*
X595603Y-86444D01*
X595628Y-86397D01*
X595653Y-86349D01*
X595683Y-86302D01*
X595719Y-86258D01*
X595759Y-86215D01*
X595763Y-86211D01*
X595770Y-86204D01*
X595781Y-86193D01*
X595799Y-86178D01*
X595824Y-86160D01*
X595850Y-86142D01*
X595883Y-86120D01*
X595919Y-86098D01*
X595959Y-86080D01*
X596003Y-86058D01*
X596054Y-86040D01*
X596105Y-86022D01*
X596159Y-86007D01*
X596221Y-85996D01*
X596283Y-85989D01*
X596349Y-85985D01*
X596352D01*
X596363D01*
X596381D01*
X596407Y-85989D01*
D02*
G37*
G36*
X596010Y-87962D02*
X596058D01*
X596112Y-87966D01*
X596167Y-87973D01*
X596290Y-87984D01*
X596421Y-88002D01*
X596545Y-88027D01*
X596607Y-88046D01*
X596662Y-88064D01*
X596665D01*
X596673Y-88067D01*
X596687Y-88075D01*
X596709Y-88082D01*
X596731Y-88093D01*
X596760Y-88108D01*
X596822Y-88144D01*
X596891Y-88187D01*
X596964Y-88239D01*
X597033Y-88304D01*
X597095Y-88377D01*
Y-88380D01*
X597102Y-88388D01*
X597109Y-88399D01*
X597117Y-88413D01*
X597128Y-88435D01*
X597142Y-88457D01*
X597157Y-88486D01*
X597168Y-88515D01*
X597197Y-88584D01*
X597222Y-88668D01*
X597237Y-88759D01*
X597244Y-88861D01*
Y-88890D01*
X597240Y-88908D01*
Y-88934D01*
X597237Y-88963D01*
X597222Y-89032D01*
X597204Y-89109D01*
X597175Y-89188D01*
X597135Y-89269D01*
X597109Y-89309D01*
X597080Y-89345D01*
X597077Y-89349D01*
X597073Y-89352D01*
X597062Y-89363D01*
X597051Y-89374D01*
X597033Y-89389D01*
X597011Y-89407D01*
X596960Y-89443D01*
X596895Y-89480D01*
X596815Y-89516D01*
X596724Y-89545D01*
X596618Y-89567D01*
X596593Y-89269D01*
X596596D01*
X596603Y-89265D01*
X596611D01*
X596625Y-89261D01*
X596665Y-89250D01*
X596709Y-89236D01*
X596760Y-89218D01*
X596811Y-89192D01*
X596858Y-89163D01*
X596898Y-89127D01*
X596902Y-89123D01*
X596913Y-89109D01*
X596927Y-89083D01*
X596942Y-89054D01*
X596960Y-89014D01*
X596975Y-88967D01*
X596986Y-88912D01*
X596989Y-88854D01*
Y-88828D01*
X596986Y-88803D01*
X596982Y-88770D01*
X596975Y-88730D01*
X596964Y-88690D01*
X596949Y-88646D01*
X596927Y-88606D01*
X596924Y-88603D01*
X596916Y-88588D01*
X596902Y-88566D01*
X596880Y-88544D01*
X596855Y-88515D01*
X596826Y-88486D01*
X596793Y-88457D01*
X596753Y-88428D01*
X596749Y-88424D01*
X596731Y-88417D01*
X596705Y-88402D01*
X596673Y-88388D01*
X596629Y-88370D01*
X596578Y-88351D01*
X596520Y-88333D01*
X596454Y-88315D01*
X596451D01*
X596447Y-88311D01*
X596436D01*
X596421Y-88308D01*
X596385Y-88300D01*
X596338Y-88289D01*
X596279Y-88282D01*
X596218Y-88275D01*
X596148Y-88271D01*
X596076Y-88268D01*
X596072D01*
X596061D01*
X596043D01*
X596014D01*
X596021Y-88271D01*
X596039Y-88286D01*
X596065Y-88308D01*
X596101Y-88333D01*
X596138Y-88370D01*
X596178Y-88413D01*
X596218Y-88464D01*
X596254Y-88522D01*
X596258Y-88530D01*
X596269Y-88551D01*
X596283Y-88584D01*
X596298Y-88624D01*
X596316Y-88679D01*
X596330Y-88737D01*
X596341Y-88803D01*
X596345Y-88872D01*
Y-88901D01*
X596341Y-88923D01*
X596338Y-88952D01*
X596334Y-88981D01*
X596327Y-89017D01*
X596316Y-89054D01*
X596290Y-89138D01*
X596272Y-89181D01*
X596250Y-89225D01*
X596225Y-89272D01*
X596192Y-89316D01*
X596159Y-89360D01*
X596119Y-89400D01*
X596116Y-89403D01*
X596108Y-89411D01*
X596098Y-89418D01*
X596079Y-89432D01*
X596054Y-89451D01*
X596028Y-89469D01*
X595996Y-89487D01*
X595959Y-89505D01*
X595919Y-89527D01*
X595876Y-89545D01*
X595824Y-89564D01*
X595774Y-89582D01*
X595715Y-89596D01*
X595653Y-89604D01*
X595592Y-89611D01*
X595522Y-89614D01*
X595519D01*
X595504D01*
X595486D01*
X595461Y-89611D01*
X595428Y-89607D01*
X595388Y-89604D01*
X595348Y-89596D01*
X595300Y-89585D01*
X595206Y-89560D01*
X595155Y-89542D01*
X595100Y-89520D01*
X595049Y-89494D01*
X595002Y-89461D01*
X594951Y-89429D01*
X594907Y-89389D01*
X594904Y-89385D01*
X594896Y-89378D01*
X594885Y-89367D01*
X594871Y-89349D01*
X594853Y-89327D01*
X594831Y-89298D01*
X594813Y-89269D01*
X594787Y-89232D01*
X594765Y-89196D01*
X594747Y-89152D01*
X594707Y-89054D01*
X594693Y-89003D01*
X594682Y-88945D01*
X594674Y-88886D01*
X594671Y-88824D01*
Y-88799D01*
X594674Y-88781D01*
Y-88763D01*
X594678Y-88737D01*
X594689Y-88675D01*
X594703Y-88606D01*
X594729Y-88530D01*
X594762Y-88453D01*
X594805Y-88377D01*
Y-88373D01*
X594813Y-88370D01*
X594820Y-88359D01*
X594831Y-88344D01*
X594860Y-88308D01*
X594900Y-88260D01*
X594955Y-88213D01*
X595020Y-88158D01*
X595096Y-88111D01*
X595184Y-88067D01*
X595188D01*
X595195Y-88064D01*
X595209Y-88056D01*
X595228Y-88049D01*
X595253Y-88042D01*
X595286Y-88031D01*
X595322Y-88024D01*
X595362Y-88013D01*
X595410Y-88002D01*
X595464Y-87991D01*
X595522Y-87984D01*
X595584Y-87976D01*
X595653Y-87969D01*
X595726Y-87962D01*
X595806Y-87958D01*
X595890D01*
X595894D01*
X595912D01*
X595937D01*
X595970D01*
X596010Y-87962D01*
D02*
G37*
G36*
X596421Y-89902D02*
X596443Y-89909D01*
X596472Y-89920D01*
X596505Y-89931D01*
X596545Y-89946D01*
X596589Y-89964D01*
X596636Y-89986D01*
X596738Y-90037D01*
X596840Y-90102D01*
X596891Y-90142D01*
X596942Y-90182D01*
X596986Y-90226D01*
X597029Y-90277D01*
X597033Y-90281D01*
X597040Y-90288D01*
X597048Y-90306D01*
X597062Y-90324D01*
X597080Y-90353D01*
X597098Y-90382D01*
X597117Y-90422D01*
X597135Y-90462D01*
X597157Y-90510D01*
X597175Y-90561D01*
X597193Y-90615D01*
X597211Y-90674D01*
X597226Y-90736D01*
X597233Y-90801D01*
X597240Y-90870D01*
X597244Y-90943D01*
Y-90983D01*
X597240Y-91012D01*
Y-91045D01*
X597237Y-91085D01*
X597230Y-91129D01*
X597222Y-91180D01*
X597204Y-91285D01*
X597175Y-91394D01*
X597135Y-91504D01*
X597109Y-91554D01*
X597080Y-91606D01*
X597077Y-91609D01*
X597073Y-91616D01*
X597062Y-91631D01*
X597048Y-91646D01*
X597033Y-91667D01*
X597011Y-91693D01*
X596986Y-91722D01*
X596957Y-91751D01*
X596924Y-91780D01*
X596891Y-91813D01*
X596807Y-91878D01*
X596709Y-91940D01*
X596600Y-91995D01*
X596596D01*
X596585Y-92002D01*
X596567Y-92006D01*
X596545Y-92017D01*
X596516Y-92024D01*
X596480Y-92035D01*
X596440Y-92050D01*
X596396Y-92061D01*
X596349Y-92071D01*
X596294Y-92086D01*
X596181Y-92104D01*
X596054Y-92119D01*
X595923Y-92126D01*
X595919D01*
X595905D01*
X595883D01*
X595857Y-92122D01*
X595821D01*
X595785Y-92119D01*
X595737Y-92115D01*
X595690Y-92108D01*
X595584Y-92090D01*
X595468Y-92064D01*
X595351Y-92028D01*
X595238Y-91977D01*
X595235Y-91973D01*
X595224Y-91970D01*
X595209Y-91962D01*
X595191Y-91948D01*
X595166Y-91933D01*
X595137Y-91915D01*
X595071Y-91868D01*
X594998Y-91806D01*
X594925Y-91733D01*
X594853Y-91649D01*
X594791Y-91551D01*
X594787Y-91547D01*
X594783Y-91536D01*
X594776Y-91522D01*
X594765Y-91504D01*
X594754Y-91474D01*
X594743Y-91445D01*
X594729Y-91409D01*
X594714Y-91369D01*
X594700Y-91325D01*
X594685Y-91278D01*
X594663Y-91176D01*
X594645Y-91059D01*
X594638Y-90939D01*
Y-90903D01*
X594641Y-90877D01*
X594645Y-90845D01*
X594649Y-90805D01*
X594652Y-90765D01*
X594663Y-90717D01*
X594685Y-90619D01*
X594718Y-90510D01*
X594740Y-90455D01*
X594765Y-90404D01*
X594798Y-90353D01*
X594831Y-90302D01*
X594834Y-90299D01*
X594838Y-90292D01*
X594849Y-90277D01*
X594867Y-90259D01*
X594885Y-90241D01*
X594911Y-90215D01*
X594940Y-90189D01*
X594969Y-90160D01*
X595006Y-90131D01*
X595049Y-90102D01*
X595093Y-90069D01*
X595140Y-90040D01*
X595195Y-90015D01*
X595249Y-89986D01*
X595308Y-89964D01*
X595373Y-89942D01*
X595450Y-90270D01*
X595446D01*
X595439Y-90273D01*
X595424Y-90281D01*
X595406Y-90288D01*
X595384Y-90295D01*
X595355Y-90306D01*
X595297Y-90335D01*
X595231Y-90372D01*
X595166Y-90415D01*
X595104Y-90470D01*
X595049Y-90528D01*
X595042Y-90535D01*
X595027Y-90557D01*
X595009Y-90594D01*
X594984Y-90641D01*
X594962Y-90703D01*
X594940Y-90772D01*
X594925Y-90856D01*
X594922Y-90947D01*
Y-90976D01*
X594925Y-90994D01*
Y-91019D01*
X594929Y-91049D01*
X594940Y-91118D01*
X594955Y-91194D01*
X594980Y-91274D01*
X595016Y-91358D01*
X595064Y-91434D01*
Y-91438D01*
X595071Y-91442D01*
X595089Y-91467D01*
X595118Y-91500D01*
X595162Y-91540D01*
X595217Y-91587D01*
X595279Y-91631D01*
X595355Y-91671D01*
X595439Y-91707D01*
X595442D01*
X595450Y-91711D01*
X595461Y-91715D01*
X595479Y-91718D01*
X595501Y-91726D01*
X595526Y-91733D01*
X595588Y-91744D01*
X595661Y-91758D01*
X595741Y-91773D01*
X595828Y-91780D01*
X595923Y-91784D01*
X595926D01*
X595937D01*
X595956D01*
X595977D01*
X596003Y-91780D01*
X596036D01*
X596072Y-91777D01*
X596112Y-91773D01*
X596199Y-91762D01*
X596294Y-91744D01*
X596389Y-91722D01*
X596483Y-91693D01*
X596487D01*
X596494Y-91689D01*
X596505Y-91682D01*
X596523Y-91675D01*
X596567Y-91653D01*
X596618Y-91620D01*
X596676Y-91580D01*
X596738Y-91529D01*
X596793Y-91471D01*
X596844Y-91402D01*
Y-91398D01*
X596847Y-91391D01*
X596855Y-91380D01*
X596862Y-91365D01*
X596869Y-91347D01*
X596880Y-91325D01*
X596902Y-91274D01*
X596924Y-91209D01*
X596942Y-91136D01*
X596957Y-91056D01*
X596960Y-90972D01*
Y-90947D01*
X596957Y-90925D01*
Y-90899D01*
X596953Y-90874D01*
X596938Y-90808D01*
X596920Y-90732D01*
X596891Y-90655D01*
X596851Y-90575D01*
X596829Y-90535D01*
X596800Y-90499D01*
X596796Y-90495D01*
X596793Y-90492D01*
X596782Y-90481D01*
X596771Y-90466D01*
X596753Y-90452D01*
X596731Y-90433D01*
X596709Y-90412D01*
X596680Y-90393D01*
X596647Y-90372D01*
X596611Y-90346D01*
X596574Y-90324D01*
X596531Y-90302D01*
X596483Y-90284D01*
X596432Y-90266D01*
X596378Y-90248D01*
X596320Y-90233D01*
X596403Y-89898D01*
X596407D01*
X596421Y-89902D01*
D02*
G37*
G36*
X424674Y-122201D02*
X424699D01*
X424769Y-122208D01*
X424845Y-122219D01*
X424925Y-122237D01*
X425012Y-122259D01*
X425093Y-122288D01*
X425096D01*
X425104Y-122292D01*
X425114Y-122299D01*
X425129Y-122306D01*
X425165Y-122324D01*
X425213Y-122357D01*
X425267Y-122394D01*
X425322Y-122441D01*
X425373Y-122495D01*
X425420Y-122557D01*
Y-122561D01*
X425424Y-122565D01*
X425431Y-122575D01*
X425438Y-122586D01*
X425457Y-122623D01*
X425478Y-122670D01*
X425504Y-122728D01*
X425522Y-122798D01*
X425540Y-122870D01*
X425548Y-122950D01*
X425227Y-122976D01*
Y-122972D01*
Y-122965D01*
X425224Y-122954D01*
X425220Y-122936D01*
X425209Y-122896D01*
X425195Y-122841D01*
X425173Y-122783D01*
X425140Y-122725D01*
X425100Y-122670D01*
X425049Y-122619D01*
X425042Y-122616D01*
X425023Y-122601D01*
X424987Y-122579D01*
X424940Y-122557D01*
X424878Y-122536D01*
X424805Y-122514D01*
X424714Y-122499D01*
X424612Y-122495D01*
X424561D01*
X424539Y-122499D01*
X424510Y-122503D01*
X424445Y-122510D01*
X424372Y-122525D01*
X424299Y-122543D01*
X424230Y-122572D01*
X424201Y-122590D01*
X424172Y-122608D01*
X424164Y-122612D01*
X424150Y-122626D01*
X424128Y-122652D01*
X424106Y-122681D01*
X424081Y-122721D01*
X424059Y-122765D01*
X424044Y-122816D01*
X424037Y-122874D01*
Y-122881D01*
Y-122896D01*
X424041Y-122921D01*
X424048Y-122950D01*
X424059Y-122987D01*
X424077Y-123023D01*
X424099Y-123060D01*
X424132Y-123096D01*
X424135Y-123100D01*
X424153Y-123111D01*
X424168Y-123122D01*
X424183Y-123129D01*
X424204Y-123140D01*
X424230Y-123154D01*
X424263Y-123165D01*
X424299Y-123180D01*
X424339Y-123194D01*
X424386Y-123213D01*
X424437Y-123227D01*
X424496Y-123245D01*
X424561Y-123260D01*
X424634Y-123278D01*
X424638D01*
X424652Y-123282D01*
X424674Y-123285D01*
X424699Y-123293D01*
X424732Y-123300D01*
X424772Y-123311D01*
X424812Y-123322D01*
X424856Y-123333D01*
X424951Y-123358D01*
X425042Y-123384D01*
X425085Y-123398D01*
X425125Y-123413D01*
X425162Y-123424D01*
X425191Y-123438D01*
X425195D01*
X425202Y-123442D01*
X425213Y-123449D01*
X425227Y-123456D01*
X425267Y-123478D01*
X425315Y-123507D01*
X425369Y-123547D01*
X425424Y-123591D01*
X425475Y-123642D01*
X425518Y-123697D01*
X425522Y-123704D01*
X425537Y-123722D01*
X425551Y-123755D01*
X425573Y-123799D01*
X425591Y-123849D01*
X425609Y-123911D01*
X425620Y-123981D01*
X425624Y-124053D01*
Y-124057D01*
Y-124061D01*
Y-124072D01*
Y-124086D01*
X425617Y-124126D01*
X425609Y-124177D01*
X425595Y-124235D01*
X425577Y-124297D01*
X425548Y-124363D01*
X425507Y-124432D01*
Y-124436D01*
X425504Y-124439D01*
X425486Y-124461D01*
X425460Y-124494D01*
X425424Y-124530D01*
X425377Y-124574D01*
X425318Y-124621D01*
X425253Y-124665D01*
X425176Y-124705D01*
X425173D01*
X425165Y-124709D01*
X425154Y-124712D01*
X425140Y-124720D01*
X425118Y-124727D01*
X425093Y-124738D01*
X425034Y-124752D01*
X424965Y-124770D01*
X424881Y-124789D01*
X424790Y-124800D01*
X424692Y-124803D01*
X424634D01*
X424605Y-124800D01*
X424572D01*
X424536Y-124796D01*
X424492Y-124792D01*
X424401Y-124778D01*
X424306Y-124763D01*
X424212Y-124738D01*
X424121Y-124705D01*
X424117D01*
X424110Y-124701D01*
X424099Y-124694D01*
X424084Y-124687D01*
X424041Y-124665D01*
X423990Y-124632D01*
X423931Y-124588D01*
X423870Y-124538D01*
X423811Y-124476D01*
X423757Y-124406D01*
Y-124403D01*
X423749Y-124396D01*
X423746Y-124385D01*
X423735Y-124370D01*
X423728Y-124352D01*
X423717Y-124330D01*
X423691Y-124275D01*
X423666Y-124206D01*
X423644Y-124130D01*
X423629Y-124042D01*
X423622Y-123951D01*
X423935Y-123922D01*
Y-123926D01*
Y-123930D01*
X423939Y-123941D01*
Y-123955D01*
X423946Y-123988D01*
X423957Y-124035D01*
X423971Y-124083D01*
X423986Y-124137D01*
X424012Y-124188D01*
X424037Y-124235D01*
X424041Y-124239D01*
X424052Y-124254D01*
X424070Y-124279D01*
X424099Y-124304D01*
X424135Y-124337D01*
X424175Y-124370D01*
X424230Y-124403D01*
X424288Y-124432D01*
X424292D01*
X424295Y-124436D01*
X424306Y-124439D01*
X424317Y-124443D01*
X424354Y-124454D01*
X424401Y-124468D01*
X424459Y-124483D01*
X424525Y-124494D01*
X424598Y-124501D01*
X424678Y-124505D01*
X424710D01*
X424747Y-124501D01*
X424790Y-124497D01*
X424841Y-124490D01*
X424900Y-124483D01*
X424958Y-124468D01*
X425012Y-124450D01*
X425020Y-124446D01*
X425038Y-124439D01*
X425063Y-124425D01*
X425096Y-124410D01*
X425129Y-124385D01*
X425165Y-124359D01*
X425202Y-124330D01*
X425231Y-124294D01*
X425235Y-124290D01*
X425242Y-124275D01*
X425253Y-124257D01*
X425267Y-124228D01*
X425282Y-124199D01*
X425293Y-124163D01*
X425300Y-124123D01*
X425304Y-124079D01*
Y-124075D01*
Y-124057D01*
X425300Y-124035D01*
X425296Y-124006D01*
X425285Y-123977D01*
X425275Y-123941D01*
X425256Y-123904D01*
X425231Y-123871D01*
X425227Y-123868D01*
X425216Y-123857D01*
X425202Y-123842D01*
X425176Y-123820D01*
X425147Y-123799D01*
X425107Y-123773D01*
X425060Y-123748D01*
X425005Y-123726D01*
X425002Y-123722D01*
X424983Y-123719D01*
X424954Y-123708D01*
X424936Y-123704D01*
X424911Y-123697D01*
X424885Y-123686D01*
X424852Y-123678D01*
X424816Y-123668D01*
X424772Y-123657D01*
X424729Y-123646D01*
X424678Y-123631D01*
X424619Y-123617D01*
X424557Y-123602D01*
X424554D01*
X424543Y-123598D01*
X424525Y-123595D01*
X424503Y-123587D01*
X424474Y-123580D01*
X424441Y-123573D01*
X424368Y-123551D01*
X424288Y-123526D01*
X424204Y-123500D01*
X424132Y-123475D01*
X424099Y-123460D01*
X424070Y-123445D01*
X424066D01*
X424062Y-123442D01*
X424041Y-123427D01*
X424008Y-123409D01*
X423971Y-123380D01*
X423928Y-123347D01*
X423884Y-123307D01*
X423840Y-123260D01*
X423804Y-123209D01*
X423800Y-123202D01*
X423789Y-123183D01*
X423775Y-123154D01*
X423760Y-123118D01*
X423746Y-123071D01*
X423731Y-123016D01*
X423720Y-122958D01*
X423717Y-122896D01*
Y-122892D01*
Y-122889D01*
Y-122878D01*
Y-122863D01*
X423724Y-122827D01*
X423731Y-122779D01*
X423742Y-122725D01*
X423760Y-122663D01*
X423786Y-122601D01*
X423822Y-122539D01*
Y-122536D01*
X423826Y-122532D01*
X423844Y-122510D01*
X423870Y-122481D01*
X423902Y-122444D01*
X423946Y-122404D01*
X424001Y-122361D01*
X424066Y-122321D01*
X424139Y-122284D01*
X424143D01*
X424150Y-122281D01*
X424161Y-122277D01*
X424175Y-122270D01*
X424193Y-122263D01*
X424219Y-122255D01*
X424274Y-122241D01*
X424343Y-122226D01*
X424423Y-122212D01*
X424507Y-122201D01*
X424601Y-122197D01*
X424649D01*
X424674Y-122201D01*
D02*
G37*
G36*
X428401Y-124759D02*
X428074D01*
X427546Y-122841D01*
Y-122838D01*
X427542Y-122830D01*
X427539Y-122819D01*
X427535Y-122801D01*
X427524Y-122761D01*
X427513Y-122714D01*
X427499Y-122663D01*
X427484Y-122616D01*
X427473Y-122575D01*
X427469Y-122557D01*
X427466Y-122546D01*
Y-122550D01*
X427462Y-122554D01*
X427459Y-122575D01*
X427451Y-122608D01*
X427440Y-122648D01*
X427429Y-122692D01*
X427415Y-122743D01*
X427404Y-122794D01*
X427389Y-122841D01*
X426858Y-124759D01*
X426509D01*
X425850Y-122241D01*
X426195D01*
X426570Y-123893D01*
Y-123897D01*
X426574Y-123904D01*
X426578Y-123919D01*
X426581Y-123937D01*
X426585Y-123962D01*
X426592Y-123988D01*
X426600Y-124021D01*
X426607Y-124057D01*
X426625Y-124133D01*
X426643Y-124221D01*
X426661Y-124315D01*
X426680Y-124410D01*
Y-124406D01*
X426683Y-124392D01*
X426690Y-124374D01*
X426694Y-124345D01*
X426701Y-124315D01*
X426712Y-124279D01*
X426731Y-124199D01*
X426752Y-124119D01*
X426760Y-124079D01*
X426771Y-124042D01*
X426778Y-124010D01*
X426785Y-123981D01*
X426792Y-123959D01*
X426796Y-123944D01*
X427273Y-122241D01*
X427677D01*
X428034Y-123518D01*
Y-123522D01*
X428041Y-123540D01*
X428048Y-123566D01*
X428055Y-123598D01*
X428066Y-123642D01*
X428081Y-123689D01*
X428096Y-123744D01*
X428110Y-123806D01*
X428128Y-123875D01*
X428143Y-123944D01*
X428176Y-124093D01*
X428208Y-124250D01*
X428234Y-124410D01*
Y-124406D01*
X428237Y-124399D01*
Y-124385D01*
X428245Y-124366D01*
X428248Y-124345D01*
X428256Y-124319D01*
X428259Y-124286D01*
X428270Y-124250D01*
X428289Y-124170D01*
X428310Y-124075D01*
X428332Y-123973D01*
X428361Y-123860D01*
X428754Y-122241D01*
X429093D01*
X428401Y-124759D01*
D02*
G37*
G36*
X430443D02*
X430134D01*
Y-122790D01*
X430130Y-122794D01*
X430112Y-122809D01*
X430090Y-122830D01*
X430054Y-122856D01*
X430014Y-122889D01*
X429963Y-122925D01*
X429905Y-122965D01*
X429839Y-123005D01*
X429836D01*
X429832Y-123009D01*
X429810Y-123023D01*
X429774Y-123041D01*
X429730Y-123063D01*
X429679Y-123089D01*
X429624Y-123114D01*
X429570Y-123140D01*
X429515Y-123162D01*
Y-122863D01*
X429519D01*
X429526Y-122856D01*
X429541Y-122852D01*
X429559Y-122841D01*
X429581Y-122830D01*
X429606Y-122816D01*
X429668Y-122779D01*
X429741Y-122739D01*
X429814Y-122688D01*
X429890Y-122630D01*
X429966Y-122568D01*
X429970Y-122565D01*
X429974Y-122561D01*
X429985Y-122550D01*
X429999Y-122539D01*
X430032Y-122503D01*
X430076Y-122459D01*
X430119Y-122408D01*
X430167Y-122350D01*
X430207Y-122292D01*
X430243Y-122230D01*
X430443D01*
Y-124759D01*
D02*
G37*
G36*
X411664Y-130889D02*
X411660Y-130955D01*
X411657Y-131028D01*
X411649Y-131101D01*
X411638Y-131173D01*
X411628Y-131235D01*
Y-131239D01*
X411624Y-131246D01*
Y-131257D01*
X411617Y-131272D01*
X411606Y-131312D01*
X411587Y-131363D01*
X411562Y-131421D01*
X411529Y-131483D01*
X411493Y-131545D01*
X411446Y-131603D01*
X411442Y-131607D01*
X411438Y-131610D01*
X411427Y-131621D01*
X411416Y-131636D01*
X411380Y-131672D01*
X411329Y-131716D01*
X411267Y-131763D01*
X411194Y-131814D01*
X411111Y-131861D01*
X411016Y-131901D01*
X411012D01*
X411005Y-131905D01*
X410991Y-131912D01*
X410969Y-131916D01*
X410943Y-131927D01*
X410914Y-131934D01*
X410881Y-131941D01*
X410841Y-131952D01*
X410801Y-131963D01*
X410754Y-131971D01*
X410652Y-131989D01*
X410539Y-132000D01*
X410415Y-132003D01*
X410412D01*
X410404D01*
X410386D01*
X410368D01*
X410343Y-132000D01*
X410314D01*
X410244Y-131996D01*
X410164Y-131985D01*
X410081Y-131974D01*
X409993Y-131956D01*
X409906Y-131934D01*
X409902D01*
X409895Y-131930D01*
X409884Y-131927D01*
X409869Y-131923D01*
X409829Y-131909D01*
X409778Y-131887D01*
X409720Y-131865D01*
X409662Y-131836D01*
X409600Y-131799D01*
X409542Y-131763D01*
X409535Y-131760D01*
X409516Y-131745D01*
X409491Y-131723D01*
X409458Y-131694D01*
X409422Y-131661D01*
X409385Y-131621D01*
X409345Y-131581D01*
X409312Y-131534D01*
X409309Y-131527D01*
X409298Y-131512D01*
X409283Y-131486D01*
X409265Y-131450D01*
X409243Y-131406D01*
X409225Y-131355D01*
X409203Y-131297D01*
X409185Y-131232D01*
Y-131224D01*
X409181Y-131213D01*
X409178Y-131202D01*
X409174Y-131166D01*
X409167Y-131115D01*
X409160Y-131057D01*
X409152Y-130988D01*
X409149Y-130911D01*
X409145Y-130828D01*
Y-129921D01*
X411664D01*
Y-130889D01*
D02*
G37*
G36*
X409214Y-132295D02*
X409247Y-132298D01*
X409283Y-132306D01*
X409320Y-132313D01*
X409360Y-132327D01*
X409364D01*
X409367Y-132331D01*
X409389Y-132338D01*
X409422Y-132353D01*
X409465Y-132375D01*
X409516Y-132404D01*
X409575Y-132440D01*
X409633Y-132480D01*
X409695Y-132531D01*
X409698D01*
X409702Y-132538D01*
X409724Y-132557D01*
X409757Y-132589D01*
X409804Y-132637D01*
X409859Y-132691D01*
X409924Y-132761D01*
X409997Y-132844D01*
X410073Y-132935D01*
X410077Y-132939D01*
X410088Y-132953D01*
X410106Y-132975D01*
X410128Y-133001D01*
X410157Y-133034D01*
X410190Y-133073D01*
X410226Y-133114D01*
X410266Y-133161D01*
X410354Y-133252D01*
X410441Y-133343D01*
X410485Y-133387D01*
X410528Y-133427D01*
X410568Y-133463D01*
X410608Y-133492D01*
X410612D01*
X410616Y-133499D01*
X410627Y-133507D01*
X410641Y-133514D01*
X410681Y-133539D01*
X410729Y-133569D01*
X410787Y-133594D01*
X410849Y-133619D01*
X410918Y-133634D01*
X410983Y-133641D01*
X410987D01*
X410991D01*
X411012Y-133638D01*
X411049Y-133634D01*
X411089Y-133623D01*
X411140Y-133609D01*
X411191Y-133583D01*
X411242Y-133550D01*
X411293Y-133507D01*
X411300Y-133499D01*
X411314Y-133481D01*
X411333Y-133456D01*
X411358Y-133416D01*
X411380Y-133365D01*
X411402Y-133307D01*
X411416Y-133237D01*
X411420Y-133161D01*
Y-133139D01*
X411416Y-133124D01*
X411413Y-133081D01*
X411402Y-133030D01*
X411387Y-132975D01*
X411362Y-132913D01*
X411329Y-132855D01*
X411285Y-132800D01*
X411278Y-132793D01*
X411260Y-132779D01*
X411231Y-132757D01*
X411187Y-132735D01*
X411136Y-132710D01*
X411071Y-132688D01*
X410998Y-132673D01*
X410914Y-132666D01*
X410947Y-132349D01*
X410951D01*
X410961Y-132353D01*
X410980D01*
X411005Y-132356D01*
X411034Y-132364D01*
X411067Y-132371D01*
X411107Y-132382D01*
X411147Y-132393D01*
X411235Y-132422D01*
X411322Y-132466D01*
X411366Y-132491D01*
X411409Y-132524D01*
X411449Y-132557D01*
X411486Y-132593D01*
X411489Y-132597D01*
X411493Y-132604D01*
X411504Y-132615D01*
X411515Y-132633D01*
X411529Y-132655D01*
X411544Y-132680D01*
X411562Y-132710D01*
X411580Y-132746D01*
X411598Y-132786D01*
X411617Y-132830D01*
X411631Y-132877D01*
X411646Y-132928D01*
X411657Y-132983D01*
X411668Y-133041D01*
X411671Y-133103D01*
X411675Y-133168D01*
Y-133204D01*
X411671Y-133230D01*
X411668Y-133259D01*
X411664Y-133296D01*
X411657Y-133336D01*
X411649Y-133376D01*
X411624Y-133470D01*
X411587Y-133565D01*
X411566Y-133612D01*
X411540Y-133660D01*
X411507Y-133703D01*
X411471Y-133743D01*
X411467Y-133747D01*
X411464Y-133754D01*
X411449Y-133762D01*
X411435Y-133776D01*
X411416Y-133794D01*
X411391Y-133812D01*
X411366Y-133831D01*
X411333Y-133853D01*
X411264Y-133889D01*
X411176Y-133925D01*
X411132Y-133940D01*
X411082Y-133947D01*
X411031Y-133954D01*
X410976Y-133958D01*
X410969D01*
X410951D01*
X410921Y-133954D01*
X410881Y-133951D01*
X410838Y-133943D01*
X410787Y-133929D01*
X410732Y-133914D01*
X410677Y-133893D01*
X410670Y-133889D01*
X410652Y-133882D01*
X410623Y-133867D01*
X410583Y-133845D01*
X410539Y-133816D01*
X410485Y-133780D01*
X410430Y-133736D01*
X410368Y-133685D01*
X410361Y-133678D01*
X410339Y-133660D01*
X410321Y-133641D01*
X410303Y-133623D01*
X410281Y-133601D01*
X410252Y-133572D01*
X410222Y-133543D01*
X410190Y-133507D01*
X410153Y-133470D01*
X410113Y-133427D01*
X410073Y-133379D01*
X410026Y-133328D01*
X409979Y-133270D01*
X409928Y-133212D01*
X409924Y-133208D01*
X409917Y-133201D01*
X409906Y-133186D01*
X409891Y-133168D01*
X409869Y-133146D01*
X409848Y-133121D01*
X409800Y-133063D01*
X409746Y-133001D01*
X409691Y-132942D01*
X409644Y-132891D01*
X409626Y-132870D01*
X409607Y-132852D01*
X409604Y-132848D01*
X409593Y-132837D01*
X409578Y-132822D01*
X409556Y-132804D01*
X409531Y-132786D01*
X409506Y-132764D01*
X409444Y-132720D01*
Y-133962D01*
X409145D01*
Y-132291D01*
X409149D01*
X409163D01*
X409185D01*
X409214Y-132295D01*
D02*
G37*
G36*
X409829Y-134617D02*
X409826D01*
X409819D01*
X409808Y-134620D01*
X409789Y-134624D01*
X409749Y-134635D01*
X409695Y-134650D01*
X409640Y-134671D01*
X409578Y-134701D01*
X409524Y-134737D01*
X409473Y-134781D01*
X409469Y-134788D01*
X409454Y-134802D01*
X409436Y-134832D01*
X409414Y-134872D01*
X409393Y-134915D01*
X409374Y-134970D01*
X409360Y-135032D01*
X409356Y-135101D01*
Y-135123D01*
X409360Y-135137D01*
X409364Y-135181D01*
X409378Y-135232D01*
X409396Y-135294D01*
X409425Y-135356D01*
X409469Y-135421D01*
X409494Y-135450D01*
X409524Y-135479D01*
X409527Y-135483D01*
X409531Y-135487D01*
X409542Y-135494D01*
X409553Y-135505D01*
X409593Y-135530D01*
X409644Y-135560D01*
X409706Y-135585D01*
X409782Y-135611D01*
X409873Y-135629D01*
X409920Y-135636D01*
X409971D01*
X409975D01*
X409982D01*
X409997D01*
X410015Y-135632D01*
X410037D01*
X410062Y-135629D01*
X410121Y-135618D01*
X410190Y-135600D01*
X410259Y-135574D01*
X410324Y-135538D01*
X410386Y-135487D01*
X410390D01*
X410394Y-135479D01*
X410412Y-135461D01*
X410437Y-135429D01*
X410466Y-135385D01*
X410492Y-135327D01*
X410517Y-135261D01*
X410536Y-135185D01*
X410543Y-135141D01*
Y-135072D01*
X410539Y-135043D01*
X410536Y-135006D01*
X410525Y-134963D01*
X410514Y-134919D01*
X410496Y-134872D01*
X410474Y-134824D01*
X410470Y-134821D01*
X410463Y-134806D01*
X410445Y-134784D01*
X410426Y-134755D01*
X410401Y-134726D01*
X410368Y-134697D01*
X410335Y-134664D01*
X410295Y-134639D01*
X410335Y-134347D01*
X411631Y-134591D01*
Y-135844D01*
X411336D01*
Y-134835D01*
X410656Y-134701D01*
X410659Y-134704D01*
X410663Y-134712D01*
X410670Y-134722D01*
X410681Y-134741D01*
X410692Y-134763D01*
X410707Y-134788D01*
X410736Y-134846D01*
X410765Y-134919D01*
X410790Y-134999D01*
X410809Y-135086D01*
X410816Y-135130D01*
Y-135210D01*
X410812Y-135232D01*
X410809Y-135261D01*
X410805Y-135294D01*
X410798Y-135330D01*
X410787Y-135370D01*
X410761Y-135458D01*
X410743Y-135505D01*
X410718Y-135552D01*
X410692Y-135600D01*
X410663Y-135647D01*
X410627Y-135691D01*
X410587Y-135734D01*
X410583Y-135738D01*
X410576Y-135745D01*
X410565Y-135756D01*
X410546Y-135771D01*
X410521Y-135789D01*
X410496Y-135807D01*
X410463Y-135829D01*
X410426Y-135851D01*
X410386Y-135869D01*
X410343Y-135891D01*
X410292Y-135909D01*
X410241Y-135927D01*
X410186Y-135942D01*
X410124Y-135953D01*
X410062Y-135960D01*
X409997Y-135964D01*
X409993D01*
X409982D01*
X409964D01*
X409939Y-135960D01*
X409909Y-135956D01*
X409877Y-135953D01*
X409837Y-135945D01*
X409797Y-135938D01*
X409702Y-135916D01*
X409604Y-135880D01*
X409553Y-135858D01*
X409506Y-135829D01*
X409454Y-135800D01*
X409407Y-135764D01*
X409404Y-135760D01*
X409393Y-135752D01*
X409378Y-135738D01*
X409360Y-135720D01*
X409338Y-135694D01*
X409309Y-135665D01*
X409283Y-135629D01*
X409254Y-135589D01*
X409225Y-135545D01*
X409200Y-135494D01*
X409174Y-135440D01*
X409149Y-135381D01*
X409130Y-135319D01*
X409116Y-135250D01*
X409105Y-135177D01*
X409101Y-135101D01*
Y-135068D01*
X409105Y-135043D01*
X409109Y-135014D01*
X409112Y-134981D01*
X409116Y-134941D01*
X409127Y-134901D01*
X409149Y-134810D01*
X409181Y-134719D01*
X409203Y-134671D01*
X409229Y-134624D01*
X409258Y-134581D01*
X409291Y-134537D01*
X409294Y-134533D01*
X409298Y-134526D01*
X409312Y-134519D01*
X409327Y-134504D01*
X409345Y-134486D01*
X409367Y-134468D01*
X409396Y-134446D01*
X409429Y-134428D01*
X409462Y-134406D01*
X409502Y-134384D01*
X409589Y-134344D01*
X409691Y-134311D01*
X409746Y-134300D01*
X409804Y-134293D01*
X409829Y-134617D01*
D02*
G37*
G36*
X438392Y-130496D02*
X438388Y-130561D01*
X438385Y-130634D01*
X438377Y-130707D01*
X438366Y-130780D01*
X438355Y-130842D01*
Y-130845D01*
X438352Y-130852D01*
Y-130863D01*
X438345Y-130878D01*
X438334Y-130918D01*
X438315Y-130969D01*
X438290Y-131027D01*
X438257Y-131089D01*
X438221Y-131151D01*
X438173Y-131209D01*
X438170Y-131213D01*
X438166Y-131217D01*
X438155Y-131227D01*
X438144Y-131242D01*
X438108Y-131278D01*
X438057Y-131322D01*
X437995Y-131369D01*
X437922Y-131420D01*
X437839Y-131468D01*
X437744Y-131508D01*
X437740D01*
X437733Y-131511D01*
X437718Y-131519D01*
X437697Y-131522D01*
X437671Y-131533D01*
X437642Y-131541D01*
X437609Y-131548D01*
X437569Y-131559D01*
X437529Y-131570D01*
X437482Y-131577D01*
X437380Y-131595D01*
X437267Y-131606D01*
X437143Y-131610D01*
X437140D01*
X437133D01*
X437114D01*
X437096D01*
X437071Y-131606D01*
X437042D01*
X436972Y-131602D01*
X436892Y-131591D01*
X436808Y-131580D01*
X436721Y-131562D01*
X436634Y-131541D01*
X436630D01*
X436623Y-131537D01*
X436612Y-131533D01*
X436597Y-131530D01*
X436557Y-131515D01*
X436506Y-131493D01*
X436448Y-131471D01*
X436390Y-131442D01*
X436328Y-131406D01*
X436270Y-131369D01*
X436263Y-131366D01*
X436244Y-131351D01*
X436219Y-131329D01*
X436186Y-131300D01*
X436150Y-131267D01*
X436113Y-131227D01*
X436073Y-131187D01*
X436040Y-131140D01*
X436037Y-131133D01*
X436026Y-131118D01*
X436011Y-131093D01*
X435993Y-131056D01*
X435971Y-131013D01*
X435953Y-130962D01*
X435931Y-130903D01*
X435913Y-130838D01*
Y-130831D01*
X435910Y-130820D01*
X435906Y-130809D01*
X435902Y-130772D01*
X435895Y-130721D01*
X435888Y-130663D01*
X435880Y-130594D01*
X435877Y-130518D01*
X435873Y-130434D01*
Y-129528D01*
X438392D01*
Y-130496D01*
D02*
G37*
G36*
X435942Y-131901D02*
X435975Y-131904D01*
X436011Y-131912D01*
X436048Y-131919D01*
X436088Y-131934D01*
X436091D01*
X436095Y-131937D01*
X436117Y-131945D01*
X436150Y-131959D01*
X436193Y-131981D01*
X436244Y-132010D01*
X436303Y-132046D01*
X436361Y-132087D01*
X436423Y-132137D01*
X436426D01*
X436430Y-132145D01*
X436452Y-132163D01*
X436485Y-132196D01*
X436532Y-132243D01*
X436587Y-132298D01*
X436652Y-132367D01*
X436725Y-132450D01*
X436801Y-132542D01*
X436805Y-132545D01*
X436816Y-132560D01*
X436834Y-132581D01*
X436856Y-132607D01*
X436885Y-132640D01*
X436918Y-132680D01*
X436954Y-132720D01*
X436994Y-132767D01*
X437081Y-132858D01*
X437169Y-132949D01*
X437213Y-132993D01*
X437256Y-133033D01*
X437296Y-133069D01*
X437336Y-133098D01*
X437340D01*
X437344Y-133106D01*
X437355Y-133113D01*
X437369Y-133120D01*
X437409Y-133146D01*
X437457Y-133175D01*
X437515Y-133200D01*
X437577Y-133226D01*
X437646Y-133240D01*
X437711Y-133248D01*
X437715D01*
X437718D01*
X437740Y-133244D01*
X437777Y-133240D01*
X437817Y-133229D01*
X437868Y-133215D01*
X437919Y-133189D01*
X437970Y-133157D01*
X438021Y-133113D01*
X438028Y-133106D01*
X438042Y-133088D01*
X438061Y-133062D01*
X438086Y-133022D01*
X438108Y-132971D01*
X438130Y-132913D01*
X438144Y-132844D01*
X438148Y-132767D01*
Y-132745D01*
X438144Y-132731D01*
X438141Y-132687D01*
X438130Y-132636D01*
X438115Y-132581D01*
X438090Y-132520D01*
X438057Y-132461D01*
X438013Y-132407D01*
X438006Y-132399D01*
X437988Y-132385D01*
X437959Y-132363D01*
X437915Y-132341D01*
X437864Y-132316D01*
X437799Y-132294D01*
X437726Y-132279D01*
X437642Y-132272D01*
X437675Y-131955D01*
X437678D01*
X437689Y-131959D01*
X437708D01*
X437733Y-131963D01*
X437762Y-131970D01*
X437795Y-131977D01*
X437835Y-131988D01*
X437875Y-131999D01*
X437962Y-132028D01*
X438050Y-132072D01*
X438094Y-132097D01*
X438137Y-132130D01*
X438177Y-132163D01*
X438214Y-132199D01*
X438217Y-132203D01*
X438221Y-132210D01*
X438232Y-132221D01*
X438243Y-132239D01*
X438257Y-132261D01*
X438272Y-132287D01*
X438290Y-132316D01*
X438308Y-132352D01*
X438326Y-132392D01*
X438345Y-132436D01*
X438359Y-132483D01*
X438374Y-132534D01*
X438385Y-132589D01*
X438396Y-132647D01*
X438399Y-132709D01*
X438403Y-132774D01*
Y-132811D01*
X438399Y-132836D01*
X438396Y-132865D01*
X438392Y-132902D01*
X438385Y-132942D01*
X438377Y-132982D01*
X438352Y-133077D01*
X438315Y-133171D01*
X438294Y-133219D01*
X438268Y-133266D01*
X438235Y-133309D01*
X438199Y-133350D01*
X438195Y-133353D01*
X438192Y-133361D01*
X438177Y-133368D01*
X438163Y-133382D01*
X438144Y-133400D01*
X438119Y-133419D01*
X438094Y-133437D01*
X438061Y-133459D01*
X437992Y-133495D01*
X437904Y-133532D01*
X437860Y-133546D01*
X437810Y-133553D01*
X437759Y-133561D01*
X437704Y-133564D01*
X437697D01*
X437678D01*
X437649Y-133561D01*
X437609Y-133557D01*
X437566Y-133550D01*
X437515Y-133535D01*
X437460Y-133521D01*
X437405Y-133499D01*
X437398Y-133495D01*
X437380Y-133488D01*
X437351Y-133473D01*
X437311Y-133451D01*
X437267Y-133422D01*
X437213Y-133386D01*
X437158Y-133342D01*
X437096Y-133291D01*
X437089Y-133284D01*
X437067Y-133266D01*
X437049Y-133248D01*
X437031Y-133229D01*
X437009Y-133208D01*
X436980Y-133178D01*
X436950Y-133149D01*
X436918Y-133113D01*
X436881Y-133077D01*
X436841Y-133033D01*
X436801Y-132986D01*
X436754Y-132935D01*
X436707Y-132876D01*
X436656Y-132818D01*
X436652Y-132815D01*
X436645Y-132807D01*
X436634Y-132793D01*
X436619Y-132774D01*
X436597Y-132753D01*
X436576Y-132727D01*
X436528Y-132669D01*
X436474Y-132607D01*
X436419Y-132549D01*
X436372Y-132498D01*
X436353Y-132476D01*
X436335Y-132458D01*
X436332Y-132454D01*
X436321Y-132443D01*
X436306Y-132429D01*
X436284Y-132410D01*
X436259Y-132392D01*
X436233Y-132370D01*
X436171Y-132327D01*
Y-133568D01*
X435873D01*
Y-131897D01*
X435877D01*
X435891D01*
X435913D01*
X435942Y-131901D01*
D02*
G37*
G36*
X438392Y-134948D02*
Y-135199D01*
X436761D01*
Y-135541D01*
X436477D01*
Y-135199D01*
X435873D01*
Y-134889D01*
X436477D01*
Y-133794D01*
X436761D01*
X438392Y-134948D01*
D02*
G37*
G36*
X247694Y-115243D02*
X247723Y-115247D01*
X247756Y-115254D01*
X247792Y-115261D01*
X247832Y-115268D01*
X247919Y-115298D01*
X247967Y-115319D01*
X248010Y-115341D01*
X248058Y-115370D01*
X248105Y-115403D01*
X248152Y-115439D01*
X248196Y-115483D01*
X248200Y-115487D01*
X248207Y-115494D01*
X248218Y-115509D01*
X248232Y-115527D01*
X248251Y-115549D01*
X248269Y-115578D01*
X248291Y-115611D01*
X248309Y-115651D01*
X248331Y-115691D01*
X248352Y-115738D01*
X248371Y-115785D01*
X248389Y-115840D01*
X248403Y-115898D01*
X248414Y-115960D01*
X248422Y-116022D01*
X248425Y-116091D01*
Y-116124D01*
X248422Y-116146D01*
X248418Y-116175D01*
X248414Y-116208D01*
X248407Y-116244D01*
X248400Y-116284D01*
X248378Y-116371D01*
X248341Y-116462D01*
X248320Y-116510D01*
X248294Y-116553D01*
X248261Y-116597D01*
X248229Y-116641D01*
X248225Y-116644D01*
X248218Y-116652D01*
X248207Y-116663D01*
X248192Y-116674D01*
X248174Y-116692D01*
X248149Y-116710D01*
X248123Y-116732D01*
X248090Y-116754D01*
X248054Y-116775D01*
X248018Y-116797D01*
X247930Y-116837D01*
X247828Y-116870D01*
X247774Y-116881D01*
X247715Y-116888D01*
X247675Y-116579D01*
X247679D01*
X247686Y-116575D01*
X247701Y-116572D01*
X247719Y-116568D01*
X247741Y-116564D01*
X247766Y-116557D01*
X247821Y-116539D01*
X247886Y-116513D01*
X247948Y-116481D01*
X248007Y-116444D01*
X248058Y-116401D01*
X248061Y-116393D01*
X248076Y-116379D01*
X248094Y-116349D01*
X248112Y-116313D01*
X248134Y-116269D01*
X248152Y-116215D01*
X248167Y-116153D01*
X248170Y-116087D01*
Y-116066D01*
X248167Y-116051D01*
X248163Y-116011D01*
X248152Y-115960D01*
X248134Y-115902D01*
X248109Y-115840D01*
X248072Y-115778D01*
X248021Y-115720D01*
X248014Y-115712D01*
X247992Y-115694D01*
X247959Y-115673D01*
X247916Y-115643D01*
X247861Y-115614D01*
X247799Y-115592D01*
X247726Y-115574D01*
X247646Y-115567D01*
X247643D01*
X247635D01*
X247624D01*
X247610Y-115571D01*
X247570Y-115574D01*
X247522Y-115585D01*
X247464Y-115600D01*
X247406Y-115625D01*
X247348Y-115662D01*
X247293Y-115709D01*
X247286Y-115716D01*
X247271Y-115734D01*
X247250Y-115763D01*
X247224Y-115804D01*
X247199Y-115855D01*
X247177Y-115916D01*
X247162Y-115986D01*
X247155Y-116062D01*
Y-116095D01*
X247159Y-116120D01*
X247162Y-116153D01*
X247169Y-116189D01*
X247177Y-116233D01*
X247188Y-116280D01*
X246915Y-116244D01*
Y-116226D01*
X246918Y-116211D01*
Y-116164D01*
X246911Y-116124D01*
X246904Y-116077D01*
X246893Y-116022D01*
X246875Y-115960D01*
X246849Y-115902D01*
X246816Y-115840D01*
Y-115836D01*
X246813Y-115833D01*
X246798Y-115814D01*
X246773Y-115789D01*
X246740Y-115760D01*
X246693Y-115731D01*
X246638Y-115705D01*
X246576Y-115687D01*
X246540Y-115680D01*
X246500D01*
X246496D01*
X246492D01*
X246471D01*
X246441Y-115687D01*
X246401Y-115694D01*
X246358Y-115709D01*
X246310Y-115727D01*
X246263Y-115756D01*
X246219Y-115796D01*
X246216Y-115800D01*
X246201Y-115818D01*
X246183Y-115844D01*
X246161Y-115876D01*
X246143Y-115920D01*
X246125Y-115971D01*
X246110Y-116029D01*
X246107Y-116095D01*
Y-116124D01*
X246114Y-116157D01*
X246121Y-116200D01*
X246136Y-116248D01*
X246154Y-116295D01*
X246183Y-116346D01*
X246219Y-116393D01*
X246223Y-116397D01*
X246241Y-116411D01*
X246267Y-116433D01*
X246303Y-116459D01*
X246350Y-116484D01*
X246409Y-116510D01*
X246478Y-116532D01*
X246558Y-116546D01*
X246503Y-116856D01*
X246500D01*
X246489Y-116852D01*
X246474Y-116848D01*
X246452Y-116845D01*
X246427Y-116837D01*
X246398Y-116826D01*
X246329Y-116805D01*
X246249Y-116768D01*
X246168Y-116724D01*
X246092Y-116670D01*
X246023Y-116601D01*
X246019Y-116597D01*
X246016Y-116590D01*
X246008Y-116579D01*
X245997Y-116564D01*
X245983Y-116546D01*
X245968Y-116521D01*
X245954Y-116495D01*
X245936Y-116462D01*
X245906Y-116390D01*
X245877Y-116306D01*
X245859Y-116208D01*
X245852Y-116157D01*
Y-116066D01*
X245855Y-116026D01*
X245863Y-115978D01*
X245874Y-115920D01*
X245892Y-115855D01*
X245914Y-115789D01*
X245943Y-115723D01*
Y-115720D01*
X245946Y-115716D01*
X245957Y-115694D01*
X245979Y-115662D01*
X246005Y-115625D01*
X246041Y-115582D01*
X246081Y-115538D01*
X246128Y-115494D01*
X246183Y-115458D01*
X246190Y-115454D01*
X246209Y-115443D01*
X246241Y-115429D01*
X246281Y-115410D01*
X246329Y-115392D01*
X246383Y-115378D01*
X246445Y-115367D01*
X246507Y-115363D01*
X246514D01*
X246536D01*
X246565Y-115367D01*
X246605Y-115374D01*
X246653Y-115385D01*
X246704Y-115403D01*
X246755Y-115425D01*
X246805Y-115454D01*
X246813Y-115458D01*
X246827Y-115469D01*
X246853Y-115490D01*
X246882Y-115520D01*
X246915Y-115556D01*
X246951Y-115600D01*
X246984Y-115651D01*
X247017Y-115712D01*
Y-115709D01*
X247020Y-115702D01*
X247024Y-115691D01*
X247027Y-115676D01*
X247042Y-115636D01*
X247064Y-115585D01*
X247093Y-115527D01*
X247129Y-115469D01*
X247177Y-115414D01*
X247231Y-115363D01*
X247239Y-115359D01*
X247260Y-115345D01*
X247297Y-115323D01*
X247344Y-115301D01*
X247402Y-115279D01*
X247472Y-115258D01*
X247552Y-115243D01*
X247639Y-115239D01*
X247643D01*
X247654D01*
X247672D01*
X247694Y-115243D01*
D02*
G37*
G36*
X248382Y-118894D02*
X248378D01*
X248363D01*
X248341D01*
X248312Y-118890D01*
X248280Y-118887D01*
X248243Y-118879D01*
X248207Y-118872D01*
X248167Y-118858D01*
X248163D01*
X248160Y-118854D01*
X248138Y-118847D01*
X248105Y-118832D01*
X248061Y-118810D01*
X248010Y-118781D01*
X247952Y-118745D01*
X247894Y-118705D01*
X247832Y-118654D01*
X247828D01*
X247825Y-118646D01*
X247803Y-118628D01*
X247770Y-118595D01*
X247723Y-118548D01*
X247668Y-118493D01*
X247603Y-118424D01*
X247530Y-118341D01*
X247453Y-118250D01*
X247450Y-118246D01*
X247439Y-118231D01*
X247421Y-118210D01*
X247399Y-118184D01*
X247370Y-118151D01*
X247337Y-118111D01*
X247301Y-118071D01*
X247260Y-118024D01*
X247173Y-117933D01*
X247086Y-117842D01*
X247042Y-117798D01*
X246998Y-117758D01*
X246958Y-117722D01*
X246918Y-117693D01*
X246915D01*
X246911Y-117685D01*
X246900Y-117678D01*
X246885Y-117671D01*
X246846Y-117645D01*
X246798Y-117616D01*
X246740Y-117591D01*
X246678Y-117565D01*
X246609Y-117551D01*
X246543Y-117543D01*
X246540D01*
X246536D01*
X246514Y-117547D01*
X246478Y-117551D01*
X246438Y-117562D01*
X246387Y-117576D01*
X246336Y-117602D01*
X246285Y-117634D01*
X246234Y-117678D01*
X246227Y-117685D01*
X246212Y-117704D01*
X246194Y-117729D01*
X246168Y-117769D01*
X246147Y-117820D01*
X246125Y-117878D01*
X246110Y-117947D01*
X246107Y-118024D01*
Y-118046D01*
X246110Y-118060D01*
X246114Y-118104D01*
X246125Y-118155D01*
X246139Y-118210D01*
X246165Y-118271D01*
X246198Y-118330D01*
X246241Y-118384D01*
X246249Y-118392D01*
X246267Y-118406D01*
X246296Y-118428D01*
X246340Y-118450D01*
X246391Y-118475D01*
X246456Y-118497D01*
X246529Y-118512D01*
X246613Y-118519D01*
X246580Y-118836D01*
X246576D01*
X246565Y-118832D01*
X246547D01*
X246521Y-118828D01*
X246492Y-118821D01*
X246460Y-118814D01*
X246420Y-118803D01*
X246380Y-118792D01*
X246292Y-118763D01*
X246205Y-118719D01*
X246161Y-118694D01*
X246117Y-118661D01*
X246077Y-118628D01*
X246041Y-118592D01*
X246037Y-118588D01*
X246034Y-118581D01*
X246023Y-118570D01*
X246012Y-118552D01*
X245997Y-118530D01*
X245983Y-118504D01*
X245965Y-118475D01*
X245946Y-118439D01*
X245928Y-118399D01*
X245910Y-118355D01*
X245895Y-118308D01*
X245881Y-118257D01*
X245870Y-118202D01*
X245859Y-118144D01*
X245855Y-118082D01*
X245852Y-118017D01*
Y-117980D01*
X245855Y-117955D01*
X245859Y-117926D01*
X245863Y-117889D01*
X245870Y-117849D01*
X245877Y-117809D01*
X245903Y-117715D01*
X245939Y-117620D01*
X245961Y-117573D01*
X245986Y-117525D01*
X246019Y-117482D01*
X246056Y-117441D01*
X246059Y-117438D01*
X246063Y-117431D01*
X246077Y-117423D01*
X246092Y-117409D01*
X246110Y-117391D01*
X246136Y-117372D01*
X246161Y-117354D01*
X246194Y-117332D01*
X246263Y-117296D01*
X246350Y-117260D01*
X246394Y-117245D01*
X246445Y-117238D01*
X246496Y-117230D01*
X246551Y-117227D01*
X246558D01*
X246576D01*
X246605Y-117230D01*
X246645Y-117234D01*
X246689Y-117241D01*
X246740Y-117256D01*
X246795Y-117270D01*
X246849Y-117292D01*
X246856Y-117296D01*
X246875Y-117303D01*
X246904Y-117318D01*
X246944Y-117340D01*
X246987Y-117369D01*
X247042Y-117405D01*
X247097Y-117449D01*
X247159Y-117500D01*
X247166Y-117507D01*
X247188Y-117525D01*
X247206Y-117543D01*
X247224Y-117562D01*
X247246Y-117584D01*
X247275Y-117613D01*
X247304Y-117642D01*
X247337Y-117678D01*
X247373Y-117715D01*
X247413Y-117758D01*
X247453Y-117806D01*
X247501Y-117857D01*
X247548Y-117915D01*
X247599Y-117973D01*
X247603Y-117977D01*
X247610Y-117984D01*
X247621Y-117998D01*
X247635Y-118017D01*
X247657Y-118038D01*
X247679Y-118064D01*
X247726Y-118122D01*
X247781Y-118184D01*
X247836Y-118242D01*
X247883Y-118293D01*
X247901Y-118315D01*
X247919Y-118333D01*
X247923Y-118337D01*
X247934Y-118348D01*
X247948Y-118362D01*
X247970Y-118381D01*
X247996Y-118399D01*
X248021Y-118421D01*
X248083Y-118464D01*
Y-117223D01*
X248382D01*
Y-118894D01*
D02*
G37*
G36*
X247413Y-119283D02*
X247450D01*
X247493Y-119287D01*
X247537Y-119291D01*
X247635Y-119302D01*
X247737Y-119316D01*
X247836Y-119338D01*
X247883Y-119352D01*
X247927Y-119367D01*
X247930D01*
X247937Y-119371D01*
X247948Y-119378D01*
X247963Y-119385D01*
X248003Y-119407D01*
X248054Y-119440D01*
X248112Y-119484D01*
X248170Y-119535D01*
X248232Y-119600D01*
X248287Y-119680D01*
Y-119684D01*
X248294Y-119691D01*
X248298Y-119702D01*
X248309Y-119720D01*
X248320Y-119742D01*
X248331Y-119771D01*
X248341Y-119800D01*
X248356Y-119837D01*
X248371Y-119877D01*
X248382Y-119920D01*
X248393Y-119968D01*
X248403Y-120022D01*
X248411Y-120077D01*
X248418Y-120135D01*
X248425Y-120266D01*
Y-120299D01*
X248422Y-120324D01*
Y-120353D01*
X248418Y-120390D01*
X248414Y-120430D01*
X248411Y-120470D01*
X248396Y-120561D01*
X248374Y-120659D01*
X248345Y-120754D01*
X248305Y-120845D01*
Y-120849D01*
X248298Y-120856D01*
X248291Y-120867D01*
X248283Y-120881D01*
X248254Y-120921D01*
X248214Y-120969D01*
X248163Y-121023D01*
X248105Y-121074D01*
X248032Y-121125D01*
X247952Y-121165D01*
X247948D01*
X247941Y-121169D01*
X247927Y-121172D01*
X247908Y-121180D01*
X247886Y-121187D01*
X247857Y-121194D01*
X247825Y-121205D01*
X247785Y-121213D01*
X247741Y-121220D01*
X247694Y-121231D01*
X247643Y-121238D01*
X247588Y-121245D01*
X247526Y-121253D01*
X247461Y-121256D01*
X247392Y-121260D01*
X247319D01*
X245863D01*
Y-120925D01*
X247319D01*
X247322D01*
X247333D01*
X247351D01*
X247373D01*
X247399Y-120921D01*
X247431D01*
X247501Y-120918D01*
X247581Y-120910D01*
X247661Y-120899D01*
X247737Y-120885D01*
X247770Y-120878D01*
X247803Y-120867D01*
X247810Y-120863D01*
X247828Y-120856D01*
X247854Y-120838D01*
X247890Y-120816D01*
X247927Y-120790D01*
X247967Y-120754D01*
X248007Y-120710D01*
X248039Y-120659D01*
X248043Y-120652D01*
X248054Y-120634D01*
X248065Y-120601D01*
X248079Y-120557D01*
X248098Y-120506D01*
X248109Y-120441D01*
X248119Y-120372D01*
X248123Y-120295D01*
Y-120259D01*
X248119Y-120237D01*
Y-120204D01*
X248116Y-120171D01*
X248101Y-120091D01*
X248083Y-120004D01*
X248054Y-119920D01*
X248014Y-119840D01*
X247988Y-119804D01*
X247959Y-119771D01*
X247956Y-119767D01*
X247952Y-119764D01*
X247941Y-119757D01*
X247927Y-119746D01*
X247905Y-119735D01*
X247883Y-119720D01*
X247850Y-119706D01*
X247817Y-119691D01*
X247777Y-119676D01*
X247730Y-119666D01*
X247675Y-119651D01*
X247617Y-119640D01*
X247552Y-119629D01*
X247482Y-119622D01*
X247402Y-119615D01*
X247319D01*
X245863D01*
Y-119280D01*
X247319D01*
X247322D01*
X247337D01*
X247355D01*
X247381D01*
X247413Y-119283D01*
D02*
G37*
G36*
X249597Y-104511D02*
X249618D01*
X249677Y-104522D01*
X249746Y-104533D01*
X249819Y-104551D01*
X249899Y-104577D01*
X249975Y-104613D01*
X249979D01*
X249982Y-104617D01*
X249993Y-104624D01*
X250008Y-104631D01*
X250044Y-104653D01*
X250092Y-104686D01*
X250143Y-104726D01*
X250194Y-104773D01*
X250244Y-104831D01*
X250288Y-104893D01*
Y-104897D01*
X250292Y-104901D01*
X250299Y-104911D01*
X250303Y-104926D01*
X250321Y-104963D01*
X250339Y-105010D01*
X250361Y-105072D01*
X250376Y-105141D01*
X250390Y-105217D01*
X250394Y-105301D01*
Y-105319D01*
X250390Y-105337D01*
Y-105367D01*
X250387Y-105399D01*
X250379Y-105436D01*
X250368Y-105479D01*
X250357Y-105523D01*
X250343Y-105574D01*
X250325Y-105625D01*
X250303Y-105676D01*
X250274Y-105730D01*
X250241Y-105781D01*
X250204Y-105832D01*
X250161Y-105883D01*
X250110Y-105931D01*
X250106Y-105934D01*
X250095Y-105942D01*
X250081Y-105953D01*
X250055Y-105967D01*
X250023Y-105989D01*
X249986Y-106007D01*
X249939Y-106029D01*
X249888Y-106051D01*
X249826Y-106076D01*
X249757Y-106098D01*
X249680Y-106116D01*
X249597Y-106135D01*
X249502Y-106153D01*
X249400Y-106164D01*
X249291Y-106171D01*
X249174Y-106175D01*
X249171D01*
X249167D01*
X249156D01*
X249142D01*
X249105Y-106171D01*
X249054D01*
X248996Y-106167D01*
X248927Y-106160D01*
X248850Y-106153D01*
X248767Y-106142D01*
X248683Y-106127D01*
X248592Y-106109D01*
X248505Y-106087D01*
X248417Y-106062D01*
X248334Y-106029D01*
X248253Y-105993D01*
X248177Y-105953D01*
X248112Y-105905D01*
X248108Y-105902D01*
X248100Y-105894D01*
X248086Y-105880D01*
X248064Y-105862D01*
X248042Y-105840D01*
X248021Y-105811D01*
X247991Y-105774D01*
X247966Y-105738D01*
X247940Y-105694D01*
X247911Y-105647D01*
X247889Y-105592D01*
X247864Y-105538D01*
X247846Y-105476D01*
X247831Y-105410D01*
X247824Y-105341D01*
X247820Y-105268D01*
Y-105239D01*
X247824Y-105217D01*
Y-105192D01*
X247828Y-105163D01*
X247842Y-105094D01*
X247860Y-105017D01*
X247889Y-104937D01*
X247933Y-104857D01*
X247959Y-104817D01*
X247988Y-104780D01*
X247991Y-104777D01*
X247995Y-104773D01*
X248006Y-104762D01*
X248017Y-104751D01*
X248035Y-104733D01*
X248057Y-104719D01*
X248108Y-104679D01*
X248173Y-104639D01*
X248253Y-104602D01*
X248344Y-104569D01*
X248446Y-104548D01*
X248472Y-104857D01*
X248468D01*
X248464Y-104861D01*
X248443Y-104864D01*
X248410Y-104875D01*
X248370Y-104890D01*
X248326Y-104904D01*
X248283Y-104926D01*
X248242Y-104952D01*
X248210Y-104977D01*
X248202Y-104984D01*
X248188Y-104999D01*
X248166Y-105024D01*
X248141Y-105061D01*
X248119Y-105108D01*
X248097Y-105159D01*
X248082Y-105221D01*
X248075Y-105286D01*
Y-105312D01*
X248079Y-105341D01*
X248086Y-105374D01*
X248097Y-105418D01*
X248112Y-105461D01*
X248130Y-105505D01*
X248159Y-105549D01*
X248162Y-105556D01*
X248177Y-105574D01*
X248202Y-105599D01*
X248239Y-105632D01*
X248283Y-105669D01*
X248334Y-105709D01*
X248399Y-105745D01*
X248472Y-105781D01*
X248476D01*
X248483Y-105785D01*
X248494Y-105789D01*
X248508Y-105796D01*
X248530Y-105800D01*
X248555Y-105807D01*
X248585Y-105814D01*
X248621Y-105822D01*
X248661Y-105832D01*
X248705Y-105840D01*
X248752Y-105847D01*
X248803Y-105851D01*
X248861Y-105858D01*
X248920Y-105862D01*
X248985Y-105865D01*
X249051D01*
X249047Y-105862D01*
X249025Y-105847D01*
X248996Y-105822D01*
X248960Y-105789D01*
X248916Y-105752D01*
X248876Y-105705D01*
X248836Y-105654D01*
X248799Y-105596D01*
Y-105592D01*
X248796Y-105589D01*
X248785Y-105567D01*
X248774Y-105534D01*
X248756Y-105490D01*
X248741Y-105439D01*
X248730Y-105381D01*
X248719Y-105319D01*
X248716Y-105254D01*
Y-105225D01*
X248719Y-105203D01*
X248723Y-105174D01*
X248727Y-105145D01*
X248734Y-105108D01*
X248745Y-105072D01*
X248770Y-104988D01*
X248788Y-104944D01*
X248814Y-104901D01*
X248839Y-104857D01*
X248869Y-104810D01*
X248905Y-104766D01*
X248945Y-104726D01*
X248949Y-104722D01*
X248956Y-104715D01*
X248967Y-104704D01*
X248985Y-104693D01*
X249010Y-104675D01*
X249036Y-104657D01*
X249069Y-104639D01*
X249105Y-104617D01*
X249145Y-104595D01*
X249189Y-104577D01*
X249240Y-104558D01*
X249291Y-104540D01*
X249345Y-104529D01*
X249407Y-104518D01*
X249469Y-104511D01*
X249535Y-104508D01*
X249538D01*
X249546D01*
X249556D01*
X249575D01*
X249597Y-104511D01*
D02*
G37*
G36*
X249160Y-106466D02*
X249207D01*
X249262Y-106469D01*
X249316Y-106477D01*
X249440Y-106488D01*
X249571Y-106506D01*
X249695Y-106531D01*
X249757Y-106550D01*
X249811Y-106568D01*
X249815D01*
X249822Y-106571D01*
X249837Y-106579D01*
X249859Y-106586D01*
X249881Y-106597D01*
X249910Y-106611D01*
X249972Y-106648D01*
X250041Y-106692D01*
X250114Y-106742D01*
X250183Y-106808D01*
X250244Y-106881D01*
Y-106884D01*
X250252Y-106892D01*
X250259Y-106903D01*
X250266Y-106917D01*
X250277Y-106939D01*
X250292Y-106961D01*
X250306Y-106990D01*
X250317Y-107019D01*
X250346Y-107088D01*
X250372Y-107172D01*
X250387Y-107263D01*
X250394Y-107365D01*
Y-107394D01*
X250390Y-107412D01*
Y-107438D01*
X250387Y-107467D01*
X250372Y-107536D01*
X250354Y-107612D01*
X250325Y-107693D01*
X250285Y-107773D01*
X250259Y-107813D01*
X250230Y-107849D01*
X250226Y-107853D01*
X250223Y-107856D01*
X250212Y-107867D01*
X250201Y-107878D01*
X250183Y-107893D01*
X250161Y-107911D01*
X250110Y-107947D01*
X250044Y-107984D01*
X249964Y-108020D01*
X249873Y-108049D01*
X249768Y-108071D01*
X249742Y-107773D01*
X249746D01*
X249753Y-107769D01*
X249760D01*
X249775Y-107765D01*
X249815Y-107754D01*
X249859Y-107740D01*
X249910Y-107722D01*
X249961Y-107696D01*
X250008Y-107667D01*
X250048Y-107631D01*
X250052Y-107627D01*
X250062Y-107612D01*
X250077Y-107587D01*
X250092Y-107558D01*
X250110Y-107518D01*
X250124Y-107470D01*
X250135Y-107416D01*
X250139Y-107358D01*
Y-107332D01*
X250135Y-107307D01*
X250132Y-107274D01*
X250124Y-107234D01*
X250114Y-107194D01*
X250099Y-107150D01*
X250077Y-107110D01*
X250073Y-107106D01*
X250066Y-107092D01*
X250052Y-107070D01*
X250030Y-107048D01*
X250004Y-107019D01*
X249975Y-106990D01*
X249942Y-106961D01*
X249902Y-106932D01*
X249899Y-106928D01*
X249881Y-106921D01*
X249855Y-106906D01*
X249822Y-106892D01*
X249779Y-106874D01*
X249728Y-106855D01*
X249669Y-106837D01*
X249604Y-106819D01*
X249600D01*
X249597Y-106815D01*
X249586D01*
X249571Y-106812D01*
X249535Y-106804D01*
X249487Y-106793D01*
X249429Y-106786D01*
X249367Y-106779D01*
X249298Y-106775D01*
X249225Y-106772D01*
X249222D01*
X249211D01*
X249193D01*
X249163D01*
X249171Y-106775D01*
X249189Y-106790D01*
X249214Y-106812D01*
X249251Y-106837D01*
X249287Y-106874D01*
X249327Y-106917D01*
X249367Y-106968D01*
X249404Y-107026D01*
X249407Y-107034D01*
X249418Y-107055D01*
X249433Y-107088D01*
X249447Y-107128D01*
X249465Y-107183D01*
X249480Y-107241D01*
X249491Y-107307D01*
X249495Y-107376D01*
Y-107405D01*
X249491Y-107427D01*
X249487Y-107456D01*
X249484Y-107485D01*
X249477Y-107521D01*
X249465Y-107558D01*
X249440Y-107641D01*
X249422Y-107685D01*
X249400Y-107729D01*
X249375Y-107776D01*
X249342Y-107820D01*
X249309Y-107864D01*
X249269Y-107904D01*
X249265Y-107907D01*
X249258Y-107914D01*
X249247Y-107922D01*
X249229Y-107936D01*
X249203Y-107955D01*
X249178Y-107973D01*
X249145Y-107991D01*
X249109Y-108009D01*
X249069Y-108031D01*
X249025Y-108049D01*
X248974Y-108067D01*
X248923Y-108086D01*
X248865Y-108100D01*
X248803Y-108107D01*
X248741Y-108115D01*
X248672Y-108118D01*
X248668D01*
X248654D01*
X248636D01*
X248610Y-108115D01*
X248577Y-108111D01*
X248537Y-108107D01*
X248497Y-108100D01*
X248450Y-108089D01*
X248355Y-108064D01*
X248304Y-108046D01*
X248250Y-108024D01*
X248199Y-107998D01*
X248151Y-107966D01*
X248100Y-107933D01*
X248057Y-107893D01*
X248053Y-107889D01*
X248046Y-107882D01*
X248035Y-107871D01*
X248021Y-107853D01*
X248002Y-107831D01*
X247980Y-107802D01*
X247962Y-107773D01*
X247937Y-107736D01*
X247915Y-107700D01*
X247897Y-107656D01*
X247857Y-107558D01*
X247842Y-107507D01*
X247831Y-107449D01*
X247824Y-107390D01*
X247820Y-107328D01*
Y-107303D01*
X247824Y-107285D01*
Y-107267D01*
X247828Y-107241D01*
X247838Y-107179D01*
X247853Y-107110D01*
X247879Y-107034D01*
X247911Y-106957D01*
X247955Y-106881D01*
Y-106877D01*
X247962Y-106874D01*
X247970Y-106863D01*
X247980Y-106848D01*
X248009Y-106812D01*
X248050Y-106764D01*
X248104Y-106717D01*
X248170Y-106662D01*
X248246Y-106615D01*
X248334Y-106571D01*
X248337D01*
X248344Y-106568D01*
X248359Y-106560D01*
X248377Y-106553D01*
X248403Y-106546D01*
X248435Y-106535D01*
X248472Y-106528D01*
X248512Y-106517D01*
X248559Y-106506D01*
X248614Y-106495D01*
X248672Y-106488D01*
X248734Y-106480D01*
X248803Y-106473D01*
X248876Y-106466D01*
X248956Y-106462D01*
X249040D01*
X249043D01*
X249061D01*
X249087D01*
X249120D01*
X249160Y-106466D01*
D02*
G37*
G36*
X249571Y-108406D02*
X249593Y-108413D01*
X249622Y-108424D01*
X249655Y-108435D01*
X249695Y-108450D01*
X249739Y-108468D01*
X249786Y-108490D01*
X249888Y-108541D01*
X249990Y-108606D01*
X250041Y-108646D01*
X250092Y-108686D01*
X250135Y-108730D01*
X250179Y-108781D01*
X250183Y-108784D01*
X250190Y-108792D01*
X250197Y-108810D01*
X250212Y-108828D01*
X250230Y-108857D01*
X250248Y-108886D01*
X250266Y-108926D01*
X250285Y-108967D01*
X250306Y-109014D01*
X250325Y-109065D01*
X250343Y-109119D01*
X250361Y-109178D01*
X250376Y-109239D01*
X250383Y-109305D01*
X250390Y-109374D01*
X250394Y-109447D01*
Y-109487D01*
X250390Y-109516D01*
Y-109549D01*
X250387Y-109589D01*
X250379Y-109633D01*
X250372Y-109684D01*
X250354Y-109789D01*
X250325Y-109898D01*
X250285Y-110008D01*
X250259Y-110058D01*
X250230Y-110109D01*
X250226Y-110113D01*
X250223Y-110120D01*
X250212Y-110135D01*
X250197Y-110150D01*
X250183Y-110171D01*
X250161Y-110197D01*
X250135Y-110226D01*
X250106Y-110255D01*
X250073Y-110284D01*
X250041Y-110317D01*
X249957Y-110382D01*
X249859Y-110444D01*
X249749Y-110499D01*
X249746D01*
X249735Y-110506D01*
X249717Y-110510D01*
X249695Y-110521D01*
X249666Y-110528D01*
X249629Y-110539D01*
X249589Y-110554D01*
X249546Y-110564D01*
X249498Y-110575D01*
X249444Y-110590D01*
X249331Y-110608D01*
X249203Y-110623D01*
X249072Y-110630D01*
X249069D01*
X249054D01*
X249032D01*
X249007Y-110626D01*
X248971D01*
X248934Y-110623D01*
X248887Y-110619D01*
X248839Y-110612D01*
X248734Y-110594D01*
X248617Y-110568D01*
X248501Y-110532D01*
X248388Y-110481D01*
X248384Y-110477D01*
X248374Y-110473D01*
X248359Y-110466D01*
X248341Y-110452D01*
X248315Y-110437D01*
X248286Y-110419D01*
X248221Y-110371D01*
X248148Y-110310D01*
X248075Y-110237D01*
X248002Y-110153D01*
X247940Y-110055D01*
X247937Y-110051D01*
X247933Y-110040D01*
X247926Y-110026D01*
X247915Y-110008D01*
X247904Y-109978D01*
X247893Y-109949D01*
X247879Y-109913D01*
X247864Y-109873D01*
X247849Y-109829D01*
X247835Y-109782D01*
X247813Y-109680D01*
X247795Y-109563D01*
X247787Y-109443D01*
Y-109407D01*
X247791Y-109381D01*
X247795Y-109349D01*
X247798Y-109309D01*
X247802Y-109269D01*
X247813Y-109221D01*
X247835Y-109123D01*
X247868Y-109014D01*
X247889Y-108959D01*
X247915Y-108908D01*
X247948Y-108857D01*
X247980Y-108806D01*
X247984Y-108803D01*
X247988Y-108795D01*
X247999Y-108781D01*
X248017Y-108763D01*
X248035Y-108744D01*
X248060Y-108719D01*
X248090Y-108694D01*
X248119Y-108664D01*
X248155Y-108635D01*
X248199Y-108606D01*
X248242Y-108573D01*
X248290Y-108544D01*
X248344Y-108519D01*
X248399Y-108490D01*
X248457Y-108468D01*
X248523Y-108446D01*
X248599Y-108774D01*
X248596D01*
X248588Y-108777D01*
X248574Y-108784D01*
X248555Y-108792D01*
X248534Y-108799D01*
X248505Y-108810D01*
X248446Y-108839D01*
X248381Y-108876D01*
X248315Y-108919D01*
X248253Y-108974D01*
X248199Y-109032D01*
X248191Y-109039D01*
X248177Y-109061D01*
X248159Y-109098D01*
X248133Y-109145D01*
X248112Y-109207D01*
X248090Y-109276D01*
X248075Y-109360D01*
X248071Y-109451D01*
Y-109480D01*
X248075Y-109498D01*
Y-109523D01*
X248079Y-109553D01*
X248090Y-109622D01*
X248104Y-109698D01*
X248130Y-109778D01*
X248166Y-109862D01*
X248213Y-109938D01*
Y-109942D01*
X248221Y-109946D01*
X248239Y-109971D01*
X248268Y-110004D01*
X248312Y-110044D01*
X248366Y-110091D01*
X248428Y-110135D01*
X248505Y-110175D01*
X248588Y-110211D01*
X248592D01*
X248599Y-110215D01*
X248610Y-110219D01*
X248628Y-110222D01*
X248650Y-110230D01*
X248676Y-110237D01*
X248738Y-110248D01*
X248810Y-110262D01*
X248890Y-110277D01*
X248978Y-110284D01*
X249072Y-110288D01*
X249076D01*
X249087D01*
X249105D01*
X249127D01*
X249152Y-110284D01*
X249185D01*
X249222Y-110281D01*
X249262Y-110277D01*
X249349Y-110266D01*
X249444Y-110248D01*
X249538Y-110226D01*
X249633Y-110197D01*
X249637D01*
X249644Y-110193D01*
X249655Y-110186D01*
X249673Y-110179D01*
X249717Y-110157D01*
X249768Y-110124D01*
X249826Y-110084D01*
X249888Y-110033D01*
X249942Y-109975D01*
X249993Y-109906D01*
Y-109902D01*
X249997Y-109895D01*
X250004Y-109884D01*
X250011Y-109869D01*
X250019Y-109851D01*
X250030Y-109829D01*
X250052Y-109778D01*
X250073Y-109713D01*
X250092Y-109640D01*
X250106Y-109560D01*
X250110Y-109476D01*
Y-109451D01*
X250106Y-109429D01*
Y-109403D01*
X250102Y-109378D01*
X250088Y-109312D01*
X250070Y-109236D01*
X250041Y-109159D01*
X250001Y-109079D01*
X249979Y-109039D01*
X249950Y-109003D01*
X249946Y-108999D01*
X249942Y-108996D01*
X249932Y-108985D01*
X249921Y-108970D01*
X249902Y-108956D01*
X249881Y-108937D01*
X249859Y-108915D01*
X249830Y-108897D01*
X249797Y-108876D01*
X249760Y-108850D01*
X249724Y-108828D01*
X249680Y-108806D01*
X249633Y-108788D01*
X249582Y-108770D01*
X249527Y-108752D01*
X249469Y-108737D01*
X249553Y-108402D01*
X249556D01*
X249571Y-108406D01*
D02*
G37*
G36*
X412293Y-118955D02*
X412289Y-118984D01*
Y-119017D01*
X412285Y-119093D01*
X412274Y-119174D01*
X412263Y-119261D01*
X412245Y-119341D01*
X412234Y-119381D01*
X412223Y-119414D01*
Y-119417D01*
X412220Y-119421D01*
X412209Y-119443D01*
X412194Y-119476D01*
X412169Y-119516D01*
X412136Y-119559D01*
X412092Y-119607D01*
X412042Y-119650D01*
X411983Y-119694D01*
X411980D01*
X411976Y-119698D01*
X411954Y-119712D01*
X411918Y-119727D01*
X411870Y-119749D01*
X411816Y-119767D01*
X411750Y-119785D01*
X411681Y-119796D01*
X411605Y-119800D01*
X411601D01*
X411594D01*
X411579D01*
X411561Y-119796D01*
X411536D01*
X411510Y-119792D01*
X411448Y-119778D01*
X411375Y-119756D01*
X411299Y-119727D01*
X411223Y-119683D01*
X411186Y-119654D01*
X411150Y-119625D01*
X411146Y-119621D01*
X411142Y-119618D01*
X411131Y-119607D01*
X411121Y-119592D01*
X411106Y-119574D01*
X411091Y-119552D01*
X411073Y-119523D01*
X411051Y-119494D01*
X411033Y-119457D01*
X411015Y-119417D01*
X410993Y-119374D01*
X410975Y-119326D01*
X410960Y-119272D01*
X410942Y-119217D01*
X410931Y-119155D01*
X410920Y-119090D01*
X410917Y-119097D01*
X410909Y-119112D01*
X410895Y-119133D01*
X410880Y-119163D01*
X410840Y-119228D01*
X410815Y-119261D01*
X410793Y-119290D01*
X410786Y-119297D01*
X410768Y-119316D01*
X410738Y-119345D01*
X410702Y-119381D01*
X410651Y-119421D01*
X410596Y-119468D01*
X410531Y-119516D01*
X410458Y-119567D01*
X409774Y-120000D01*
Y-119585D01*
X410298Y-119254D01*
X410302D01*
X410309Y-119246D01*
X410320Y-119239D01*
X410334Y-119228D01*
X410374Y-119203D01*
X410425Y-119170D01*
X410480Y-119130D01*
X410538Y-119090D01*
X410593Y-119050D01*
X410644Y-119013D01*
X410647Y-119010D01*
X410662Y-118999D01*
X410684Y-118981D01*
X410709Y-118955D01*
X410764Y-118901D01*
X410789Y-118871D01*
X410811Y-118842D01*
X410815Y-118839D01*
X410818Y-118831D01*
X410826Y-118817D01*
X410837Y-118795D01*
X410848Y-118773D01*
X410858Y-118748D01*
X410877Y-118689D01*
Y-118686D01*
X410880Y-118678D01*
Y-118664D01*
X410884Y-118646D01*
X410888Y-118620D01*
Y-118591D01*
X410891Y-118551D01*
Y-118122D01*
X409774D01*
Y-117787D01*
X412293D01*
Y-118955D01*
D02*
G37*
G36*
X411514Y-120200D02*
X411546Y-120204D01*
X411587Y-120207D01*
X411626Y-120215D01*
X411674Y-120226D01*
X411768Y-120251D01*
X411819Y-120269D01*
X411874Y-120291D01*
X411925Y-120317D01*
X411972Y-120349D01*
X412023Y-120382D01*
X412067Y-120422D01*
X412071Y-120426D01*
X412078Y-120433D01*
X412089Y-120444D01*
X412103Y-120462D01*
X412122Y-120484D01*
X412143Y-120513D01*
X412162Y-120542D01*
X412187Y-120579D01*
X412209Y-120615D01*
X412227Y-120659D01*
X412267Y-120757D01*
X412282Y-120808D01*
X412293Y-120866D01*
X412300Y-120924D01*
X412303Y-120986D01*
Y-121012D01*
X412300Y-121030D01*
Y-121048D01*
X412296Y-121074D01*
X412285Y-121135D01*
X412271Y-121205D01*
X412245Y-121281D01*
X412213Y-121358D01*
X412169Y-121434D01*
Y-121438D01*
X412162Y-121441D01*
X412154Y-121452D01*
X412143Y-121467D01*
X412114Y-121503D01*
X412074Y-121550D01*
X412020Y-121598D01*
X411954Y-121652D01*
X411878Y-121700D01*
X411790Y-121743D01*
X411787D01*
X411779Y-121747D01*
X411765Y-121754D01*
X411747Y-121762D01*
X411721Y-121769D01*
X411688Y-121780D01*
X411652Y-121787D01*
X411612Y-121798D01*
X411565Y-121809D01*
X411510Y-121820D01*
X411452Y-121827D01*
X411390Y-121834D01*
X411321Y-121842D01*
X411248Y-121849D01*
X411168Y-121853D01*
X411084D01*
X411081D01*
X411062D01*
X411037D01*
X411004D01*
X410964Y-121849D01*
X410917D01*
X410862Y-121845D01*
X410808Y-121838D01*
X410684Y-121827D01*
X410553Y-121809D01*
X410429Y-121783D01*
X410367Y-121765D01*
X410313Y-121747D01*
X410309D01*
X410302Y-121743D01*
X410287Y-121736D01*
X410265Y-121729D01*
X410243Y-121718D01*
X410214Y-121703D01*
X410152Y-121667D01*
X410083Y-121623D01*
X410010Y-121572D01*
X409941Y-121507D01*
X409879Y-121434D01*
Y-121430D01*
X409872Y-121423D01*
X409865Y-121412D01*
X409858Y-121398D01*
X409847Y-121376D01*
X409832Y-121354D01*
X409817Y-121325D01*
X409806Y-121296D01*
X409777Y-121227D01*
X409752Y-121143D01*
X409737Y-121052D01*
X409730Y-120950D01*
Y-120921D01*
X409734Y-120903D01*
Y-120877D01*
X409737Y-120848D01*
X409752Y-120779D01*
X409770Y-120702D01*
X409799Y-120622D01*
X409839Y-120542D01*
X409865Y-120502D01*
X409894Y-120466D01*
X409898Y-120462D01*
X409901Y-120458D01*
X409912Y-120448D01*
X409923Y-120437D01*
X409941Y-120422D01*
X409963Y-120404D01*
X410014Y-120367D01*
X410079Y-120331D01*
X410160Y-120295D01*
X410251Y-120265D01*
X410356Y-120244D01*
X410382Y-120542D01*
X410378D01*
X410371Y-120546D01*
X410363D01*
X410349Y-120549D01*
X410309Y-120560D01*
X410265Y-120575D01*
X410214Y-120593D01*
X410163Y-120619D01*
X410116Y-120648D01*
X410076Y-120684D01*
X410072Y-120688D01*
X410061Y-120702D01*
X410047Y-120728D01*
X410032Y-120757D01*
X410014Y-120797D01*
X409999Y-120844D01*
X409988Y-120899D01*
X409985Y-120957D01*
Y-120983D01*
X409988Y-121008D01*
X409992Y-121041D01*
X409999Y-121081D01*
X410010Y-121121D01*
X410025Y-121165D01*
X410047Y-121205D01*
X410050Y-121208D01*
X410058Y-121223D01*
X410072Y-121245D01*
X410094Y-121266D01*
X410119Y-121296D01*
X410149Y-121325D01*
X410181Y-121354D01*
X410221Y-121383D01*
X410225Y-121387D01*
X410243Y-121394D01*
X410269Y-121408D01*
X410302Y-121423D01*
X410345Y-121441D01*
X410396Y-121459D01*
X410454Y-121478D01*
X410520Y-121496D01*
X410524D01*
X410527Y-121500D01*
X410538D01*
X410553Y-121503D01*
X410589Y-121510D01*
X410636Y-121521D01*
X410695Y-121529D01*
X410756Y-121536D01*
X410826Y-121539D01*
X410898Y-121543D01*
X410902D01*
X410913D01*
X410931D01*
X410960D01*
X410953Y-121539D01*
X410935Y-121525D01*
X410909Y-121503D01*
X410873Y-121478D01*
X410837Y-121441D01*
X410797Y-121398D01*
X410756Y-121347D01*
X410720Y-121288D01*
X410716Y-121281D01*
X410706Y-121259D01*
X410691Y-121227D01*
X410676Y-121186D01*
X410658Y-121132D01*
X410644Y-121074D01*
X410633Y-121008D01*
X410629Y-120939D01*
Y-120910D01*
X410633Y-120888D01*
X410636Y-120859D01*
X410640Y-120830D01*
X410647Y-120793D01*
X410658Y-120757D01*
X410684Y-120673D01*
X410702Y-120630D01*
X410724Y-120586D01*
X410749Y-120538D01*
X410782Y-120495D01*
X410815Y-120451D01*
X410855Y-120411D01*
X410858Y-120407D01*
X410866Y-120400D01*
X410877Y-120393D01*
X410895Y-120378D01*
X410920Y-120360D01*
X410946Y-120342D01*
X410979Y-120324D01*
X411015Y-120306D01*
X411055Y-120284D01*
X411099Y-120265D01*
X411150Y-120247D01*
X411201Y-120229D01*
X411259Y-120215D01*
X411321Y-120207D01*
X411383Y-120200D01*
X411452Y-120196D01*
X411455D01*
X411470D01*
X411488D01*
X411514Y-120200D01*
D02*
G37*
G36*
X410458Y-122479D02*
X410454D01*
X410447D01*
X410436Y-122482D01*
X410418Y-122486D01*
X410378Y-122497D01*
X410323Y-122511D01*
X410269Y-122533D01*
X410207Y-122562D01*
X410152Y-122599D01*
X410101Y-122642D01*
X410098Y-122650D01*
X410083Y-122664D01*
X410065Y-122693D01*
X410043Y-122733D01*
X410021Y-122777D01*
X410003Y-122832D01*
X409988Y-122894D01*
X409985Y-122963D01*
Y-122985D01*
X409988Y-122999D01*
X409992Y-123043D01*
X410007Y-123094D01*
X410025Y-123156D01*
X410054Y-123218D01*
X410098Y-123283D01*
X410123Y-123312D01*
X410152Y-123341D01*
X410156Y-123345D01*
X410160Y-123349D01*
X410171Y-123356D01*
X410181Y-123367D01*
X410221Y-123392D01*
X410272Y-123421D01*
X410334Y-123447D01*
X410411Y-123472D01*
X410502Y-123491D01*
X410549Y-123498D01*
X410600D01*
X410604D01*
X410611D01*
X410626D01*
X410644Y-123494D01*
X410666D01*
X410691Y-123491D01*
X410749Y-123480D01*
X410818Y-123461D01*
X410888Y-123436D01*
X410953Y-123400D01*
X411015Y-123349D01*
X411019D01*
X411022Y-123341D01*
X411040Y-123323D01*
X411066Y-123290D01*
X411095Y-123247D01*
X411121Y-123188D01*
X411146Y-123123D01*
X411164Y-123047D01*
X411171Y-123003D01*
Y-122934D01*
X411168Y-122905D01*
X411164Y-122868D01*
X411153Y-122824D01*
X411142Y-122781D01*
X411124Y-122733D01*
X411102Y-122686D01*
X411099Y-122682D01*
X411091Y-122668D01*
X411073Y-122646D01*
X411055Y-122617D01*
X411030Y-122588D01*
X410997Y-122559D01*
X410964Y-122526D01*
X410924Y-122501D01*
X410964Y-122209D01*
X412260Y-122453D01*
Y-123705D01*
X411965D01*
Y-122697D01*
X411284Y-122562D01*
X411288Y-122566D01*
X411292Y-122573D01*
X411299Y-122584D01*
X411310Y-122602D01*
X411321Y-122624D01*
X411335Y-122650D01*
X411364Y-122708D01*
X411393Y-122781D01*
X411419Y-122861D01*
X411437Y-122948D01*
X411445Y-122992D01*
Y-123072D01*
X411441Y-123094D01*
X411437Y-123123D01*
X411434Y-123156D01*
X411426Y-123192D01*
X411415Y-123232D01*
X411390Y-123319D01*
X411372Y-123367D01*
X411346Y-123414D01*
X411321Y-123461D01*
X411292Y-123509D01*
X411255Y-123552D01*
X411215Y-123596D01*
X411211Y-123600D01*
X411204Y-123607D01*
X411193Y-123618D01*
X411175Y-123633D01*
X411150Y-123651D01*
X411124Y-123669D01*
X411091Y-123691D01*
X411055Y-123713D01*
X411015Y-123731D01*
X410971Y-123753D01*
X410920Y-123771D01*
X410869Y-123789D01*
X410815Y-123804D01*
X410753Y-123814D01*
X410691Y-123822D01*
X410626Y-123825D01*
X410622D01*
X410611D01*
X410593D01*
X410567Y-123822D01*
X410538Y-123818D01*
X410505Y-123814D01*
X410465Y-123807D01*
X410425Y-123800D01*
X410331Y-123778D01*
X410232Y-123742D01*
X410181Y-123720D01*
X410134Y-123691D01*
X410083Y-123662D01*
X410036Y-123625D01*
X410032Y-123622D01*
X410021Y-123614D01*
X410007Y-123600D01*
X409988Y-123582D01*
X409967Y-123556D01*
X409938Y-123527D01*
X409912Y-123491D01*
X409883Y-123451D01*
X409854Y-123407D01*
X409828Y-123356D01*
X409803Y-123301D01*
X409777Y-123243D01*
X409759Y-123181D01*
X409745Y-123112D01*
X409734Y-123039D01*
X409730Y-122963D01*
Y-122930D01*
X409734Y-122905D01*
X409737Y-122875D01*
X409741Y-122843D01*
X409745Y-122803D01*
X409756Y-122763D01*
X409777Y-122672D01*
X409810Y-122581D01*
X409832Y-122533D01*
X409858Y-122486D01*
X409887Y-122442D01*
X409919Y-122399D01*
X409923Y-122395D01*
X409927Y-122388D01*
X409941Y-122380D01*
X409956Y-122366D01*
X409974Y-122348D01*
X409996Y-122329D01*
X410025Y-122308D01*
X410058Y-122289D01*
X410090Y-122267D01*
X410131Y-122246D01*
X410218Y-122206D01*
X410320Y-122173D01*
X410374Y-122162D01*
X410433Y-122155D01*
X410458Y-122479D01*
D02*
G37*
G36*
X439177Y-120058D02*
X439173Y-120087D01*
Y-120120D01*
X439169Y-120196D01*
X439158Y-120276D01*
X439148Y-120363D01*
X439129Y-120443D01*
X439118Y-120484D01*
X439108Y-120516D01*
Y-120520D01*
X439104Y-120524D01*
X439093Y-120545D01*
X439078Y-120578D01*
X439053Y-120618D01*
X439020Y-120662D01*
X438976Y-120709D01*
X438926Y-120753D01*
X438867Y-120797D01*
X438864D01*
X438860Y-120800D01*
X438838Y-120815D01*
X438802Y-120829D01*
X438754Y-120851D01*
X438700Y-120869D01*
X438634Y-120887D01*
X438565Y-120898D01*
X438489Y-120902D01*
X438485D01*
X438478D01*
X438463D01*
X438445Y-120898D01*
X438420D01*
X438394Y-120895D01*
X438332Y-120880D01*
X438259Y-120858D01*
X438183Y-120829D01*
X438106Y-120786D01*
X438070Y-120756D01*
X438034Y-120727D01*
X438030Y-120724D01*
X438027Y-120720D01*
X438016Y-120709D01*
X438005Y-120695D01*
X437990Y-120676D01*
X437976Y-120654D01*
X437957Y-120625D01*
X437935Y-120596D01*
X437917Y-120560D01*
X437899Y-120520D01*
X437877Y-120476D01*
X437859Y-120429D01*
X437844Y-120374D01*
X437826Y-120320D01*
X437815Y-120258D01*
X437804Y-120192D01*
X437801Y-120200D01*
X437793Y-120214D01*
X437779Y-120236D01*
X437764Y-120265D01*
X437724Y-120331D01*
X437699Y-120363D01*
X437677Y-120393D01*
X437670Y-120400D01*
X437651Y-120418D01*
X437622Y-120447D01*
X437586Y-120484D01*
X437535Y-120524D01*
X437480Y-120571D01*
X437415Y-120618D01*
X437342Y-120669D01*
X436658Y-121102D01*
Y-120687D01*
X437182Y-120356D01*
X437186D01*
X437193Y-120349D01*
X437204Y-120342D01*
X437218Y-120331D01*
X437258Y-120305D01*
X437309Y-120272D01*
X437364Y-120232D01*
X437422Y-120192D01*
X437477Y-120152D01*
X437528Y-120116D01*
X437531Y-120112D01*
X437546Y-120101D01*
X437568Y-120083D01*
X437593Y-120058D01*
X437648Y-120003D01*
X437673Y-119974D01*
X437695Y-119945D01*
X437699Y-119941D01*
X437703Y-119934D01*
X437710Y-119919D01*
X437721Y-119897D01*
X437732Y-119876D01*
X437743Y-119850D01*
X437761Y-119792D01*
Y-119788D01*
X437764Y-119781D01*
Y-119766D01*
X437768Y-119748D01*
X437772Y-119723D01*
Y-119694D01*
X437775Y-119653D01*
Y-119224D01*
X436658D01*
Y-118889D01*
X439177D01*
Y-120058D01*
D02*
G37*
G36*
X438398Y-121302D02*
X438431Y-121306D01*
X438471Y-121310D01*
X438511Y-121317D01*
X438558Y-121328D01*
X438653Y-121353D01*
X438703Y-121372D01*
X438758Y-121394D01*
X438809Y-121419D01*
X438856Y-121452D01*
X438907Y-121484D01*
X438951Y-121525D01*
X438955Y-121528D01*
X438962Y-121535D01*
X438973Y-121546D01*
X438987Y-121565D01*
X439006Y-121586D01*
X439028Y-121616D01*
X439046Y-121645D01*
X439071Y-121681D01*
X439093Y-121717D01*
X439111Y-121761D01*
X439151Y-121859D01*
X439166Y-121910D01*
X439177Y-121969D01*
X439184Y-122027D01*
X439188Y-122089D01*
Y-122114D01*
X439184Y-122132D01*
Y-122151D01*
X439180Y-122176D01*
X439169Y-122238D01*
X439155Y-122307D01*
X439129Y-122383D01*
X439097Y-122460D01*
X439053Y-122536D01*
Y-122540D01*
X439046Y-122544D01*
X439038Y-122555D01*
X439028Y-122569D01*
X438998Y-122606D01*
X438958Y-122653D01*
X438904Y-122700D01*
X438838Y-122755D01*
X438762Y-122802D01*
X438674Y-122846D01*
X438671D01*
X438663Y-122850D01*
X438649Y-122857D01*
X438631Y-122864D01*
X438605Y-122871D01*
X438573Y-122882D01*
X438536Y-122889D01*
X438496Y-122900D01*
X438449Y-122911D01*
X438394Y-122922D01*
X438336Y-122930D01*
X438274Y-122937D01*
X438205Y-122944D01*
X438132Y-122951D01*
X438052Y-122955D01*
X437968D01*
X437965D01*
X437946D01*
X437921D01*
X437888D01*
X437848Y-122951D01*
X437801D01*
X437746Y-122948D01*
X437692Y-122941D01*
X437568Y-122930D01*
X437437Y-122911D01*
X437313Y-122886D01*
X437251Y-122868D01*
X437196Y-122850D01*
X437193D01*
X437186Y-122846D01*
X437171Y-122839D01*
X437149Y-122831D01*
X437127Y-122820D01*
X437098Y-122806D01*
X437036Y-122769D01*
X436967Y-122726D01*
X436894Y-122675D01*
X436825Y-122609D01*
X436763Y-122536D01*
Y-122533D01*
X436756Y-122526D01*
X436749Y-122515D01*
X436741Y-122500D01*
X436731Y-122478D01*
X436716Y-122456D01*
X436701Y-122427D01*
X436691Y-122398D01*
X436661Y-122329D01*
X436636Y-122245D01*
X436621Y-122154D01*
X436614Y-122052D01*
Y-122023D01*
X436618Y-122005D01*
Y-121979D01*
X436621Y-121950D01*
X436636Y-121881D01*
X436654Y-121805D01*
X436683Y-121725D01*
X436723Y-121645D01*
X436749Y-121605D01*
X436778Y-121568D01*
X436782Y-121565D01*
X436785Y-121561D01*
X436796Y-121550D01*
X436807Y-121539D01*
X436825Y-121525D01*
X436847Y-121506D01*
X436898Y-121470D01*
X436964Y-121433D01*
X437044Y-121397D01*
X437135Y-121368D01*
X437240Y-121346D01*
X437266Y-121645D01*
X437262D01*
X437255Y-121648D01*
X437248D01*
X437233Y-121652D01*
X437193Y-121663D01*
X437149Y-121677D01*
X437098Y-121696D01*
X437047Y-121721D01*
X437000Y-121750D01*
X436960Y-121787D01*
X436956Y-121790D01*
X436945Y-121805D01*
X436931Y-121830D01*
X436916Y-121859D01*
X436898Y-121899D01*
X436883Y-121947D01*
X436873Y-122001D01*
X436869Y-122060D01*
Y-122085D01*
X436873Y-122110D01*
X436876Y-122143D01*
X436883Y-122183D01*
X436894Y-122223D01*
X436909Y-122267D01*
X436931Y-122307D01*
X436935Y-122311D01*
X436942Y-122325D01*
X436956Y-122347D01*
X436978Y-122369D01*
X437004Y-122398D01*
X437033Y-122427D01*
X437066Y-122456D01*
X437106Y-122485D01*
X437109Y-122489D01*
X437127Y-122496D01*
X437153Y-122511D01*
X437186Y-122526D01*
X437229Y-122544D01*
X437280Y-122562D01*
X437338Y-122580D01*
X437404Y-122598D01*
X437408D01*
X437411Y-122602D01*
X437422D01*
X437437Y-122606D01*
X437473Y-122613D01*
X437521Y-122624D01*
X437579Y-122631D01*
X437641Y-122638D01*
X437710Y-122642D01*
X437783Y-122646D01*
X437786D01*
X437797D01*
X437815D01*
X437844D01*
X437837Y-122642D01*
X437819Y-122627D01*
X437793Y-122606D01*
X437757Y-122580D01*
X437721Y-122544D01*
X437681Y-122500D01*
X437641Y-122449D01*
X437604Y-122391D01*
X437601Y-122383D01*
X437590Y-122362D01*
X437575Y-122329D01*
X437561Y-122289D01*
X437542Y-122234D01*
X437528Y-122176D01*
X437517Y-122110D01*
X437513Y-122041D01*
Y-122012D01*
X437517Y-121990D01*
X437521Y-121961D01*
X437524Y-121932D01*
X437531Y-121896D01*
X437542Y-121859D01*
X437568Y-121776D01*
X437586Y-121732D01*
X437608Y-121688D01*
X437633Y-121641D01*
X437666Y-121597D01*
X437699Y-121554D01*
X437739Y-121514D01*
X437743Y-121510D01*
X437750Y-121503D01*
X437761Y-121495D01*
X437779Y-121481D01*
X437804Y-121463D01*
X437830Y-121444D01*
X437863Y-121426D01*
X437899Y-121408D01*
X437939Y-121386D01*
X437983Y-121368D01*
X438034Y-121350D01*
X438085Y-121332D01*
X438143Y-121317D01*
X438205Y-121310D01*
X438267Y-121302D01*
X438336Y-121299D01*
X438340D01*
X438354D01*
X438372D01*
X438398Y-121302D01*
D02*
G37*
G36*
X439177Y-124305D02*
Y-124557D01*
X437546D01*
Y-124899D01*
X437262D01*
Y-124557D01*
X436658D01*
Y-124247D01*
X437262D01*
Y-123152D01*
X437546D01*
X439177Y-124305D01*
D02*
G37*
G36*
X548886Y-279925D02*
X548919D01*
X548959Y-279928D01*
X549003Y-279936D01*
X549054Y-279943D01*
X549159Y-279961D01*
X549268Y-279990D01*
X549378Y-280030D01*
X549429Y-280056D01*
X549479Y-280085D01*
X549483Y-280089D01*
X549490Y-280092D01*
X549505Y-280103D01*
X549520Y-280118D01*
X549541Y-280132D01*
X549567Y-280154D01*
X549596Y-280180D01*
X549625Y-280209D01*
X549654Y-280242D01*
X549687Y-280274D01*
X549753Y-280358D01*
X549814Y-280456D01*
X549869Y-280566D01*
Y-280569D01*
X549876Y-280580D01*
X549880Y-280598D01*
X549891Y-280620D01*
X549898Y-280649D01*
X549909Y-280686D01*
X549924Y-280726D01*
X549934Y-280769D01*
X549945Y-280817D01*
X549960Y-280871D01*
X549978Y-280984D01*
X549993Y-281112D01*
X550000Y-281242D01*
Y-281246D01*
Y-281261D01*
Y-281283D01*
X549996Y-281308D01*
Y-281345D01*
X549993Y-281381D01*
X549989Y-281428D01*
X549982Y-281475D01*
X549964Y-281581D01*
X549938Y-281698D01*
X549902Y-281814D01*
X549851Y-281927D01*
X549847Y-281930D01*
X549844Y-281941D01*
X549836Y-281956D01*
X549822Y-281974D01*
X549807Y-282000D01*
X549789Y-282029D01*
X549742Y-282094D01*
X549680Y-282167D01*
X549607Y-282240D01*
X549523Y-282313D01*
X549425Y-282375D01*
X549421Y-282378D01*
X549410Y-282382D01*
X549396Y-282389D01*
X549378Y-282400D01*
X549348Y-282411D01*
X549319Y-282422D01*
X549283Y-282436D01*
X549243Y-282451D01*
X549199Y-282466D01*
X549152Y-282480D01*
X549050Y-282502D01*
X548934Y-282520D01*
X548813Y-282527D01*
X548777D01*
X548751Y-282524D01*
X548719Y-282520D01*
X548679Y-282517D01*
X548639Y-282513D01*
X548591Y-282502D01*
X548493Y-282480D01*
X548384Y-282447D01*
X548329Y-282426D01*
X548278Y-282400D01*
X548227Y-282367D01*
X548176Y-282334D01*
X548173Y-282331D01*
X548166Y-282327D01*
X548151Y-282316D01*
X548133Y-282298D01*
X548114Y-282280D01*
X548089Y-282255D01*
X548064Y-282225D01*
X548034Y-282196D01*
X548005Y-282160D01*
X547976Y-282116D01*
X547943Y-282072D01*
X547914Y-282025D01*
X547889Y-281971D01*
X547860Y-281916D01*
X547838Y-281858D01*
X547816Y-281792D01*
X548144Y-281716D01*
Y-281719D01*
X548147Y-281727D01*
X548155Y-281741D01*
X548162Y-281759D01*
X548169Y-281781D01*
X548180Y-281810D01*
X548209Y-281869D01*
X548246Y-281934D01*
X548289Y-282000D01*
X548344Y-282062D01*
X548402Y-282116D01*
X548409Y-282123D01*
X548431Y-282138D01*
X548468Y-282156D01*
X548515Y-282182D01*
X548577Y-282204D01*
X548646Y-282225D01*
X548730Y-282240D01*
X548821Y-282244D01*
X548850D01*
X548868Y-282240D01*
X548893D01*
X548923Y-282236D01*
X548992Y-282225D01*
X549068Y-282211D01*
X549148Y-282185D01*
X549232Y-282149D01*
X549308Y-282102D01*
X549312D01*
X549316Y-282094D01*
X549341Y-282076D01*
X549374Y-282047D01*
X549414Y-282003D01*
X549461Y-281949D01*
X549505Y-281887D01*
X549545Y-281810D01*
X549581Y-281727D01*
Y-281723D01*
X549585Y-281716D01*
X549589Y-281705D01*
X549592Y-281687D01*
X549600Y-281665D01*
X549607Y-281639D01*
X549618Y-281577D01*
X549632Y-281505D01*
X549647Y-281424D01*
X549654Y-281337D01*
X549658Y-281242D01*
Y-281239D01*
Y-281228D01*
Y-281210D01*
Y-281188D01*
X549654Y-281163D01*
Y-281130D01*
X549651Y-281093D01*
X549647Y-281053D01*
X549636Y-280966D01*
X549618Y-280871D01*
X549596Y-280777D01*
X549567Y-280682D01*
Y-280678D01*
X549563Y-280671D01*
X549556Y-280660D01*
X549549Y-280642D01*
X549527Y-280598D01*
X549494Y-280547D01*
X549454Y-280489D01*
X549403Y-280427D01*
X549345Y-280373D01*
X549276Y-280322D01*
X549272D01*
X549265Y-280318D01*
X549254Y-280311D01*
X549239Y-280303D01*
X549221Y-280296D01*
X549199Y-280285D01*
X549148Y-280263D01*
X549083Y-280242D01*
X549010Y-280223D01*
X548930Y-280209D01*
X548846Y-280205D01*
X548821D01*
X548799Y-280209D01*
X548773D01*
X548748Y-280212D01*
X548682Y-280227D01*
X548606Y-280245D01*
X548529Y-280274D01*
X548449Y-280314D01*
X548409Y-280336D01*
X548373Y-280365D01*
X548369Y-280369D01*
X548366Y-280373D01*
X548355Y-280383D01*
X548340Y-280394D01*
X548326Y-280413D01*
X548307Y-280434D01*
X548286Y-280456D01*
X548267Y-280485D01*
X548246Y-280518D01*
X548220Y-280555D01*
X548198Y-280591D01*
X548176Y-280635D01*
X548158Y-280682D01*
X548140Y-280733D01*
X548122Y-280788D01*
X548107Y-280846D01*
X547772Y-280762D01*
Y-280758D01*
X547776Y-280744D01*
X547783Y-280722D01*
X547794Y-280693D01*
X547805Y-280660D01*
X547820Y-280620D01*
X547838Y-280576D01*
X547860Y-280529D01*
X547911Y-280427D01*
X547976Y-280325D01*
X548016Y-280274D01*
X548056Y-280223D01*
X548100Y-280180D01*
X548151Y-280136D01*
X548155Y-280132D01*
X548162Y-280125D01*
X548180Y-280118D01*
X548198Y-280103D01*
X548227Y-280085D01*
X548256Y-280067D01*
X548296Y-280049D01*
X548337Y-280030D01*
X548384Y-280009D01*
X548435Y-279990D01*
X548490Y-279972D01*
X548548Y-279954D01*
X548610Y-279939D01*
X548675Y-279932D01*
X548744Y-279925D01*
X548817Y-279921D01*
X548857D01*
X548886Y-279925D01*
D02*
G37*
G36*
X547114Y-279969D02*
Y-279979D01*
Y-279994D01*
X547110Y-280016D01*
Y-280045D01*
X547106Y-280081D01*
X547103Y-280121D01*
X547099Y-280165D01*
X547092Y-280216D01*
X547084Y-280267D01*
X547074Y-280329D01*
X547063Y-280391D01*
X547052Y-280456D01*
X547037Y-280529D01*
X547001Y-280678D01*
Y-280682D01*
X546997Y-280697D01*
X546990Y-280718D01*
X546979Y-280751D01*
X546968Y-280788D01*
X546953Y-280831D01*
X546939Y-280882D01*
X546917Y-280937D01*
X546895Y-280999D01*
X546873Y-281061D01*
X546819Y-281199D01*
X546753Y-281345D01*
X546680Y-281490D01*
X546677Y-281494D01*
X546669Y-281508D01*
X546659Y-281526D01*
X546644Y-281556D01*
X546626Y-281588D01*
X546600Y-281628D01*
X546575Y-281672D01*
X546546Y-281719D01*
X546477Y-281825D01*
X546404Y-281934D01*
X546320Y-282047D01*
X546233Y-282153D01*
X547467D01*
Y-282451D01*
X545836D01*
Y-282207D01*
X545840Y-282204D01*
X545847Y-282196D01*
X545861Y-282182D01*
X545876Y-282160D01*
X545898Y-282134D01*
X545927Y-282105D01*
X545956Y-282069D01*
X545989Y-282025D01*
X546022Y-281981D01*
X546062Y-281930D01*
X546102Y-281872D01*
X546142Y-281814D01*
X546185Y-281749D01*
X546229Y-281679D01*
X546273Y-281603D01*
X546316Y-281526D01*
X546320Y-281523D01*
X546327Y-281508D01*
X546338Y-281486D01*
X546356Y-281454D01*
X546375Y-281414D01*
X546396Y-281370D01*
X546422Y-281319D01*
X546447Y-281261D01*
X546477Y-281195D01*
X546509Y-281130D01*
X546538Y-281057D01*
X546567Y-280980D01*
X546626Y-280824D01*
X546680Y-280657D01*
Y-280653D01*
X546684Y-280642D01*
X546688Y-280624D01*
X546695Y-280602D01*
X546702Y-280573D01*
X546709Y-280536D01*
X546720Y-280496D01*
X546728Y-280453D01*
X546739Y-280402D01*
X546749Y-280347D01*
X546768Y-280231D01*
X546786Y-280103D01*
X546797Y-279965D01*
X547114D01*
Y-279969D01*
D02*
G37*
G36*
X544675Y-281934D02*
X544678Y-281930D01*
X544697Y-281916D01*
X544718Y-281894D01*
X544755Y-281869D01*
X544795Y-281836D01*
X544846Y-281800D01*
X544904Y-281759D01*
X544970Y-281719D01*
X544973D01*
X544977Y-281716D01*
X544999Y-281701D01*
X545035Y-281683D01*
X545079Y-281661D01*
X545130Y-281636D01*
X545184Y-281610D01*
X545239Y-281585D01*
X545294Y-281563D01*
Y-281861D01*
X545290D01*
X545283Y-281869D01*
X545268Y-281872D01*
X545250Y-281883D01*
X545228Y-281894D01*
X545202Y-281909D01*
X545141Y-281945D01*
X545068Y-281985D01*
X544995Y-282036D01*
X544919Y-282094D01*
X544842Y-282156D01*
X544838Y-282160D01*
X544835Y-282164D01*
X544824Y-282174D01*
X544809Y-282185D01*
X544777Y-282222D01*
X544733Y-282265D01*
X544689Y-282316D01*
X544642Y-282375D01*
X544602Y-282433D01*
X544565Y-282495D01*
X544365D01*
Y-279965D01*
X544675D01*
Y-281934D01*
D02*
G37*
G36*
X619546Y-215748D02*
X619236D01*
Y-213779D01*
X619233Y-213783D01*
X619214Y-213797D01*
X619193Y-213819D01*
X619156Y-213844D01*
X619116Y-213877D01*
X619065Y-213913D01*
X619007Y-213954D01*
X618941Y-213994D01*
X618938D01*
X618934Y-213997D01*
X618912Y-214012D01*
X618876Y-214030D01*
X618832Y-214052D01*
X618781Y-214077D01*
X618727Y-214103D01*
X618672Y-214128D01*
X618617Y-214150D01*
Y-213852D01*
X618621D01*
X618628Y-213844D01*
X618643Y-213841D01*
X618661Y-213830D01*
X618683Y-213819D01*
X618709Y-213804D01*
X618770Y-213768D01*
X618843Y-213728D01*
X618916Y-213677D01*
X618992Y-213619D01*
X619069Y-213557D01*
X619072Y-213553D01*
X619076Y-213549D01*
X619087Y-213539D01*
X619102Y-213528D01*
X619134Y-213491D01*
X619178Y-213448D01*
X619222Y-213397D01*
X619269Y-213338D01*
X619309Y-213280D01*
X619346Y-213218D01*
X619546D01*
Y-215748D01*
D02*
G37*
G36*
X616870Y-215450D02*
X618112D01*
Y-215748D01*
X616535D01*
Y-213229D01*
X616870D01*
Y-215450D01*
D02*
G37*
G36*
X660882Y-183468D02*
X660918D01*
X660955Y-183472D01*
X661002Y-183475D01*
X661049Y-183483D01*
X661155Y-183501D01*
X661271Y-183527D01*
X661388Y-183563D01*
X661501Y-183614D01*
X661504Y-183617D01*
X661515Y-183621D01*
X661530Y-183628D01*
X661548Y-183643D01*
X661574Y-183658D01*
X661603Y-183676D01*
X661668Y-183723D01*
X661741Y-183785D01*
X661814Y-183858D01*
X661887Y-183941D01*
X661948Y-184040D01*
X661952Y-184043D01*
X661956Y-184054D01*
X661963Y-184069D01*
X661974Y-184087D01*
X661985Y-184116D01*
X661996Y-184145D01*
X662010Y-184182D01*
X662025Y-184222D01*
X662040Y-184265D01*
X662054Y-184313D01*
X662076Y-184415D01*
X662094Y-184531D01*
X662101Y-184651D01*
Y-184688D01*
X662098Y-184713D01*
X662094Y-184746D01*
X662090Y-184786D01*
X662087Y-184826D01*
X662076Y-184873D01*
X662054Y-184972D01*
X662021Y-185081D01*
X661999Y-185135D01*
X661974Y-185186D01*
X661941Y-185237D01*
X661908Y-185288D01*
X661905Y-185292D01*
X661901Y-185299D01*
X661890Y-185314D01*
X661872Y-185332D01*
X661854Y-185350D01*
X661828Y-185376D01*
X661799Y-185401D01*
X661770Y-185430D01*
X661734Y-185459D01*
X661690Y-185488D01*
X661646Y-185521D01*
X661599Y-185550D01*
X661544Y-185576D01*
X661490Y-185605D01*
X661432Y-185627D01*
X661366Y-185649D01*
X661290Y-185321D01*
X661293D01*
X661301Y-185317D01*
X661315Y-185310D01*
X661333Y-185303D01*
X661355Y-185295D01*
X661384Y-185285D01*
X661443Y-185256D01*
X661508Y-185219D01*
X661574Y-185175D01*
X661635Y-185121D01*
X661690Y-185063D01*
X661697Y-185055D01*
X661712Y-185033D01*
X661730Y-184997D01*
X661756Y-184950D01*
X661777Y-184888D01*
X661799Y-184819D01*
X661814Y-184735D01*
X661817Y-184644D01*
Y-184615D01*
X661814Y-184597D01*
Y-184571D01*
X661810Y-184542D01*
X661799Y-184473D01*
X661785Y-184396D01*
X661759Y-184316D01*
X661723Y-184233D01*
X661676Y-184156D01*
Y-184152D01*
X661668Y-184149D01*
X661650Y-184123D01*
X661621Y-184091D01*
X661577Y-184051D01*
X661523Y-184003D01*
X661461Y-183960D01*
X661384Y-183920D01*
X661301Y-183883D01*
X661297D01*
X661290Y-183879D01*
X661279Y-183876D01*
X661261Y-183872D01*
X661239Y-183865D01*
X661213Y-183858D01*
X661151Y-183847D01*
X661079Y-183832D01*
X660998Y-183818D01*
X660911Y-183810D01*
X660816Y-183807D01*
X660813D01*
X660802D01*
X660784D01*
X660762D01*
X660736Y-183810D01*
X660704D01*
X660667Y-183814D01*
X660627Y-183818D01*
X660540Y-183829D01*
X660445Y-183847D01*
X660351Y-183869D01*
X660256Y-183898D01*
X660252D01*
X660245Y-183901D01*
X660234Y-183909D01*
X660216Y-183916D01*
X660172Y-183938D01*
X660121Y-183971D01*
X660063Y-184011D01*
X660001Y-184062D01*
X659946Y-184120D01*
X659896Y-184189D01*
Y-184193D01*
X659892Y-184200D01*
X659885Y-184211D01*
X659877Y-184225D01*
X659870Y-184244D01*
X659859Y-184265D01*
X659837Y-184316D01*
X659815Y-184382D01*
X659797Y-184455D01*
X659783Y-184535D01*
X659779Y-184618D01*
Y-184644D01*
X659783Y-184666D01*
Y-184691D01*
X659786Y-184717D01*
X659801Y-184782D01*
X659819Y-184859D01*
X659848Y-184935D01*
X659888Y-185015D01*
X659910Y-185055D01*
X659939Y-185092D01*
X659943Y-185095D01*
X659946Y-185099D01*
X659957Y-185110D01*
X659968Y-185124D01*
X659986Y-185139D01*
X660008Y-185157D01*
X660030Y-185179D01*
X660059Y-185197D01*
X660092Y-185219D01*
X660128Y-185245D01*
X660165Y-185266D01*
X660209Y-185288D01*
X660256Y-185306D01*
X660307Y-185325D01*
X660361Y-185343D01*
X660420Y-185357D01*
X660336Y-185692D01*
X660332D01*
X660318Y-185689D01*
X660296Y-185681D01*
X660267Y-185670D01*
X660234Y-185660D01*
X660194Y-185645D01*
X660150Y-185627D01*
X660103Y-185605D01*
X660001Y-185554D01*
X659899Y-185488D01*
X659848Y-185448D01*
X659797Y-185408D01*
X659754Y-185365D01*
X659710Y-185314D01*
X659706Y-185310D01*
X659699Y-185303D01*
X659692Y-185285D01*
X659677Y-185266D01*
X659659Y-185237D01*
X659641Y-185208D01*
X659622Y-185168D01*
X659604Y-185128D01*
X659583Y-185081D01*
X659564Y-185030D01*
X659546Y-184975D01*
X659528Y-184917D01*
X659513Y-184855D01*
X659506Y-184790D01*
X659499Y-184720D01*
X659495Y-184648D01*
Y-184608D01*
X659499Y-184578D01*
Y-184546D01*
X659502Y-184506D01*
X659510Y-184462D01*
X659517Y-184411D01*
X659535Y-184305D01*
X659564Y-184196D01*
X659604Y-184087D01*
X659630Y-184036D01*
X659659Y-183985D01*
X659662Y-183982D01*
X659666Y-183974D01*
X659677Y-183960D01*
X659692Y-183945D01*
X659706Y-183923D01*
X659728Y-183898D01*
X659754Y-183869D01*
X659783Y-183839D01*
X659815Y-183810D01*
X659848Y-183778D01*
X659932Y-183712D01*
X660030Y-183650D01*
X660139Y-183596D01*
X660143D01*
X660154Y-183588D01*
X660172Y-183585D01*
X660194Y-183574D01*
X660223Y-183566D01*
X660259Y-183556D01*
X660299Y-183541D01*
X660343Y-183530D01*
X660391Y-183519D01*
X660445Y-183505D01*
X660558Y-183486D01*
X660685Y-183472D01*
X660816Y-183465D01*
X660820D01*
X660835D01*
X660856D01*
X660882Y-183468D01*
D02*
G37*
G36*
X661435Y-186216D02*
X661443Y-186224D01*
X661446Y-186238D01*
X661457Y-186257D01*
X661468Y-186278D01*
X661482Y-186304D01*
X661519Y-186366D01*
X661559Y-186439D01*
X661610Y-186511D01*
X661668Y-186588D01*
X661730Y-186664D01*
X661734Y-186668D01*
X661737Y-186671D01*
X661748Y-186682D01*
X661759Y-186697D01*
X661796Y-186730D01*
X661839Y-186773D01*
X661890Y-186817D01*
X661948Y-186864D01*
X662007Y-186904D01*
X662069Y-186941D01*
Y-187141D01*
X659539D01*
Y-186832D01*
X661508D01*
X661504Y-186828D01*
X661490Y-186810D01*
X661468Y-186788D01*
X661443Y-186751D01*
X661410Y-186712D01*
X661373Y-186661D01*
X661333Y-186602D01*
X661293Y-186537D01*
Y-186533D01*
X661290Y-186530D01*
X661275Y-186508D01*
X661257Y-186471D01*
X661235Y-186427D01*
X661209Y-186377D01*
X661184Y-186322D01*
X661159Y-186267D01*
X661137Y-186213D01*
X661435D01*
Y-186216D01*
D02*
G37*
G36*
X662058Y-188983D02*
Y-189234D01*
X660427D01*
Y-189576D01*
X660143D01*
Y-189234D01*
X659539D01*
Y-188925D01*
X660143D01*
Y-187829D01*
X660427D01*
X662058Y-188983D01*
D02*
G37*
G36*
X681079Y-179061D02*
X681087Y-179068D01*
X681101Y-179083D01*
X681123Y-179097D01*
X681149Y-179119D01*
X681178Y-179148D01*
X681214Y-179177D01*
X681258Y-179210D01*
X681301Y-179243D01*
X681352Y-179283D01*
X681411Y-179323D01*
X681469Y-179363D01*
X681534Y-179407D01*
X681604Y-179450D01*
X681680Y-179494D01*
X681756Y-179538D01*
X681760Y-179541D01*
X681775Y-179549D01*
X681797Y-179560D01*
X681829Y-179578D01*
X681869Y-179596D01*
X681913Y-179618D01*
X681964Y-179643D01*
X682022Y-179669D01*
X682088Y-179698D01*
X682153Y-179731D01*
X682226Y-179760D01*
X682303Y-179789D01*
X682459Y-179847D01*
X682626Y-179902D01*
X682630D01*
X682641Y-179905D01*
X682659Y-179909D01*
X682681Y-179916D01*
X682710Y-179923D01*
X682747Y-179931D01*
X682787Y-179942D01*
X682830Y-179949D01*
X682881Y-179960D01*
X682936Y-179971D01*
X683052Y-179989D01*
X683180Y-180007D01*
X683318Y-180018D01*
Y-180335D01*
X683314D01*
X683303D01*
X683289D01*
X683267Y-180331D01*
X683238D01*
X683202Y-180327D01*
X683161Y-180324D01*
X683118Y-180320D01*
X683067Y-180313D01*
X683016Y-180306D01*
X682954Y-180295D01*
X682892Y-180284D01*
X682827Y-180273D01*
X682754Y-180258D01*
X682605Y-180222D01*
X682601D01*
X682586Y-180218D01*
X682564Y-180211D01*
X682532Y-180200D01*
X682495Y-180189D01*
X682452Y-180175D01*
X682401Y-180160D01*
X682346Y-180138D01*
X682284Y-180116D01*
X682222Y-180095D01*
X682084Y-180040D01*
X681939Y-179974D01*
X681793Y-179902D01*
X681789Y-179898D01*
X681775Y-179891D01*
X681756Y-179880D01*
X681727Y-179865D01*
X681695Y-179847D01*
X681655Y-179822D01*
X681611Y-179796D01*
X681564Y-179767D01*
X681458Y-179698D01*
X681349Y-179625D01*
X681236Y-179541D01*
X681130Y-179454D01*
Y-180688D01*
X680832D01*
Y-179057D01*
X681076D01*
X681079Y-179061D01*
D02*
G37*
G36*
X683318Y-181813D02*
X681349D01*
X681352Y-181816D01*
X681367Y-181834D01*
X681389Y-181856D01*
X681414Y-181893D01*
X681447Y-181933D01*
X681484Y-181984D01*
X681524Y-182042D01*
X681564Y-182107D01*
Y-182111D01*
X681567Y-182115D01*
X681582Y-182137D01*
X681600Y-182173D01*
X681622Y-182217D01*
X681647Y-182268D01*
X681673Y-182322D01*
X681698Y-182377D01*
X681720Y-182431D01*
X681422D01*
Y-182428D01*
X681414Y-182421D01*
X681411Y-182406D01*
X681400Y-182388D01*
X681389Y-182366D01*
X681374Y-182341D01*
X681338Y-182279D01*
X681298Y-182206D01*
X681247Y-182133D01*
X681189Y-182056D01*
X681127Y-181980D01*
X681123Y-181976D01*
X681119Y-181973D01*
X681109Y-181962D01*
X681098Y-181947D01*
X681061Y-181915D01*
X681017Y-181871D01*
X680967Y-181827D01*
X680908Y-181780D01*
X680850Y-181740D01*
X680788Y-181703D01*
Y-181503D01*
X683318D01*
Y-181813D01*
D02*
G37*
G36*
X682539Y-182956D02*
X682561Y-182963D01*
X682590Y-182974D01*
X682623Y-182985D01*
X682663Y-182999D01*
X682706Y-183018D01*
X682754Y-183039D01*
X682856Y-183090D01*
X682958Y-183156D01*
X683009Y-183196D01*
X683060Y-183236D01*
X683103Y-183280D01*
X683147Y-183331D01*
X683151Y-183334D01*
X683158Y-183342D01*
X683165Y-183360D01*
X683180Y-183378D01*
X683198Y-183407D01*
X683216Y-183436D01*
X683234Y-183476D01*
X683252Y-183516D01*
X683274Y-183563D01*
X683292Y-183615D01*
X683311Y-183669D01*
X683329Y-183727D01*
X683344Y-183789D01*
X683351Y-183855D01*
X683358Y-183924D01*
X683362Y-183997D01*
Y-184037D01*
X683358Y-184066D01*
Y-184099D01*
X683354Y-184139D01*
X683347Y-184182D01*
X683340Y-184233D01*
X683322Y-184339D01*
X683292Y-184448D01*
X683252Y-184557D01*
X683227Y-184608D01*
X683198Y-184659D01*
X683194Y-184663D01*
X683191Y-184670D01*
X683180Y-184685D01*
X683165Y-184699D01*
X683151Y-184721D01*
X683129Y-184747D01*
X683103Y-184776D01*
X683074Y-184805D01*
X683041Y-184834D01*
X683009Y-184867D01*
X682925Y-184932D01*
X682827Y-184994D01*
X682717Y-185049D01*
X682714D01*
X682703Y-185056D01*
X682685Y-185059D01*
X682663Y-185071D01*
X682634Y-185078D01*
X682597Y-185089D01*
X682557Y-185103D01*
X682514Y-185114D01*
X682466Y-185125D01*
X682412Y-185140D01*
X682299Y-185158D01*
X682171Y-185172D01*
X682040Y-185180D01*
X682037D01*
X682022D01*
X682000D01*
X681975Y-185176D01*
X681939D01*
X681902Y-185172D01*
X681855Y-185169D01*
X681807Y-185161D01*
X681702Y-185143D01*
X681585Y-185118D01*
X681469Y-185081D01*
X681356Y-185030D01*
X681352Y-185027D01*
X681342Y-185023D01*
X681327Y-185016D01*
X681309Y-185001D01*
X681283Y-184987D01*
X681254Y-184968D01*
X681189Y-184921D01*
X681116Y-184859D01*
X681043Y-184786D01*
X680970Y-184703D01*
X680908Y-184605D01*
X680905Y-184601D01*
X680901Y-184590D01*
X680894Y-184575D01*
X680883Y-184557D01*
X680872Y-184528D01*
X680861Y-184499D01*
X680847Y-184463D01*
X680832Y-184423D01*
X680817Y-184379D01*
X680803Y-184332D01*
X680781Y-184230D01*
X680763Y-184113D01*
X680756Y-183993D01*
Y-183957D01*
X680759Y-183931D01*
X680763Y-183898D01*
X680766Y-183858D01*
X680770Y-183818D01*
X680781Y-183771D01*
X680803Y-183673D01*
X680835Y-183563D01*
X680857Y-183509D01*
X680883Y-183458D01*
X680916Y-183407D01*
X680948Y-183356D01*
X680952Y-183352D01*
X680956Y-183345D01*
X680967Y-183331D01*
X680985Y-183312D01*
X681003Y-183294D01*
X681029Y-183269D01*
X681058Y-183243D01*
X681087Y-183214D01*
X681123Y-183185D01*
X681167Y-183156D01*
X681211Y-183123D01*
X681258Y-183094D01*
X681312Y-183069D01*
X681367Y-183039D01*
X681425Y-183018D01*
X681491Y-182996D01*
X681567Y-183323D01*
X681564D01*
X681556Y-183327D01*
X681542Y-183334D01*
X681524Y-183342D01*
X681502Y-183349D01*
X681472Y-183360D01*
X681414Y-183389D01*
X681349Y-183425D01*
X681283Y-183469D01*
X681221Y-183523D01*
X681167Y-183582D01*
X681159Y-183589D01*
X681145Y-183611D01*
X681127Y-183647D01*
X681101Y-183695D01*
X681079Y-183756D01*
X681058Y-183826D01*
X681043Y-183909D01*
X681039Y-184000D01*
Y-184029D01*
X681043Y-184048D01*
Y-184073D01*
X681047Y-184102D01*
X681058Y-184171D01*
X681072Y-184248D01*
X681098Y-184328D01*
X681134Y-184412D01*
X681181Y-184488D01*
Y-184492D01*
X681189Y-184495D01*
X681207Y-184521D01*
X681236Y-184554D01*
X681280Y-184594D01*
X681334Y-184641D01*
X681396Y-184685D01*
X681472Y-184725D01*
X681556Y-184761D01*
X681560D01*
X681567Y-184765D01*
X681578Y-184768D01*
X681596Y-184772D01*
X681618Y-184779D01*
X681644Y-184786D01*
X681706Y-184798D01*
X681778Y-184812D01*
X681858Y-184827D01*
X681946Y-184834D01*
X682040Y-184837D01*
X682044D01*
X682055D01*
X682073D01*
X682095D01*
X682121Y-184834D01*
X682153D01*
X682190Y-184830D01*
X682230Y-184827D01*
X682317Y-184816D01*
X682412Y-184798D01*
X682506Y-184776D01*
X682601Y-184747D01*
X682605D01*
X682612Y-184743D01*
X682623Y-184736D01*
X682641Y-184728D01*
X682685Y-184706D01*
X682736Y-184674D01*
X682794Y-184634D01*
X682856Y-184583D01*
X682910Y-184525D01*
X682961Y-184455D01*
Y-184452D01*
X682965Y-184444D01*
X682972Y-184433D01*
X682979Y-184419D01*
X682987Y-184401D01*
X682998Y-184379D01*
X683019Y-184328D01*
X683041Y-184262D01*
X683060Y-184190D01*
X683074Y-184109D01*
X683078Y-184026D01*
Y-184000D01*
X683074Y-183978D01*
Y-183953D01*
X683071Y-183928D01*
X683056Y-183862D01*
X683038Y-183785D01*
X683009Y-183709D01*
X682969Y-183629D01*
X682947Y-183589D01*
X682918Y-183553D01*
X682914Y-183549D01*
X682910Y-183545D01*
X682899Y-183534D01*
X682889Y-183520D01*
X682870Y-183505D01*
X682849Y-183487D01*
X682827Y-183465D01*
X682797Y-183447D01*
X682765Y-183425D01*
X682728Y-183400D01*
X682692Y-183378D01*
X682648Y-183356D01*
X682601Y-183338D01*
X682550Y-183320D01*
X682495Y-183301D01*
X682437Y-183287D01*
X682521Y-182952D01*
X682524D01*
X682539Y-182956D01*
D02*
G37*
G36*
X636245Y-233858D02*
X635936D01*
Y-231889D01*
X635932Y-231893D01*
X635914Y-231907D01*
X635892Y-231929D01*
X635856Y-231955D01*
X635815Y-231987D01*
X635765Y-232024D01*
X635706Y-232064D01*
X635641Y-232104D01*
X635637D01*
X635634Y-232107D01*
X635612Y-232122D01*
X635575Y-232140D01*
X635532Y-232162D01*
X635481Y-232188D01*
X635426Y-232213D01*
X635371Y-232239D01*
X635317Y-232260D01*
Y-231962D01*
X635321D01*
X635328Y-231955D01*
X635342Y-231951D01*
X635360Y-231940D01*
X635382Y-231929D01*
X635408Y-231915D01*
X635470Y-231878D01*
X635542Y-231838D01*
X635615Y-231787D01*
X635692Y-231729D01*
X635768Y-231667D01*
X635772Y-231663D01*
X635776Y-231660D01*
X635786Y-231649D01*
X635801Y-231638D01*
X635834Y-231602D01*
X635877Y-231558D01*
X635921Y-231507D01*
X635968Y-231449D01*
X636008Y-231390D01*
X636045Y-231329D01*
X636245D01*
Y-233858D01*
D02*
G37*
G36*
X634017Y-231332D02*
X634047Y-231336D01*
X634083Y-231339D01*
X634123Y-231347D01*
X634163Y-231354D01*
X634258Y-231380D01*
X634352Y-231416D01*
X634400Y-231438D01*
X634447Y-231463D01*
X634491Y-231496D01*
X634531Y-231532D01*
X634534Y-231536D01*
X634542Y-231540D01*
X634549Y-231554D01*
X634563Y-231569D01*
X634582Y-231587D01*
X634600Y-231612D01*
X634618Y-231638D01*
X634640Y-231671D01*
X634676Y-231740D01*
X634713Y-231827D01*
X634727Y-231871D01*
X634734Y-231922D01*
X634742Y-231973D01*
X634745Y-232027D01*
Y-232035D01*
Y-232053D01*
X634742Y-232082D01*
X634738Y-232122D01*
X634731Y-232166D01*
X634716Y-232217D01*
X634702Y-232271D01*
X634680Y-232326D01*
X634676Y-232333D01*
X634669Y-232351D01*
X634654Y-232381D01*
X634632Y-232420D01*
X634603Y-232464D01*
X634567Y-232519D01*
X634523Y-232573D01*
X634472Y-232635D01*
X634465Y-232643D01*
X634447Y-232664D01*
X634429Y-232683D01*
X634410Y-232701D01*
X634389Y-232723D01*
X634360Y-232752D01*
X634330Y-232781D01*
X634294Y-232814D01*
X634258Y-232850D01*
X634214Y-232890D01*
X634167Y-232930D01*
X634116Y-232977D01*
X634057Y-233025D01*
X633999Y-233076D01*
X633995Y-233079D01*
X633988Y-233087D01*
X633974Y-233098D01*
X633955Y-233112D01*
X633934Y-233134D01*
X633908Y-233156D01*
X633850Y-233203D01*
X633788Y-233258D01*
X633730Y-233312D01*
X633679Y-233360D01*
X633657Y-233378D01*
X633639Y-233396D01*
X633635Y-233400D01*
X633624Y-233411D01*
X633610Y-233425D01*
X633592Y-233447D01*
X633573Y-233472D01*
X633552Y-233498D01*
X633508Y-233560D01*
X634749D01*
Y-233858D01*
X633078D01*
Y-233855D01*
Y-233840D01*
Y-233818D01*
X633082Y-233789D01*
X633085Y-233756D01*
X633093Y-233720D01*
X633100Y-233684D01*
X633115Y-233644D01*
Y-233640D01*
X633118Y-233636D01*
X633126Y-233614D01*
X633140Y-233582D01*
X633162Y-233538D01*
X633191Y-233487D01*
X633227Y-233429D01*
X633267Y-233371D01*
X633319Y-233309D01*
Y-233305D01*
X633326Y-233301D01*
X633344Y-233280D01*
X633377Y-233247D01*
X633424Y-233200D01*
X633479Y-233145D01*
X633548Y-233079D01*
X633632Y-233007D01*
X633722Y-232930D01*
X633726Y-232927D01*
X633741Y-232916D01*
X633763Y-232897D01*
X633788Y-232875D01*
X633821Y-232846D01*
X633861Y-232814D01*
X633901Y-232777D01*
X633948Y-232737D01*
X634039Y-232650D01*
X634130Y-232562D01*
X634174Y-232519D01*
X634214Y-232475D01*
X634250Y-232435D01*
X634279Y-232395D01*
Y-232391D01*
X634287Y-232388D01*
X634294Y-232377D01*
X634301Y-232362D01*
X634327Y-232322D01*
X634356Y-232275D01*
X634381Y-232217D01*
X634407Y-232155D01*
X634421Y-232086D01*
X634429Y-232020D01*
Y-232016D01*
Y-232013D01*
X634425Y-231991D01*
X634421Y-231955D01*
X634410Y-231915D01*
X634396Y-231864D01*
X634370Y-231813D01*
X634338Y-231762D01*
X634294Y-231711D01*
X634287Y-231703D01*
X634269Y-231689D01*
X634243Y-231671D01*
X634203Y-231645D01*
X634152Y-231623D01*
X634094Y-231602D01*
X634025Y-231587D01*
X633948Y-231583D01*
X633926D01*
X633912Y-231587D01*
X633868Y-231591D01*
X633817Y-231602D01*
X633763Y-231616D01*
X633701Y-231642D01*
X633642Y-231674D01*
X633588Y-231718D01*
X633581Y-231725D01*
X633566Y-231744D01*
X633544Y-231773D01*
X633522Y-231816D01*
X633497Y-231867D01*
X633475Y-231933D01*
X633461Y-232006D01*
X633453Y-232089D01*
X633137Y-232056D01*
Y-232053D01*
X633140Y-232042D01*
Y-232024D01*
X633144Y-231998D01*
X633151Y-231969D01*
X633158Y-231936D01*
X633169Y-231896D01*
X633180Y-231856D01*
X633209Y-231769D01*
X633253Y-231682D01*
X633278Y-231638D01*
X633311Y-231594D01*
X633344Y-231554D01*
X633380Y-231518D01*
X633384Y-231514D01*
X633391Y-231510D01*
X633402Y-231500D01*
X633420Y-231489D01*
X633442Y-231474D01*
X633468Y-231460D01*
X633497Y-231441D01*
X633533Y-231423D01*
X633573Y-231405D01*
X633617Y-231387D01*
X633664Y-231372D01*
X633715Y-231358D01*
X633770Y-231347D01*
X633828Y-231336D01*
X633890Y-231332D01*
X633955Y-231329D01*
X633992D01*
X634017Y-231332D01*
D02*
G37*
G36*
X631742Y-231343D02*
X631815Y-231347D01*
X631888Y-231354D01*
X631961Y-231365D01*
X632023Y-231376D01*
X632026D01*
X632034Y-231380D01*
X632045D01*
X632059Y-231387D01*
X632099Y-231398D01*
X632150Y-231416D01*
X632208Y-231441D01*
X632270Y-231474D01*
X632332Y-231510D01*
X632390Y-231558D01*
X632394Y-231561D01*
X632398Y-231565D01*
X632409Y-231576D01*
X632423Y-231587D01*
X632459Y-231623D01*
X632503Y-231674D01*
X632550Y-231736D01*
X632601Y-231809D01*
X632649Y-231893D01*
X632689Y-231987D01*
Y-231991D01*
X632692Y-231998D01*
X632700Y-232013D01*
X632703Y-232035D01*
X632714Y-232060D01*
X632722Y-232089D01*
X632729Y-232122D01*
X632740Y-232162D01*
X632751Y-232202D01*
X632758Y-232249D01*
X632776Y-232351D01*
X632787Y-232464D01*
X632791Y-232588D01*
Y-232592D01*
Y-232599D01*
Y-232617D01*
Y-232635D01*
X632787Y-232661D01*
Y-232690D01*
X632783Y-232759D01*
X632772Y-232839D01*
X632762Y-232923D01*
X632743Y-233010D01*
X632722Y-233098D01*
Y-233101D01*
X632718Y-233108D01*
X632714Y-233119D01*
X632711Y-233134D01*
X632696Y-233174D01*
X632674Y-233225D01*
X632652Y-233283D01*
X632623Y-233341D01*
X632587Y-233403D01*
X632550Y-233462D01*
X632547Y-233469D01*
X632532Y-233487D01*
X632510Y-233512D01*
X632481Y-233545D01*
X632448Y-233582D01*
X632409Y-233618D01*
X632369Y-233658D01*
X632321Y-233691D01*
X632314Y-233695D01*
X632299Y-233705D01*
X632274Y-233720D01*
X632237Y-233738D01*
X632194Y-233760D01*
X632143Y-233778D01*
X632085Y-233800D01*
X632019Y-233818D01*
X632012D01*
X632001Y-233822D01*
X631990Y-233826D01*
X631953Y-233829D01*
X631903Y-233837D01*
X631844Y-233844D01*
X631775Y-233851D01*
X631699Y-233855D01*
X631615Y-233858D01*
X630709D01*
Y-231339D01*
X631677D01*
X631742Y-231343D01*
D02*
G37*
G36*
X651781Y-224807D02*
X651817D01*
X651853Y-224810D01*
X651901Y-224814D01*
X651948Y-224821D01*
X652053Y-224839D01*
X652170Y-224865D01*
X652286Y-224901D01*
X652399Y-224952D01*
X652403Y-224956D01*
X652414Y-224960D01*
X652428Y-224967D01*
X652447Y-224981D01*
X652472Y-224996D01*
X652501Y-225014D01*
X652567Y-225061D01*
X652639Y-225123D01*
X652712Y-225196D01*
X652785Y-225280D01*
X652847Y-225378D01*
X652851Y-225382D01*
X652854Y-225393D01*
X652862Y-225407D01*
X652873Y-225426D01*
X652883Y-225455D01*
X652894Y-225484D01*
X652909Y-225520D01*
X652923Y-225560D01*
X652938Y-225604D01*
X652953Y-225651D01*
X652974Y-225753D01*
X652993Y-225870D01*
X653000Y-225990D01*
Y-226026D01*
X652996Y-226052D01*
X652993Y-226084D01*
X652989Y-226124D01*
X652985Y-226165D01*
X652974Y-226212D01*
X652953Y-226310D01*
X652920Y-226419D01*
X652898Y-226474D01*
X652873Y-226525D01*
X652840Y-226576D01*
X652807Y-226627D01*
X652803Y-226630D01*
X652800Y-226638D01*
X652789Y-226652D01*
X652771Y-226670D01*
X652752Y-226689D01*
X652727Y-226714D01*
X652698Y-226740D01*
X652669Y-226769D01*
X652632Y-226798D01*
X652589Y-226827D01*
X652545Y-226860D01*
X652498Y-226889D01*
X652443Y-226914D01*
X652388Y-226943D01*
X652330Y-226965D01*
X652265Y-226987D01*
X652188Y-226659D01*
X652192D01*
X652199Y-226656D01*
X652214Y-226649D01*
X652232Y-226641D01*
X652254Y-226634D01*
X652283Y-226623D01*
X652341Y-226594D01*
X652407Y-226558D01*
X652472Y-226514D01*
X652534Y-226459D01*
X652589Y-226401D01*
X652596Y-226394D01*
X652610Y-226372D01*
X652629Y-226336D01*
X652654Y-226288D01*
X652676Y-226226D01*
X652698Y-226157D01*
X652712Y-226074D01*
X652716Y-225982D01*
Y-225953D01*
X652712Y-225935D01*
Y-225910D01*
X652709Y-225881D01*
X652698Y-225811D01*
X652683Y-225735D01*
X652658Y-225655D01*
X652621Y-225571D01*
X652574Y-225495D01*
Y-225491D01*
X652567Y-225487D01*
X652549Y-225462D01*
X652519Y-225429D01*
X652476Y-225389D01*
X652421Y-225342D01*
X652359Y-225298D01*
X652283Y-225258D01*
X652199Y-225222D01*
X652195D01*
X652188Y-225218D01*
X652177Y-225214D01*
X652159Y-225211D01*
X652137Y-225203D01*
X652112Y-225196D01*
X652050Y-225185D01*
X651977Y-225171D01*
X651897Y-225156D01*
X651810Y-225149D01*
X651715Y-225145D01*
X651711D01*
X651700D01*
X651682D01*
X651660D01*
X651635Y-225149D01*
X651602D01*
X651566Y-225152D01*
X651526Y-225156D01*
X651438Y-225167D01*
X651344Y-225185D01*
X651249Y-225207D01*
X651154Y-225236D01*
X651151D01*
X651144Y-225240D01*
X651133Y-225247D01*
X651114Y-225255D01*
X651071Y-225276D01*
X651020Y-225309D01*
X650961Y-225349D01*
X650900Y-225400D01*
X650845Y-225458D01*
X650794Y-225528D01*
Y-225531D01*
X650790Y-225538D01*
X650783Y-225549D01*
X650776Y-225564D01*
X650769Y-225582D01*
X650758Y-225604D01*
X650736Y-225655D01*
X650714Y-225720D01*
X650696Y-225793D01*
X650681Y-225873D01*
X650678Y-225957D01*
Y-225982D01*
X650681Y-226004D01*
Y-226030D01*
X650685Y-226055D01*
X650699Y-226121D01*
X650718Y-226197D01*
X650747Y-226274D01*
X650787Y-226354D01*
X650809Y-226394D01*
X650838Y-226430D01*
X650841Y-226434D01*
X650845Y-226437D01*
X650856Y-226448D01*
X650867Y-226463D01*
X650885Y-226478D01*
X650907Y-226496D01*
X650929Y-226518D01*
X650958Y-226536D01*
X650991Y-226558D01*
X651027Y-226583D01*
X651063Y-226605D01*
X651107Y-226627D01*
X651154Y-226645D01*
X651205Y-226663D01*
X651260Y-226681D01*
X651318Y-226696D01*
X651234Y-227031D01*
X651231D01*
X651216Y-227027D01*
X651194Y-227020D01*
X651165Y-227009D01*
X651133Y-226998D01*
X651092Y-226983D01*
X651049Y-226965D01*
X651002Y-226943D01*
X650900Y-226892D01*
X650798Y-226827D01*
X650747Y-226787D01*
X650696Y-226747D01*
X650652Y-226703D01*
X650608Y-226652D01*
X650605Y-226649D01*
X650597Y-226641D01*
X650590Y-226623D01*
X650576Y-226605D01*
X650557Y-226576D01*
X650539Y-226547D01*
X650521Y-226507D01*
X650503Y-226467D01*
X650481Y-226419D01*
X650463Y-226368D01*
X650445Y-226314D01*
X650426Y-226255D01*
X650412Y-226194D01*
X650405Y-226128D01*
X650397Y-226059D01*
X650394Y-225986D01*
Y-225946D01*
X650397Y-225917D01*
Y-225884D01*
X650401Y-225844D01*
X650408Y-225800D01*
X650416Y-225749D01*
X650434Y-225644D01*
X650463Y-225535D01*
X650503Y-225426D01*
X650528Y-225375D01*
X650557Y-225324D01*
X650561Y-225320D01*
X650565Y-225313D01*
X650576Y-225298D01*
X650590Y-225284D01*
X650605Y-225262D01*
X650627Y-225236D01*
X650652Y-225207D01*
X650681Y-225178D01*
X650714Y-225149D01*
X650747Y-225116D01*
X650831Y-225051D01*
X650929Y-224989D01*
X651038Y-224934D01*
X651042D01*
X651053Y-224927D01*
X651071Y-224923D01*
X651092Y-224912D01*
X651122Y-224905D01*
X651158Y-224894D01*
X651198Y-224880D01*
X651242Y-224869D01*
X651289Y-224858D01*
X651344Y-224843D01*
X651456Y-224825D01*
X651584Y-224810D01*
X651715Y-224803D01*
X651719D01*
X651733D01*
X651755D01*
X651781Y-224807D01*
D02*
G37*
G36*
X650506Y-227275D02*
X650539Y-227278D01*
X650576Y-227286D01*
X650612Y-227293D01*
X650652Y-227307D01*
X650656D01*
X650659Y-227311D01*
X650681Y-227318D01*
X650714Y-227333D01*
X650758Y-227355D01*
X650809Y-227384D01*
X650867Y-227420D01*
X650925Y-227460D01*
X650987Y-227511D01*
X650991D01*
X650994Y-227519D01*
X651016Y-227537D01*
X651049Y-227570D01*
X651096Y-227617D01*
X651151Y-227671D01*
X651216Y-227741D01*
X651289Y-227824D01*
X651366Y-227915D01*
X651369Y-227919D01*
X651380Y-227934D01*
X651398Y-227955D01*
X651420Y-227981D01*
X651449Y-228014D01*
X651482Y-228054D01*
X651518Y-228094D01*
X651558Y-228141D01*
X651646Y-228232D01*
X651733Y-228323D01*
X651777Y-228367D01*
X651821Y-228407D01*
X651861Y-228443D01*
X651901Y-228472D01*
X651904D01*
X651908Y-228480D01*
X651919Y-228487D01*
X651933Y-228494D01*
X651973Y-228520D01*
X652021Y-228549D01*
X652079Y-228574D01*
X652141Y-228600D01*
X652210Y-228614D01*
X652276Y-228622D01*
X652279D01*
X652283D01*
X652305Y-228618D01*
X652341Y-228614D01*
X652381Y-228603D01*
X652432Y-228589D01*
X652483Y-228563D01*
X652534Y-228531D01*
X652585Y-228487D01*
X652592Y-228480D01*
X652607Y-228461D01*
X652625Y-228436D01*
X652650Y-228396D01*
X652672Y-228345D01*
X652694Y-228287D01*
X652709Y-228217D01*
X652712Y-228141D01*
Y-228119D01*
X652709Y-228105D01*
X652705Y-228061D01*
X652694Y-228010D01*
X652680Y-227955D01*
X652654Y-227893D01*
X652621Y-227835D01*
X652578Y-227781D01*
X652570Y-227773D01*
X652552Y-227759D01*
X652523Y-227737D01*
X652479Y-227715D01*
X652428Y-227690D01*
X652363Y-227668D01*
X652290Y-227653D01*
X652206Y-227646D01*
X652239Y-227329D01*
X652243D01*
X652254Y-227333D01*
X652272D01*
X652297Y-227337D01*
X652326Y-227344D01*
X652359Y-227351D01*
X652399Y-227362D01*
X652439Y-227373D01*
X652527Y-227402D01*
X652614Y-227446D01*
X652658Y-227471D01*
X652701Y-227504D01*
X652741Y-227537D01*
X652778Y-227573D01*
X652781Y-227577D01*
X652785Y-227584D01*
X652796Y-227595D01*
X652807Y-227613D01*
X652821Y-227635D01*
X652836Y-227660D01*
X652854Y-227690D01*
X652873Y-227726D01*
X652891Y-227766D01*
X652909Y-227810D01*
X652923Y-227857D01*
X652938Y-227908D01*
X652949Y-227963D01*
X652960Y-228021D01*
X652963Y-228083D01*
X652967Y-228148D01*
Y-228185D01*
X652963Y-228210D01*
X652960Y-228239D01*
X652956Y-228276D01*
X652949Y-228316D01*
X652942Y-228356D01*
X652916Y-228450D01*
X652880Y-228545D01*
X652858Y-228592D01*
X652832Y-228640D01*
X652800Y-228683D01*
X652763Y-228723D01*
X652760Y-228727D01*
X652756Y-228734D01*
X652741Y-228742D01*
X652727Y-228756D01*
X652709Y-228774D01*
X652683Y-228793D01*
X652658Y-228811D01*
X652625Y-228833D01*
X652556Y-228869D01*
X652468Y-228905D01*
X652425Y-228920D01*
X652374Y-228927D01*
X652323Y-228935D01*
X652268Y-228938D01*
X652261D01*
X652243D01*
X652214Y-228935D01*
X652174Y-228931D01*
X652130Y-228924D01*
X652079Y-228909D01*
X652024Y-228894D01*
X651970Y-228873D01*
X651963Y-228869D01*
X651944Y-228862D01*
X651915Y-228847D01*
X651875Y-228825D01*
X651831Y-228796D01*
X651777Y-228760D01*
X651722Y-228716D01*
X651660Y-228665D01*
X651653Y-228658D01*
X651631Y-228640D01*
X651613Y-228622D01*
X651595Y-228603D01*
X651573Y-228581D01*
X651544Y-228552D01*
X651515Y-228523D01*
X651482Y-228487D01*
X651446Y-228450D01*
X651406Y-228407D01*
X651366Y-228359D01*
X651318Y-228308D01*
X651271Y-228250D01*
X651220Y-228192D01*
X651216Y-228188D01*
X651209Y-228181D01*
X651198Y-228167D01*
X651184Y-228148D01*
X651162Y-228126D01*
X651140Y-228101D01*
X651092Y-228043D01*
X651038Y-227981D01*
X650983Y-227923D01*
X650936Y-227872D01*
X650918Y-227850D01*
X650900Y-227832D01*
X650896Y-227828D01*
X650885Y-227817D01*
X650871Y-227802D01*
X650849Y-227784D01*
X650823Y-227766D01*
X650798Y-227744D01*
X650736Y-227700D01*
Y-228942D01*
X650437D01*
Y-227271D01*
X650441D01*
X650456D01*
X650477D01*
X650506Y-227275D01*
D02*
G37*
G36*
Y-229233D02*
X650539Y-229237D01*
X650576Y-229244D01*
X650612Y-229251D01*
X650652Y-229266D01*
X650656D01*
X650659Y-229269D01*
X650681Y-229277D01*
X650714Y-229291D01*
X650758Y-229313D01*
X650809Y-229342D01*
X650867Y-229379D01*
X650925Y-229419D01*
X650987Y-229470D01*
X650991D01*
X650994Y-229477D01*
X651016Y-229495D01*
X651049Y-229528D01*
X651096Y-229575D01*
X651151Y-229630D01*
X651216Y-229699D01*
X651289Y-229783D01*
X651366Y-229874D01*
X651369Y-229877D01*
X651380Y-229892D01*
X651398Y-229914D01*
X651420Y-229939D01*
X651449Y-229972D01*
X651482Y-230012D01*
X651518Y-230052D01*
X651558Y-230099D01*
X651646Y-230190D01*
X651733Y-230281D01*
X651777Y-230325D01*
X651821Y-230365D01*
X651861Y-230401D01*
X651901Y-230431D01*
X651904D01*
X651908Y-230438D01*
X651919Y-230445D01*
X651933Y-230452D01*
X651973Y-230478D01*
X652021Y-230507D01*
X652079Y-230533D01*
X652141Y-230558D01*
X652210Y-230573D01*
X652276Y-230580D01*
X652279D01*
X652283D01*
X652305Y-230576D01*
X652341Y-230573D01*
X652381Y-230562D01*
X652432Y-230547D01*
X652483Y-230521D01*
X652534Y-230489D01*
X652585Y-230445D01*
X652592Y-230438D01*
X652607Y-230420D01*
X652625Y-230394D01*
X652650Y-230354D01*
X652672Y-230303D01*
X652694Y-230245D01*
X652709Y-230176D01*
X652712Y-230099D01*
Y-230078D01*
X652709Y-230063D01*
X652705Y-230019D01*
X652694Y-229968D01*
X652680Y-229914D01*
X652654Y-229852D01*
X652621Y-229794D01*
X652578Y-229739D01*
X652570Y-229732D01*
X652552Y-229717D01*
X652523Y-229695D01*
X652479Y-229673D01*
X652428Y-229648D01*
X652363Y-229626D01*
X652290Y-229611D01*
X652206Y-229604D01*
X652239Y-229288D01*
X652243D01*
X652254Y-229291D01*
X652272D01*
X652297Y-229295D01*
X652326Y-229302D01*
X652359Y-229309D01*
X652399Y-229320D01*
X652439Y-229331D01*
X652527Y-229360D01*
X652614Y-229404D01*
X652658Y-229430D01*
X652701Y-229462D01*
X652741Y-229495D01*
X652778Y-229532D01*
X652781Y-229535D01*
X652785Y-229542D01*
X652796Y-229553D01*
X652807Y-229572D01*
X652821Y-229593D01*
X652836Y-229619D01*
X652854Y-229648D01*
X652873Y-229684D01*
X652891Y-229724D01*
X652909Y-229768D01*
X652923Y-229815D01*
X652938Y-229866D01*
X652949Y-229921D01*
X652960Y-229979D01*
X652963Y-230041D01*
X652967Y-230107D01*
Y-230143D01*
X652963Y-230169D01*
X652960Y-230198D01*
X652956Y-230234D01*
X652949Y-230274D01*
X652942Y-230314D01*
X652916Y-230409D01*
X652880Y-230503D01*
X652858Y-230551D01*
X652832Y-230598D01*
X652800Y-230642D01*
X652763Y-230682D01*
X652760Y-230685D01*
X652756Y-230693D01*
X652741Y-230700D01*
X652727Y-230715D01*
X652709Y-230733D01*
X652683Y-230751D01*
X652658Y-230769D01*
X652625Y-230791D01*
X652556Y-230827D01*
X652468Y-230864D01*
X652425Y-230878D01*
X652374Y-230886D01*
X652323Y-230893D01*
X652268Y-230896D01*
X652261D01*
X652243D01*
X652214Y-230893D01*
X652174Y-230889D01*
X652130Y-230882D01*
X652079Y-230867D01*
X652024Y-230853D01*
X651970Y-230831D01*
X651963Y-230827D01*
X651944Y-230820D01*
X651915Y-230805D01*
X651875Y-230784D01*
X651831Y-230754D01*
X651777Y-230718D01*
X651722Y-230674D01*
X651660Y-230624D01*
X651653Y-230616D01*
X651631Y-230598D01*
X651613Y-230580D01*
X651595Y-230562D01*
X651573Y-230540D01*
X651544Y-230511D01*
X651515Y-230482D01*
X651482Y-230445D01*
X651446Y-230409D01*
X651406Y-230365D01*
X651366Y-230318D01*
X651318Y-230267D01*
X651271Y-230208D01*
X651220Y-230150D01*
X651216Y-230147D01*
X651209Y-230139D01*
X651198Y-230125D01*
X651184Y-230107D01*
X651162Y-230085D01*
X651140Y-230059D01*
X651092Y-230001D01*
X651038Y-229939D01*
X650983Y-229881D01*
X650936Y-229830D01*
X650918Y-229808D01*
X650900Y-229790D01*
X650896Y-229786D01*
X650885Y-229775D01*
X650871Y-229761D01*
X650849Y-229743D01*
X650823Y-229724D01*
X650798Y-229702D01*
X650736Y-229659D01*
Y-230900D01*
X650437D01*
Y-229229D01*
X650441D01*
X650456D01*
X650477D01*
X650506Y-229233D01*
D02*
G37*
G36*
X560303Y-221657D02*
X560336D01*
X560376Y-221661D01*
X560420Y-221668D01*
X560471Y-221675D01*
X560577Y-221694D01*
X560686Y-221723D01*
X560795Y-221763D01*
X560846Y-221788D01*
X560897Y-221817D01*
X560900Y-221821D01*
X560908Y-221825D01*
X560922Y-221835D01*
X560937Y-221850D01*
X560959Y-221865D01*
X560984Y-221886D01*
X561013Y-221912D01*
X561042Y-221941D01*
X561072Y-221974D01*
X561104Y-222007D01*
X561170Y-222090D01*
X561232Y-222189D01*
X561286Y-222298D01*
Y-222301D01*
X561294Y-222312D01*
X561297Y-222330D01*
X561308Y-222352D01*
X561315Y-222381D01*
X561326Y-222418D01*
X561341Y-222458D01*
X561352Y-222502D01*
X561363Y-222549D01*
X561377Y-222604D01*
X561396Y-222716D01*
X561410Y-222844D01*
X561417Y-222975D01*
Y-222978D01*
Y-222993D01*
Y-223015D01*
X561414Y-223040D01*
Y-223077D01*
X561410Y-223113D01*
X561407Y-223161D01*
X561399Y-223208D01*
X561381Y-223313D01*
X561355Y-223430D01*
X561319Y-223546D01*
X561268Y-223659D01*
X561265Y-223663D01*
X561261Y-223674D01*
X561254Y-223688D01*
X561239Y-223707D01*
X561225Y-223732D01*
X561206Y-223761D01*
X561159Y-223827D01*
X561097Y-223899D01*
X561024Y-223972D01*
X560941Y-224045D01*
X560842Y-224107D01*
X560839Y-224111D01*
X560828Y-224114D01*
X560813Y-224121D01*
X560795Y-224132D01*
X560766Y-224143D01*
X560737Y-224154D01*
X560700Y-224169D01*
X560660Y-224183D01*
X560617Y-224198D01*
X560569Y-224212D01*
X560467Y-224234D01*
X560351Y-224253D01*
X560231Y-224260D01*
X560194D01*
X560169Y-224256D01*
X560136Y-224253D01*
X560096Y-224249D01*
X560056Y-224245D01*
X560009Y-224234D01*
X559910Y-224212D01*
X559801Y-224180D01*
X559747Y-224158D01*
X559696Y-224132D01*
X559645Y-224100D01*
X559594Y-224067D01*
X559590Y-224063D01*
X559583Y-224060D01*
X559568Y-224049D01*
X559550Y-224030D01*
X559532Y-224012D01*
X559506Y-223987D01*
X559481Y-223958D01*
X559452Y-223928D01*
X559423Y-223892D01*
X559394Y-223848D01*
X559361Y-223805D01*
X559332Y-223757D01*
X559306Y-223703D01*
X559277Y-223648D01*
X559255Y-223590D01*
X559233Y-223524D01*
X559561Y-223448D01*
Y-223452D01*
X559565Y-223459D01*
X559572Y-223474D01*
X559579Y-223492D01*
X559586Y-223514D01*
X559597Y-223543D01*
X559626Y-223601D01*
X559663Y-223666D01*
X559707Y-223732D01*
X559761Y-223794D01*
X559819Y-223848D01*
X559827Y-223856D01*
X559848Y-223870D01*
X559885Y-223888D01*
X559932Y-223914D01*
X559994Y-223936D01*
X560063Y-223958D01*
X560147Y-223972D01*
X560238Y-223976D01*
X560267D01*
X560285Y-223972D01*
X560311D01*
X560340Y-223969D01*
X560409Y-223958D01*
X560486Y-223943D01*
X560566Y-223918D01*
X560649Y-223881D01*
X560726Y-223834D01*
X560729D01*
X560733Y-223827D01*
X560759Y-223808D01*
X560791Y-223779D01*
X560831Y-223736D01*
X560879Y-223681D01*
X560922Y-223619D01*
X560962Y-223543D01*
X560999Y-223459D01*
Y-223455D01*
X561002Y-223448D01*
X561006Y-223437D01*
X561010Y-223419D01*
X561017Y-223397D01*
X561024Y-223372D01*
X561035Y-223310D01*
X561050Y-223237D01*
X561064Y-223157D01*
X561072Y-223070D01*
X561075Y-222975D01*
Y-222971D01*
Y-222960D01*
Y-222942D01*
Y-222920D01*
X561072Y-222895D01*
Y-222862D01*
X561068Y-222826D01*
X561064Y-222786D01*
X561053Y-222698D01*
X561035Y-222604D01*
X561013Y-222509D01*
X560984Y-222414D01*
Y-222411D01*
X560981Y-222403D01*
X560973Y-222392D01*
X560966Y-222374D01*
X560944Y-222330D01*
X560911Y-222280D01*
X560871Y-222221D01*
X560820Y-222160D01*
X560762Y-222105D01*
X560693Y-222054D01*
X560689D01*
X560682Y-222050D01*
X560671Y-222043D01*
X560657Y-222036D01*
X560638Y-222028D01*
X560617Y-222018D01*
X560566Y-221996D01*
X560500Y-221974D01*
X560427Y-221956D01*
X560347Y-221941D01*
X560263Y-221937D01*
X560238D01*
X560216Y-221941D01*
X560191D01*
X560165Y-221945D01*
X560100Y-221959D01*
X560023Y-221977D01*
X559947Y-222007D01*
X559867Y-222047D01*
X559827Y-222069D01*
X559790Y-222098D01*
X559787Y-222101D01*
X559783Y-222105D01*
X559772Y-222116D01*
X559758Y-222127D01*
X559743Y-222145D01*
X559725Y-222167D01*
X559703Y-222189D01*
X559685Y-222218D01*
X559663Y-222251D01*
X559637Y-222287D01*
X559616Y-222323D01*
X559594Y-222367D01*
X559576Y-222414D01*
X559557Y-222465D01*
X559539Y-222520D01*
X559525Y-222578D01*
X559190Y-222494D01*
Y-222491D01*
X559193Y-222476D01*
X559201Y-222454D01*
X559211Y-222425D01*
X559223Y-222392D01*
X559237Y-222352D01*
X559255Y-222309D01*
X559277Y-222261D01*
X559328Y-222160D01*
X559394Y-222058D01*
X559434Y-222007D01*
X559474Y-221956D01*
X559517Y-221912D01*
X559568Y-221868D01*
X559572Y-221865D01*
X559579Y-221857D01*
X559597Y-221850D01*
X559616Y-221835D01*
X559645Y-221817D01*
X559674Y-221799D01*
X559714Y-221781D01*
X559754Y-221763D01*
X559801Y-221741D01*
X559852Y-221723D01*
X559907Y-221705D01*
X559965Y-221686D01*
X560027Y-221672D01*
X560092Y-221664D01*
X560162Y-221657D01*
X560234Y-221654D01*
X560274D01*
X560303Y-221657D01*
D02*
G37*
G36*
X557916Y-222301D02*
X559011D01*
Y-222585D01*
X557858Y-224216D01*
X557606D01*
Y-222585D01*
X557264D01*
Y-222301D01*
X557606D01*
Y-221697D01*
X557916D01*
Y-222301D01*
D02*
G37*
G36*
X590225Y-236664D02*
X590258D01*
X590298Y-236668D01*
X590341Y-236675D01*
X590392Y-236682D01*
X590498Y-236701D01*
X590607Y-236730D01*
X590716Y-236770D01*
X590767Y-236795D01*
X590818Y-236824D01*
X590822Y-236828D01*
X590829Y-236832D01*
X590843Y-236842D01*
X590858Y-236857D01*
X590880Y-236872D01*
X590905Y-236893D01*
X590935Y-236919D01*
X590964Y-236948D01*
X590993Y-236981D01*
X591025Y-237014D01*
X591091Y-237097D01*
X591153Y-237196D01*
X591208Y-237305D01*
Y-237308D01*
X591215Y-237319D01*
X591218Y-237337D01*
X591229Y-237359D01*
X591237Y-237388D01*
X591248Y-237425D01*
X591262Y-237465D01*
X591273Y-237509D01*
X591284Y-237556D01*
X591298Y-237611D01*
X591317Y-237723D01*
X591331Y-237851D01*
X591339Y-237982D01*
Y-237985D01*
Y-238000D01*
Y-238022D01*
X591335Y-238047D01*
Y-238084D01*
X591331Y-238120D01*
X591328Y-238167D01*
X591320Y-238215D01*
X591302Y-238320D01*
X591277Y-238437D01*
X591240Y-238553D01*
X591189Y-238666D01*
X591186Y-238670D01*
X591182Y-238681D01*
X591175Y-238695D01*
X591160Y-238713D01*
X591146Y-238739D01*
X591127Y-238768D01*
X591080Y-238834D01*
X591018Y-238906D01*
X590945Y-238979D01*
X590862Y-239052D01*
X590763Y-239114D01*
X590760Y-239118D01*
X590749Y-239121D01*
X590734Y-239128D01*
X590716Y-239139D01*
X590687Y-239150D01*
X590658Y-239161D01*
X590622Y-239176D01*
X590581Y-239190D01*
X590538Y-239205D01*
X590490Y-239219D01*
X590388Y-239241D01*
X590272Y-239259D01*
X590152Y-239267D01*
X590115D01*
X590090Y-239263D01*
X590057Y-239259D01*
X590017Y-239256D01*
X589977Y-239252D01*
X589930Y-239241D01*
X589832Y-239219D01*
X589722Y-239187D01*
X589668Y-239165D01*
X589617Y-239139D01*
X589566Y-239107D01*
X589515Y-239074D01*
X589511Y-239070D01*
X589504Y-239067D01*
X589489Y-239056D01*
X589471Y-239037D01*
X589453Y-239019D01*
X589428Y-238994D01*
X589402Y-238965D01*
X589373Y-238935D01*
X589344Y-238899D01*
X589315Y-238855D01*
X589282Y-238812D01*
X589253Y-238764D01*
X589227Y-238710D01*
X589198Y-238655D01*
X589176Y-238597D01*
X589155Y-238531D01*
X589482Y-238455D01*
Y-238459D01*
X589486Y-238466D01*
X589493Y-238480D01*
X589500Y-238499D01*
X589508Y-238521D01*
X589519Y-238550D01*
X589548Y-238608D01*
X589584Y-238673D01*
X589628Y-238739D01*
X589682Y-238801D01*
X589741Y-238855D01*
X589748Y-238863D01*
X589770Y-238877D01*
X589806Y-238895D01*
X589853Y-238921D01*
X589915Y-238943D01*
X589985Y-238965D01*
X590068Y-238979D01*
X590159Y-238983D01*
X590188D01*
X590206Y-238979D01*
X590232D01*
X590261Y-238976D01*
X590330Y-238965D01*
X590407Y-238950D01*
X590487Y-238925D01*
X590570Y-238888D01*
X590647Y-238841D01*
X590651D01*
X590654Y-238834D01*
X590680Y-238815D01*
X590712Y-238786D01*
X590753Y-238742D01*
X590800Y-238688D01*
X590843Y-238626D01*
X590884Y-238550D01*
X590920Y-238466D01*
Y-238462D01*
X590924Y-238455D01*
X590927Y-238444D01*
X590931Y-238426D01*
X590938Y-238404D01*
X590945Y-238379D01*
X590956Y-238317D01*
X590971Y-238244D01*
X590985Y-238164D01*
X590993Y-238076D01*
X590996Y-237982D01*
Y-237978D01*
Y-237967D01*
Y-237949D01*
Y-237927D01*
X590993Y-237902D01*
Y-237869D01*
X590989Y-237832D01*
X590985Y-237792D01*
X590975Y-237705D01*
X590956Y-237611D01*
X590935Y-237516D01*
X590905Y-237421D01*
Y-237418D01*
X590902Y-237410D01*
X590895Y-237399D01*
X590887Y-237381D01*
X590865Y-237337D01*
X590833Y-237286D01*
X590793Y-237228D01*
X590742Y-237166D01*
X590683Y-237112D01*
X590614Y-237061D01*
X590611D01*
X590603Y-237057D01*
X590592Y-237050D01*
X590578Y-237043D01*
X590560Y-237035D01*
X590538Y-237024D01*
X590487Y-237003D01*
X590421Y-236981D01*
X590348Y-236963D01*
X590268Y-236948D01*
X590185Y-236944D01*
X590159D01*
X590137Y-236948D01*
X590112D01*
X590086Y-236952D01*
X590021Y-236966D01*
X589944Y-236984D01*
X589868Y-237014D01*
X589788Y-237054D01*
X589748Y-237075D01*
X589712Y-237105D01*
X589708Y-237108D01*
X589704Y-237112D01*
X589693Y-237123D01*
X589679Y-237134D01*
X589664Y-237152D01*
X589646Y-237174D01*
X589624Y-237196D01*
X589606Y-237225D01*
X589584Y-237257D01*
X589559Y-237294D01*
X589537Y-237330D01*
X589515Y-237374D01*
X589497Y-237421D01*
X589478Y-237472D01*
X589460Y-237527D01*
X589446Y-237585D01*
X589111Y-237501D01*
Y-237498D01*
X589115Y-237483D01*
X589122Y-237461D01*
X589133Y-237432D01*
X589144Y-237399D01*
X589158Y-237359D01*
X589176Y-237316D01*
X589198Y-237268D01*
X589249Y-237166D01*
X589315Y-237065D01*
X589355Y-237014D01*
X589395Y-236963D01*
X589438Y-236919D01*
X589489Y-236875D01*
X589493Y-236872D01*
X589500Y-236864D01*
X589519Y-236857D01*
X589537Y-236842D01*
X589566Y-236824D01*
X589595Y-236806D01*
X589635Y-236788D01*
X589675Y-236770D01*
X589722Y-236748D01*
X589773Y-236730D01*
X589828Y-236711D01*
X589886Y-236693D01*
X589948Y-236679D01*
X590014Y-236671D01*
X590083Y-236664D01*
X590156Y-236661D01*
X590196D01*
X590225Y-236664D01*
D02*
G37*
G36*
X588452Y-236708D02*
Y-236719D01*
Y-236733D01*
X588448Y-236755D01*
Y-236784D01*
X588445Y-236821D01*
X588441Y-236861D01*
X588438Y-236904D01*
X588430Y-236955D01*
X588423Y-237006D01*
X588412Y-237068D01*
X588401Y-237130D01*
X588390Y-237196D01*
X588376Y-237268D01*
X588339Y-237418D01*
Y-237421D01*
X588336Y-237436D01*
X588328Y-237458D01*
X588317Y-237490D01*
X588306Y-237527D01*
X588292Y-237571D01*
X588277Y-237621D01*
X588256Y-237676D01*
X588234Y-237738D01*
X588212Y-237800D01*
X588157Y-237938D01*
X588092Y-238084D01*
X588019Y-238229D01*
X588015Y-238233D01*
X588008Y-238247D01*
X587997Y-238266D01*
X587983Y-238295D01*
X587964Y-238328D01*
X587939Y-238368D01*
X587913Y-238411D01*
X587884Y-238459D01*
X587815Y-238564D01*
X587742Y-238673D01*
X587659Y-238786D01*
X587571Y-238892D01*
X588805D01*
Y-239190D01*
X587174D01*
Y-238946D01*
X587178Y-238943D01*
X587185Y-238935D01*
X587200Y-238921D01*
X587214Y-238899D01*
X587236Y-238874D01*
X587265Y-238844D01*
X587294Y-238808D01*
X587327Y-238764D01*
X587360Y-238721D01*
X587400Y-238670D01*
X587440Y-238612D01*
X587480Y-238553D01*
X587524Y-238488D01*
X587568Y-238419D01*
X587611Y-238342D01*
X587655Y-238266D01*
X587659Y-238262D01*
X587666Y-238247D01*
X587677Y-238226D01*
X587695Y-238193D01*
X587713Y-238153D01*
X587735Y-238109D01*
X587760Y-238058D01*
X587786Y-238000D01*
X587815Y-237934D01*
X587848Y-237869D01*
X587877Y-237796D01*
X587906Y-237720D01*
X587964Y-237563D01*
X588019Y-237396D01*
Y-237392D01*
X588023Y-237381D01*
X588026Y-237363D01*
X588033Y-237341D01*
X588041Y-237312D01*
X588048Y-237276D01*
X588059Y-237236D01*
X588066Y-237192D01*
X588077Y-237141D01*
X588088Y-237086D01*
X588106Y-236970D01*
X588124Y-236842D01*
X588135Y-236704D01*
X588452D01*
Y-236708D01*
D02*
G37*
G36*
X600599Y-239767D02*
X600636D01*
X600672Y-239771D01*
X600719Y-239775D01*
X600767Y-239782D01*
X600872Y-239800D01*
X600989Y-239826D01*
X601105Y-239862D01*
X601218Y-239913D01*
X601222Y-239917D01*
X601233Y-239920D01*
X601247Y-239928D01*
X601265Y-239942D01*
X601291Y-239957D01*
X601320Y-239975D01*
X601386Y-240022D01*
X601458Y-240084D01*
X601531Y-240157D01*
X601604Y-240241D01*
X601666Y-240339D01*
X601670Y-240342D01*
X601673Y-240353D01*
X601681Y-240368D01*
X601691Y-240386D01*
X601702Y-240415D01*
X601713Y-240444D01*
X601728Y-240481D01*
X601742Y-240521D01*
X601757Y-240564D01*
X601771Y-240612D01*
X601793Y-240714D01*
X601812Y-240830D01*
X601819Y-240950D01*
Y-240987D01*
X601815Y-241012D01*
X601812Y-241045D01*
X601808Y-241085D01*
X601804Y-241125D01*
X601793Y-241172D01*
X601771Y-241271D01*
X601739Y-241380D01*
X601717Y-241435D01*
X601691Y-241486D01*
X601659Y-241536D01*
X601626Y-241587D01*
X601622Y-241591D01*
X601619Y-241598D01*
X601608Y-241613D01*
X601589Y-241631D01*
X601571Y-241649D01*
X601546Y-241675D01*
X601517Y-241700D01*
X601487Y-241729D01*
X601451Y-241758D01*
X601407Y-241788D01*
X601364Y-241820D01*
X601316Y-241849D01*
X601262Y-241875D01*
X601207Y-241904D01*
X601149Y-241926D01*
X601084Y-241948D01*
X601007Y-241620D01*
X601011D01*
X601018Y-241617D01*
X601032Y-241609D01*
X601051Y-241602D01*
X601073Y-241595D01*
X601102Y-241584D01*
X601160Y-241555D01*
X601226Y-241518D01*
X601291Y-241475D01*
X601353Y-241420D01*
X601407Y-241362D01*
X601415Y-241354D01*
X601429Y-241333D01*
X601447Y-241296D01*
X601473Y-241249D01*
X601495Y-241187D01*
X601517Y-241118D01*
X601531Y-241034D01*
X601535Y-240943D01*
Y-240914D01*
X601531Y-240896D01*
Y-240870D01*
X601528Y-240841D01*
X601517Y-240772D01*
X601502Y-240696D01*
X601477Y-240616D01*
X601440Y-240532D01*
X601393Y-240455D01*
Y-240452D01*
X601386Y-240448D01*
X601367Y-240423D01*
X601338Y-240390D01*
X601295Y-240350D01*
X601240Y-240302D01*
X601178Y-240259D01*
X601102Y-240219D01*
X601018Y-240182D01*
X601014D01*
X601007Y-240179D01*
X600996Y-240175D01*
X600978Y-240171D01*
X600956Y-240164D01*
X600931Y-240157D01*
X600869Y-240146D01*
X600796Y-240131D01*
X600716Y-240117D01*
X600629Y-240109D01*
X600534Y-240106D01*
X600530D01*
X600519D01*
X600501D01*
X600479D01*
X600454Y-240109D01*
X600421D01*
X600385Y-240113D01*
X600345Y-240117D01*
X600257Y-240128D01*
X600163Y-240146D01*
X600068Y-240168D01*
X599973Y-240197D01*
X599970D01*
X599962Y-240200D01*
X599952Y-240208D01*
X599933Y-240215D01*
X599890Y-240237D01*
X599839Y-240270D01*
X599780Y-240310D01*
X599719Y-240361D01*
X599664Y-240419D01*
X599613Y-240488D01*
Y-240492D01*
X599609Y-240499D01*
X599602Y-240510D01*
X599595Y-240525D01*
X599587Y-240543D01*
X599577Y-240564D01*
X599555Y-240616D01*
X599533Y-240681D01*
X599515Y-240754D01*
X599500Y-240834D01*
X599497Y-240918D01*
Y-240943D01*
X599500Y-240965D01*
Y-240990D01*
X599504Y-241016D01*
X599518Y-241081D01*
X599537Y-241158D01*
X599566Y-241234D01*
X599606Y-241314D01*
X599627Y-241354D01*
X599657Y-241391D01*
X599660Y-241394D01*
X599664Y-241398D01*
X599675Y-241409D01*
X599686Y-241424D01*
X599704Y-241438D01*
X599726Y-241456D01*
X599748Y-241478D01*
X599777Y-241496D01*
X599810Y-241518D01*
X599846Y-241544D01*
X599882Y-241565D01*
X599926Y-241587D01*
X599973Y-241606D01*
X600024Y-241624D01*
X600079Y-241642D01*
X600137Y-241656D01*
X600053Y-241991D01*
X600050D01*
X600035Y-241988D01*
X600013Y-241981D01*
X599984Y-241970D01*
X599952Y-241959D01*
X599911Y-241944D01*
X599868Y-241926D01*
X599820Y-241904D01*
X599719Y-241853D01*
X599617Y-241788D01*
X599566Y-241747D01*
X599515Y-241707D01*
X599471Y-241664D01*
X599427Y-241613D01*
X599424Y-241609D01*
X599416Y-241602D01*
X599409Y-241584D01*
X599395Y-241565D01*
X599376Y-241536D01*
X599358Y-241507D01*
X599340Y-241467D01*
X599322Y-241427D01*
X599300Y-241380D01*
X599282Y-241329D01*
X599263Y-241274D01*
X599245Y-241216D01*
X599231Y-241154D01*
X599224Y-241089D01*
X599216Y-241020D01*
X599213Y-240947D01*
Y-240907D01*
X599216Y-240878D01*
Y-240845D01*
X599220Y-240805D01*
X599227Y-240761D01*
X599234Y-240710D01*
X599253Y-240605D01*
X599282Y-240495D01*
X599322Y-240386D01*
X599347Y-240335D01*
X599376Y-240284D01*
X599380Y-240281D01*
X599384Y-240273D01*
X599395Y-240259D01*
X599409Y-240244D01*
X599424Y-240222D01*
X599445Y-240197D01*
X599471Y-240168D01*
X599500Y-240139D01*
X599533Y-240109D01*
X599566Y-240077D01*
X599649Y-240011D01*
X599748Y-239949D01*
X599857Y-239895D01*
X599860D01*
X599871Y-239887D01*
X599890Y-239884D01*
X599911Y-239873D01*
X599940Y-239866D01*
X599977Y-239855D01*
X600017Y-239840D01*
X600061Y-239829D01*
X600108Y-239818D01*
X600163Y-239804D01*
X600275Y-239786D01*
X600403Y-239771D01*
X600534Y-239764D01*
X600537D01*
X600552D01*
X600574D01*
X600599Y-239767D01*
D02*
G37*
G36*
X600996Y-242279D02*
X601029Y-242283D01*
X601069Y-242286D01*
X601109Y-242294D01*
X601156Y-242304D01*
X601251Y-242330D01*
X601302Y-242348D01*
X601357Y-242370D01*
X601407Y-242395D01*
X601455Y-242428D01*
X601506Y-242461D01*
X601549Y-242501D01*
X601553Y-242505D01*
X601560Y-242512D01*
X601571Y-242523D01*
X601586Y-242541D01*
X601604Y-242563D01*
X601626Y-242592D01*
X601644Y-242621D01*
X601670Y-242657D01*
X601691Y-242694D01*
X601710Y-242738D01*
X601750Y-242836D01*
X601764Y-242887D01*
X601775Y-242945D01*
X601782Y-243003D01*
X601786Y-243065D01*
Y-243091D01*
X601782Y-243109D01*
Y-243127D01*
X601779Y-243153D01*
X601768Y-243215D01*
X601753Y-243284D01*
X601728Y-243360D01*
X601695Y-243437D01*
X601651Y-243513D01*
Y-243517D01*
X601644Y-243520D01*
X601637Y-243531D01*
X601626Y-243546D01*
X601597Y-243582D01*
X601557Y-243629D01*
X601502Y-243677D01*
X601437Y-243731D01*
X601360Y-243779D01*
X601273Y-243822D01*
X601269D01*
X601262Y-243826D01*
X601247Y-243833D01*
X601229Y-243841D01*
X601204Y-243848D01*
X601171Y-243859D01*
X601134Y-243866D01*
X601094Y-243877D01*
X601047Y-243888D01*
X600992Y-243899D01*
X600934Y-243906D01*
X600872Y-243913D01*
X600803Y-243921D01*
X600730Y-243928D01*
X600650Y-243932D01*
X600567D01*
X600563D01*
X600545D01*
X600519D01*
X600487D01*
X600447Y-243928D01*
X600399D01*
X600345Y-243924D01*
X600290Y-243917D01*
X600166Y-243906D01*
X600035Y-243888D01*
X599911Y-243862D01*
X599850Y-243844D01*
X599795Y-243826D01*
X599791D01*
X599784Y-243822D01*
X599769Y-243815D01*
X599748Y-243808D01*
X599726Y-243797D01*
X599697Y-243782D01*
X599635Y-243746D01*
X599566Y-243702D01*
X599493Y-243651D01*
X599424Y-243586D01*
X599362Y-243513D01*
Y-243509D01*
X599355Y-243502D01*
X599347Y-243491D01*
X599340Y-243477D01*
X599329Y-243455D01*
X599314Y-243433D01*
X599300Y-243404D01*
X599289Y-243375D01*
X599260Y-243305D01*
X599234Y-243222D01*
X599220Y-243131D01*
X599213Y-243029D01*
Y-243000D01*
X599216Y-242982D01*
Y-242956D01*
X599220Y-242927D01*
X599234Y-242858D01*
X599253Y-242781D01*
X599282Y-242701D01*
X599322Y-242621D01*
X599347Y-242581D01*
X599376Y-242545D01*
X599380Y-242541D01*
X599384Y-242537D01*
X599395Y-242527D01*
X599405Y-242516D01*
X599424Y-242501D01*
X599445Y-242483D01*
X599497Y-242446D01*
X599562Y-242410D01*
X599642Y-242374D01*
X599733Y-242344D01*
X599839Y-242323D01*
X599864Y-242621D01*
X599860D01*
X599853Y-242625D01*
X599846D01*
X599831Y-242628D01*
X599791Y-242639D01*
X599748Y-242654D01*
X599697Y-242672D01*
X599646Y-242698D01*
X599598Y-242727D01*
X599558Y-242763D01*
X599555Y-242767D01*
X599544Y-242781D01*
X599529Y-242807D01*
X599515Y-242836D01*
X599497Y-242876D01*
X599482Y-242923D01*
X599471Y-242978D01*
X599467Y-243036D01*
Y-243062D01*
X599471Y-243087D01*
X599475Y-243120D01*
X599482Y-243160D01*
X599493Y-243200D01*
X599507Y-243244D01*
X599529Y-243284D01*
X599533Y-243287D01*
X599540Y-243302D01*
X599555Y-243324D01*
X599577Y-243345D01*
X599602Y-243375D01*
X599631Y-243404D01*
X599664Y-243433D01*
X599704Y-243462D01*
X599708Y-243466D01*
X599726Y-243473D01*
X599751Y-243488D01*
X599784Y-243502D01*
X599828Y-243520D01*
X599879Y-243538D01*
X599937Y-243557D01*
X600002Y-243575D01*
X600006D01*
X600010Y-243579D01*
X600021D01*
X600035Y-243582D01*
X600072Y-243589D01*
X600119Y-243600D01*
X600177Y-243608D01*
X600239Y-243615D01*
X600308Y-243618D01*
X600381Y-243622D01*
X600385D01*
X600395D01*
X600414D01*
X600443D01*
X600436Y-243618D01*
X600417Y-243604D01*
X600392Y-243582D01*
X600355Y-243557D01*
X600319Y-243520D01*
X600279Y-243477D01*
X600239Y-243426D01*
X600203Y-243367D01*
X600199Y-243360D01*
X600188Y-243338D01*
X600174Y-243305D01*
X600159Y-243265D01*
X600141Y-243211D01*
X600126Y-243153D01*
X600115Y-243087D01*
X600112Y-243018D01*
Y-242989D01*
X600115Y-242967D01*
X600119Y-242938D01*
X600122Y-242909D01*
X600130Y-242872D01*
X600141Y-242836D01*
X600166Y-242752D01*
X600184Y-242708D01*
X600206Y-242665D01*
X600232Y-242618D01*
X600265Y-242574D01*
X600297Y-242530D01*
X600337Y-242490D01*
X600341Y-242487D01*
X600348Y-242479D01*
X600359Y-242472D01*
X600377Y-242457D01*
X600403Y-242439D01*
X600428Y-242421D01*
X600461Y-242403D01*
X600497Y-242385D01*
X600537Y-242363D01*
X600581Y-242344D01*
X600632Y-242326D01*
X600683Y-242308D01*
X600741Y-242294D01*
X600803Y-242286D01*
X600865Y-242279D01*
X600934Y-242275D01*
X600938D01*
X600952D01*
X600971D01*
X600996Y-242279D01*
D02*
G37*
G36*
X613671Y-233468D02*
X613700Y-233472D01*
X613733Y-233475D01*
X613770Y-233483D01*
X613810Y-233490D01*
X613897Y-233512D01*
X613988Y-233548D01*
X614035Y-233570D01*
X614079Y-233596D01*
X614123Y-233628D01*
X614166Y-233661D01*
X614170Y-233665D01*
X614177Y-233672D01*
X614188Y-233683D01*
X614199Y-233698D01*
X614217Y-233716D01*
X614236Y-233741D01*
X614257Y-233767D01*
X614279Y-233799D01*
X614301Y-233836D01*
X614323Y-233872D01*
X614363Y-233960D01*
X614396Y-234062D01*
X614407Y-234116D01*
X614414Y-234174D01*
X614105Y-234214D01*
Y-234211D01*
X614101Y-234203D01*
X614097Y-234189D01*
X614094Y-234171D01*
X614090Y-234149D01*
X614083Y-234123D01*
X614065Y-234069D01*
X614039Y-234003D01*
X614006Y-233941D01*
X613970Y-233883D01*
X613926Y-233832D01*
X613919Y-233828D01*
X613904Y-233814D01*
X613875Y-233796D01*
X613839Y-233778D01*
X613795Y-233756D01*
X613740Y-233737D01*
X613679Y-233723D01*
X613613Y-233719D01*
X613591D01*
X613577Y-233723D01*
X613537Y-233727D01*
X613486Y-233737D01*
X613427Y-233756D01*
X613366Y-233781D01*
X613304Y-233818D01*
X613245Y-233869D01*
X613238Y-233876D01*
X613220Y-233898D01*
X613198Y-233930D01*
X613169Y-233974D01*
X613140Y-234029D01*
X613118Y-234091D01*
X613100Y-234163D01*
X613093Y-234243D01*
Y-234247D01*
Y-234254D01*
Y-234265D01*
X613096Y-234280D01*
X613100Y-234320D01*
X613111Y-234367D01*
X613125Y-234425D01*
X613151Y-234484D01*
X613187Y-234542D01*
X613235Y-234597D01*
X613242Y-234604D01*
X613260Y-234618D01*
X613289Y-234640D01*
X613329Y-234666D01*
X613380Y-234691D01*
X613442Y-234713D01*
X613511Y-234728D01*
X613588Y-234735D01*
X613620D01*
X613646Y-234731D01*
X613679Y-234728D01*
X613715Y-234720D01*
X613759Y-234713D01*
X613806Y-234702D01*
X613770Y-234975D01*
X613751D01*
X613737Y-234971D01*
X613690D01*
X613650Y-234979D01*
X613602Y-234986D01*
X613548Y-234997D01*
X613486Y-235015D01*
X613427Y-235041D01*
X613366Y-235073D01*
X613362D01*
X613358Y-235077D01*
X613340Y-235092D01*
X613315Y-235117D01*
X613285Y-235150D01*
X613256Y-235197D01*
X613231Y-235252D01*
X613213Y-235314D01*
X613205Y-235350D01*
Y-235390D01*
Y-235394D01*
Y-235397D01*
Y-235419D01*
X613213Y-235448D01*
X613220Y-235488D01*
X613235Y-235532D01*
X613253Y-235579D01*
X613282Y-235627D01*
X613322Y-235670D01*
X613326Y-235674D01*
X613344Y-235689D01*
X613369Y-235707D01*
X613402Y-235729D01*
X613446Y-235747D01*
X613497Y-235765D01*
X613555Y-235780D01*
X613620Y-235783D01*
X613650D01*
X613682Y-235776D01*
X613726Y-235769D01*
X613773Y-235754D01*
X613821Y-235736D01*
X613872Y-235707D01*
X613919Y-235670D01*
X613923Y-235667D01*
X613937Y-235648D01*
X613959Y-235623D01*
X613984Y-235587D01*
X614010Y-235539D01*
X614035Y-235481D01*
X614057Y-235412D01*
X614072Y-235332D01*
X614381Y-235386D01*
Y-235390D01*
X614377Y-235401D01*
X614374Y-235416D01*
X614370Y-235437D01*
X614363Y-235463D01*
X614352Y-235492D01*
X614330Y-235561D01*
X614294Y-235641D01*
X614250Y-235721D01*
X614195Y-235798D01*
X614126Y-235867D01*
X614123Y-235871D01*
X614115Y-235874D01*
X614105Y-235881D01*
X614090Y-235892D01*
X614072Y-235907D01*
X614046Y-235922D01*
X614021Y-235936D01*
X613988Y-235954D01*
X613915Y-235983D01*
X613832Y-236013D01*
X613733Y-236031D01*
X613682Y-236038D01*
X613591D01*
X613551Y-236034D01*
X613504Y-236027D01*
X613446Y-236016D01*
X613380Y-235998D01*
X613315Y-235976D01*
X613249Y-235947D01*
X613245D01*
X613242Y-235943D01*
X613220Y-235932D01*
X613187Y-235911D01*
X613151Y-235885D01*
X613107Y-235849D01*
X613063Y-235809D01*
X613020Y-235761D01*
X612983Y-235707D01*
X612980Y-235700D01*
X612969Y-235681D01*
X612954Y-235648D01*
X612936Y-235609D01*
X612918Y-235561D01*
X612903Y-235507D01*
X612892Y-235445D01*
X612889Y-235383D01*
Y-235375D01*
Y-235354D01*
X612892Y-235325D01*
X612900Y-235284D01*
X612911Y-235237D01*
X612929Y-235186D01*
X612951Y-235135D01*
X612980Y-235084D01*
X612983Y-235077D01*
X612994Y-235063D01*
X613016Y-235037D01*
X613045Y-235008D01*
X613082Y-234975D01*
X613125Y-234939D01*
X613176Y-234906D01*
X613238Y-234873D01*
X613235D01*
X613227Y-234870D01*
X613216Y-234866D01*
X613202Y-234862D01*
X613162Y-234848D01*
X613111Y-234826D01*
X613053Y-234797D01*
X612994Y-234760D01*
X612940Y-234713D01*
X612889Y-234658D01*
X612885Y-234651D01*
X612871Y-234629D01*
X612849Y-234593D01*
X612827Y-234546D01*
X612805Y-234487D01*
X612783Y-234418D01*
X612769Y-234338D01*
X612765Y-234251D01*
Y-234247D01*
Y-234236D01*
Y-234218D01*
X612769Y-234196D01*
X612772Y-234167D01*
X612780Y-234134D01*
X612787Y-234098D01*
X612794Y-234058D01*
X612823Y-233970D01*
X612845Y-233923D01*
X612867Y-233879D01*
X612896Y-233832D01*
X612929Y-233785D01*
X612965Y-233737D01*
X613009Y-233694D01*
X613013Y-233690D01*
X613020Y-233683D01*
X613034Y-233672D01*
X613053Y-233657D01*
X613074Y-233639D01*
X613103Y-233621D01*
X613136Y-233599D01*
X613176Y-233581D01*
X613216Y-233559D01*
X613264Y-233537D01*
X613311Y-233519D01*
X613366Y-233501D01*
X613424Y-233486D01*
X613486Y-233475D01*
X613548Y-233468D01*
X613617Y-233465D01*
X613650D01*
X613671Y-233468D01*
D02*
G37*
G36*
X615815D02*
X615848D01*
X615888Y-233472D01*
X615932Y-233479D01*
X615983Y-233486D01*
X616088Y-233505D01*
X616197Y-233534D01*
X616307Y-233574D01*
X616358Y-233599D01*
X616409Y-233628D01*
X616412Y-233632D01*
X616420Y-233636D01*
X616434Y-233646D01*
X616449Y-233661D01*
X616470Y-233676D01*
X616496Y-233698D01*
X616525Y-233723D01*
X616554Y-233752D01*
X616583Y-233785D01*
X616616Y-233818D01*
X616682Y-233901D01*
X616744Y-234000D01*
X616798Y-234109D01*
Y-234112D01*
X616805Y-234123D01*
X616809Y-234142D01*
X616820Y-234163D01*
X616827Y-234192D01*
X616838Y-234229D01*
X616853Y-234269D01*
X616864Y-234313D01*
X616875Y-234360D01*
X616889Y-234415D01*
X616907Y-234527D01*
X616922Y-234655D01*
X616929Y-234786D01*
Y-234789D01*
Y-234804D01*
Y-234826D01*
X616925Y-234851D01*
Y-234888D01*
X616922Y-234924D01*
X616918Y-234971D01*
X616911Y-235019D01*
X616893Y-235124D01*
X616867Y-235241D01*
X616831Y-235357D01*
X616780Y-235470D01*
X616776Y-235474D01*
X616773Y-235485D01*
X616765Y-235499D01*
X616751Y-235518D01*
X616736Y-235543D01*
X616718Y-235572D01*
X616671Y-235638D01*
X616609Y-235710D01*
X616536Y-235783D01*
X616452Y-235856D01*
X616354Y-235918D01*
X616350Y-235922D01*
X616339Y-235925D01*
X616325Y-235932D01*
X616307Y-235943D01*
X616278Y-235954D01*
X616249Y-235965D01*
X616212Y-235980D01*
X616172Y-235994D01*
X616128Y-236009D01*
X616081Y-236023D01*
X615979Y-236045D01*
X615863Y-236064D01*
X615742Y-236071D01*
X615706D01*
X615681Y-236067D01*
X615648Y-236064D01*
X615608Y-236060D01*
X615568Y-236056D01*
X615520Y-236045D01*
X615422Y-236023D01*
X615313Y-235991D01*
X615258Y-235969D01*
X615207Y-235943D01*
X615157Y-235911D01*
X615105Y-235878D01*
X615102Y-235874D01*
X615095Y-235871D01*
X615080Y-235860D01*
X615062Y-235841D01*
X615044Y-235823D01*
X615018Y-235798D01*
X614993Y-235769D01*
X614964Y-235739D01*
X614934Y-235703D01*
X614905Y-235659D01*
X614873Y-235616D01*
X614843Y-235568D01*
X614818Y-235514D01*
X614789Y-235459D01*
X614767Y-235401D01*
X614745Y-235335D01*
X615073Y-235259D01*
Y-235263D01*
X615076Y-235270D01*
X615084Y-235284D01*
X615091Y-235303D01*
X615098Y-235325D01*
X615109Y-235354D01*
X615138Y-235412D01*
X615175Y-235477D01*
X615218Y-235543D01*
X615273Y-235605D01*
X615331Y-235659D01*
X615339Y-235667D01*
X615360Y-235681D01*
X615397Y-235700D01*
X615444Y-235725D01*
X615506Y-235747D01*
X615575Y-235769D01*
X615659Y-235783D01*
X615750Y-235787D01*
X615779D01*
X615797Y-235783D01*
X615823D01*
X615852Y-235780D01*
X615921Y-235769D01*
X615997Y-235754D01*
X616077Y-235729D01*
X616161Y-235692D01*
X616238Y-235645D01*
X616241D01*
X616245Y-235638D01*
X616270Y-235619D01*
X616303Y-235590D01*
X616343Y-235547D01*
X616390Y-235492D01*
X616434Y-235430D01*
X616474Y-235354D01*
X616511Y-235270D01*
Y-235266D01*
X616514Y-235259D01*
X616518Y-235248D01*
X616522Y-235230D01*
X616529Y-235208D01*
X616536Y-235183D01*
X616547Y-235121D01*
X616562Y-235048D01*
X616576Y-234968D01*
X616583Y-234880D01*
X616587Y-234786D01*
Y-234782D01*
Y-234771D01*
Y-234753D01*
Y-234731D01*
X616583Y-234706D01*
Y-234673D01*
X616580Y-234637D01*
X616576Y-234597D01*
X616565Y-234509D01*
X616547Y-234415D01*
X616525Y-234320D01*
X616496Y-234225D01*
Y-234222D01*
X616492Y-234214D01*
X616485Y-234203D01*
X616478Y-234185D01*
X616456Y-234142D01*
X616423Y-234091D01*
X616383Y-234032D01*
X616332Y-233970D01*
X616274Y-233916D01*
X616205Y-233865D01*
X616201D01*
X616194Y-233861D01*
X616183Y-233854D01*
X616168Y-233847D01*
X616150Y-233839D01*
X616128Y-233828D01*
X616077Y-233807D01*
X616012Y-233785D01*
X615939Y-233767D01*
X615859Y-233752D01*
X615775Y-233748D01*
X615750D01*
X615728Y-233752D01*
X615702D01*
X615677Y-233756D01*
X615612Y-233770D01*
X615535Y-233788D01*
X615459Y-233818D01*
X615379Y-233858D01*
X615339Y-233879D01*
X615302Y-233909D01*
X615298Y-233912D01*
X615295Y-233916D01*
X615284Y-233927D01*
X615269Y-233938D01*
X615255Y-233956D01*
X615237Y-233978D01*
X615215Y-234000D01*
X615197Y-234029D01*
X615175Y-234062D01*
X615149Y-234098D01*
X615127Y-234134D01*
X615105Y-234178D01*
X615087Y-234225D01*
X615069Y-234276D01*
X615051Y-234331D01*
X615036Y-234389D01*
X614702Y-234305D01*
Y-234302D01*
X614705Y-234287D01*
X614712Y-234265D01*
X614723Y-234236D01*
X614734Y-234203D01*
X614749Y-234163D01*
X614767Y-234120D01*
X614789Y-234072D01*
X614840Y-233970D01*
X614905Y-233869D01*
X614945Y-233818D01*
X614985Y-233767D01*
X615029Y-233723D01*
X615080Y-233679D01*
X615084Y-233676D01*
X615091Y-233668D01*
X615109Y-233661D01*
X615127Y-233646D01*
X615157Y-233628D01*
X615186Y-233610D01*
X615226Y-233592D01*
X615266Y-233574D01*
X615313Y-233552D01*
X615364Y-233534D01*
X615419Y-233516D01*
X615477Y-233497D01*
X615539Y-233483D01*
X615604Y-233475D01*
X615673Y-233468D01*
X615746Y-233465D01*
X615786D01*
X615815Y-233468D01*
D02*
G37*
G36*
X683277Y-207226D02*
X683313D01*
X683349Y-207229D01*
X683397Y-207233D01*
X683444Y-207241D01*
X683549Y-207259D01*
X683666Y-207284D01*
X683782Y-207320D01*
X683895Y-207371D01*
X683899Y-207375D01*
X683910Y-207379D01*
X683924Y-207386D01*
X683943Y-207401D01*
X683968Y-207415D01*
X683997Y-207433D01*
X684063Y-207481D01*
X684136Y-207543D01*
X684208Y-207615D01*
X684281Y-207699D01*
X684343Y-207797D01*
X684347Y-207801D01*
X684350Y-207812D01*
X684358Y-207826D01*
X684369Y-207845D01*
X684379Y-207874D01*
X684390Y-207903D01*
X684405Y-207939D01*
X684419Y-207979D01*
X684434Y-208023D01*
X684449Y-208070D01*
X684471Y-208172D01*
X684489Y-208289D01*
X684496Y-208409D01*
Y-208445D01*
X684492Y-208471D01*
X684489Y-208504D01*
X684485Y-208544D01*
X684481Y-208584D01*
X684471Y-208631D01*
X684449Y-208729D01*
X684416Y-208838D01*
X684394Y-208893D01*
X684369Y-208944D01*
X684336Y-208995D01*
X684303Y-209046D01*
X684299Y-209050D01*
X684296Y-209057D01*
X684285Y-209071D01*
X684267Y-209090D01*
X684248Y-209108D01*
X684223Y-209133D01*
X684194Y-209159D01*
X684165Y-209188D01*
X684128Y-209217D01*
X684085Y-209246D01*
X684041Y-209279D01*
X683994Y-209308D01*
X683939Y-209333D01*
X683884Y-209363D01*
X683826Y-209384D01*
X683761Y-209406D01*
X683684Y-209079D01*
X683688D01*
X683695Y-209075D01*
X683710Y-209068D01*
X683728Y-209061D01*
X683750Y-209053D01*
X683779Y-209042D01*
X683837Y-209013D01*
X683903Y-208977D01*
X683968Y-208933D01*
X684030Y-208878D01*
X684085Y-208820D01*
X684092Y-208813D01*
X684106Y-208791D01*
X684125Y-208755D01*
X684150Y-208707D01*
X684172Y-208646D01*
X684194Y-208576D01*
X684208Y-208493D01*
X684212Y-208402D01*
Y-208372D01*
X684208Y-208354D01*
Y-208329D01*
X684205Y-208300D01*
X684194Y-208230D01*
X684179Y-208154D01*
X684154Y-208074D01*
X684117Y-207990D01*
X684070Y-207914D01*
Y-207910D01*
X684063Y-207907D01*
X684045Y-207881D01*
X684016Y-207848D01*
X683972Y-207808D01*
X683917Y-207761D01*
X683855Y-207717D01*
X683779Y-207677D01*
X683695Y-207641D01*
X683692D01*
X683684Y-207637D01*
X683673Y-207634D01*
X683655Y-207630D01*
X683633Y-207623D01*
X683608Y-207615D01*
X683546Y-207605D01*
X683473Y-207590D01*
X683393Y-207575D01*
X683306Y-207568D01*
X683211Y-207564D01*
X683207D01*
X683196D01*
X683178D01*
X683156D01*
X683131Y-207568D01*
X683098D01*
X683062Y-207572D01*
X683022Y-207575D01*
X682934Y-207586D01*
X682840Y-207605D01*
X682745Y-207626D01*
X682651Y-207655D01*
X682647D01*
X682640Y-207659D01*
X682629Y-207666D01*
X682610Y-207674D01*
X682567Y-207696D01*
X682516Y-207728D01*
X682457Y-207768D01*
X682396Y-207819D01*
X682341Y-207877D01*
X682290Y-207947D01*
Y-207950D01*
X682287Y-207958D01*
X682279Y-207968D01*
X682272Y-207983D01*
X682265Y-208001D01*
X682254Y-208023D01*
X682232Y-208074D01*
X682210Y-208139D01*
X682192Y-208212D01*
X682177Y-208292D01*
X682174Y-208376D01*
Y-208402D01*
X682177Y-208423D01*
Y-208449D01*
X682181Y-208474D01*
X682196Y-208540D01*
X682214Y-208616D01*
X682243Y-208693D01*
X682283Y-208773D01*
X682305Y-208813D01*
X682334Y-208849D01*
X682337Y-208853D01*
X682341Y-208857D01*
X682352Y-208868D01*
X682363Y-208882D01*
X682381Y-208897D01*
X682403Y-208915D01*
X682425Y-208937D01*
X682454Y-208955D01*
X682487Y-208977D01*
X682523Y-209002D01*
X682559Y-209024D01*
X682603Y-209046D01*
X682651Y-209064D01*
X682701Y-209082D01*
X682756Y-209101D01*
X682814Y-209115D01*
X682730Y-209450D01*
X682727D01*
X682712Y-209446D01*
X682690Y-209439D01*
X682661Y-209428D01*
X682629Y-209417D01*
X682589Y-209403D01*
X682545Y-209384D01*
X682498Y-209363D01*
X682396Y-209312D01*
X682294Y-209246D01*
X682243Y-209206D01*
X682192Y-209166D01*
X682148Y-209122D01*
X682104Y-209071D01*
X682101Y-209068D01*
X682093Y-209061D01*
X682086Y-209042D01*
X682072Y-209024D01*
X682054Y-208995D01*
X682035Y-208966D01*
X682017Y-208926D01*
X681999Y-208886D01*
X681977Y-208838D01*
X681959Y-208787D01*
X681941Y-208733D01*
X681922Y-208675D01*
X681908Y-208613D01*
X681901Y-208547D01*
X681893Y-208478D01*
X681890Y-208405D01*
Y-208365D01*
X681893Y-208336D01*
Y-208303D01*
X681897Y-208263D01*
X681904Y-208220D01*
X681912Y-208169D01*
X681930Y-208063D01*
X681959Y-207954D01*
X681999Y-207845D01*
X682024Y-207794D01*
X682054Y-207743D01*
X682057Y-207739D01*
X682061Y-207732D01*
X682072Y-207717D01*
X682086Y-207703D01*
X682101Y-207681D01*
X682123Y-207655D01*
X682148Y-207626D01*
X682177Y-207597D01*
X682210Y-207568D01*
X682243Y-207535D01*
X682327Y-207470D01*
X682425Y-207408D01*
X682534Y-207353D01*
X682538D01*
X682549Y-207346D01*
X682567Y-207342D01*
X682589Y-207331D01*
X682618Y-207324D01*
X682654Y-207313D01*
X682694Y-207299D01*
X682738Y-207288D01*
X682785Y-207277D01*
X682840Y-207262D01*
X682953Y-207244D01*
X683080Y-207229D01*
X683211Y-207222D01*
X683215D01*
X683229D01*
X683251D01*
X683277Y-207226D01*
D02*
G37*
G36*
X683830Y-209974D02*
X683837Y-209981D01*
X683841Y-209996D01*
X683852Y-210014D01*
X683863Y-210036D01*
X683877Y-210062D01*
X683914Y-210123D01*
X683954Y-210196D01*
X684004Y-210269D01*
X684063Y-210345D01*
X684125Y-210422D01*
X684128Y-210425D01*
X684132Y-210429D01*
X684143Y-210440D01*
X684154Y-210455D01*
X684190Y-210487D01*
X684234Y-210531D01*
X684285Y-210575D01*
X684343Y-210622D01*
X684401Y-210662D01*
X684463Y-210699D01*
Y-210899D01*
X681933D01*
Y-210589D01*
X683903D01*
X683899Y-210586D01*
X683884Y-210567D01*
X683863Y-210546D01*
X683837Y-210509D01*
X683804Y-210469D01*
X683768Y-210418D01*
X683728Y-210360D01*
X683688Y-210294D01*
Y-210291D01*
X683684Y-210287D01*
X683670Y-210265D01*
X683651Y-210229D01*
X683630Y-210185D01*
X683604Y-210134D01*
X683579Y-210080D01*
X683553Y-210025D01*
X683531Y-209970D01*
X683830D01*
Y-209974D01*
D02*
G37*
G36*
X682698Y-211692D02*
X682720D01*
X682745Y-211696D01*
X682803Y-211703D01*
X682869Y-211718D01*
X682934Y-211739D01*
X683004Y-211772D01*
X683069Y-211812D01*
X683073D01*
X683076Y-211820D01*
X683095Y-211834D01*
X683124Y-211863D01*
X683160Y-211903D01*
X683196Y-211954D01*
X683237Y-212016D01*
X683269Y-212085D01*
X683295Y-212169D01*
Y-212165D01*
X683298Y-212162D01*
X683302Y-212151D01*
X683309Y-212136D01*
X683324Y-212104D01*
X683346Y-212060D01*
X683375Y-212013D01*
X683411Y-211965D01*
X683451Y-211922D01*
X683495Y-211881D01*
X683502Y-211878D01*
X683517Y-211867D01*
X683546Y-211852D01*
X683582Y-211838D01*
X683630Y-211820D01*
X683684Y-211805D01*
X683746Y-211794D01*
X683812Y-211790D01*
X683815D01*
X683822D01*
X683837D01*
X683859Y-211794D01*
X683881Y-211798D01*
X683910Y-211801D01*
X683972Y-211816D01*
X684045Y-211838D01*
X684121Y-211874D01*
X684161Y-211896D01*
X684201Y-211922D01*
X684237Y-211954D01*
X684274Y-211987D01*
X684277Y-211991D01*
X684281Y-211998D01*
X684292Y-212009D01*
X684303Y-212023D01*
X684318Y-212042D01*
X684332Y-212067D01*
X684350Y-212096D01*
X684369Y-212125D01*
X684387Y-212162D01*
X684405Y-212202D01*
X684419Y-212245D01*
X684434Y-212293D01*
X684456Y-212395D01*
X684459Y-212453D01*
X684463Y-212511D01*
Y-212544D01*
X684459Y-212566D01*
X684456Y-212595D01*
X684452Y-212628D01*
X684449Y-212664D01*
X684438Y-212701D01*
X684416Y-212788D01*
X684383Y-212875D01*
X684361Y-212919D01*
X684336Y-212963D01*
X684303Y-213003D01*
X684270Y-213043D01*
X684267Y-213046D01*
X684263Y-213050D01*
X684252Y-213061D01*
X684237Y-213075D01*
X684216Y-213090D01*
X684194Y-213108D01*
X684139Y-213144D01*
X684070Y-213181D01*
X683990Y-213214D01*
X683899Y-213239D01*
X683852Y-213243D01*
X683801Y-213246D01*
X683797D01*
X683793D01*
X683772D01*
X683739Y-213243D01*
X683699Y-213235D01*
X683648Y-213225D01*
X683597Y-213206D01*
X683546Y-213185D01*
X683495Y-213152D01*
X683488Y-213148D01*
X683473Y-213134D01*
X683451Y-213112D01*
X683422Y-213083D01*
X683389Y-213043D01*
X683357Y-212995D01*
X683324Y-212941D01*
X683295Y-212875D01*
Y-212879D01*
X683291Y-212886D01*
X683287Y-212897D01*
X683280Y-212912D01*
X683262Y-212955D01*
X683237Y-213006D01*
X683200Y-213061D01*
X683160Y-213119D01*
X683109Y-213174D01*
X683051Y-213225D01*
X683047D01*
X683044Y-213228D01*
X683022Y-213243D01*
X682985Y-213265D01*
X682938Y-213286D01*
X682880Y-213308D01*
X682811Y-213330D01*
X682734Y-213345D01*
X682651Y-213348D01*
X682647D01*
X682636D01*
X682618D01*
X682596Y-213345D01*
X682570Y-213341D01*
X682538Y-213337D01*
X682501Y-213330D01*
X682461Y-213319D01*
X682377Y-213294D01*
X682330Y-213276D01*
X682287Y-213250D01*
X682239Y-213225D01*
X682196Y-213195D01*
X682152Y-213159D01*
X682108Y-213119D01*
X682104Y-213115D01*
X682097Y-213108D01*
X682086Y-213097D01*
X682075Y-213079D01*
X682057Y-213053D01*
X682039Y-213028D01*
X682021Y-212995D01*
X681999Y-212959D01*
X681977Y-212919D01*
X681959Y-212872D01*
X681941Y-212821D01*
X681922Y-212770D01*
X681912Y-212711D01*
X681901Y-212649D01*
X681893Y-212588D01*
X681890Y-212519D01*
Y-212482D01*
X681893Y-212457D01*
X681897Y-212424D01*
X681901Y-212387D01*
X681908Y-212347D01*
X681919Y-212304D01*
X681944Y-212205D01*
X681962Y-212155D01*
X681981Y-212107D01*
X682006Y-212056D01*
X682035Y-212005D01*
X682068Y-211958D01*
X682108Y-211914D01*
X682112Y-211911D01*
X682119Y-211903D01*
X682130Y-211892D01*
X682148Y-211878D01*
X682170Y-211863D01*
X682196Y-211841D01*
X682225Y-211823D01*
X682261Y-211801D01*
X682297Y-211779D01*
X682341Y-211761D01*
X682432Y-211725D01*
X682487Y-211710D01*
X682541Y-211700D01*
X682599Y-211692D01*
X682658Y-211688D01*
X682661D01*
X682669D01*
X682683D01*
X682698Y-211692D01*
D02*
G37*
G36*
X674859Y-178527D02*
X674888Y-178531D01*
X674921Y-178538D01*
X674957Y-178545D01*
X674997Y-178552D01*
X675085Y-178582D01*
X675132Y-178603D01*
X675176Y-178625D01*
X675223Y-178654D01*
X675270Y-178687D01*
X675318Y-178724D01*
X675361Y-178767D01*
X675365Y-178771D01*
X675372Y-178778D01*
X675383Y-178793D01*
X675398Y-178811D01*
X675416Y-178833D01*
X675434Y-178862D01*
X675456Y-178894D01*
X675474Y-178935D01*
X675496Y-178975D01*
X675518Y-179022D01*
X675536Y-179069D01*
X675554Y-179124D01*
X675569Y-179182D01*
X675580Y-179244D01*
X675587Y-179306D01*
X675591Y-179375D01*
Y-179408D01*
X675587Y-179430D01*
X675583Y-179459D01*
X675580Y-179491D01*
X675572Y-179528D01*
X675565Y-179568D01*
X675543Y-179655D01*
X675507Y-179746D01*
X675485Y-179794D01*
X675460Y-179837D01*
X675427Y-179881D01*
X675394Y-179925D01*
X675390Y-179928D01*
X675383Y-179936D01*
X675372Y-179946D01*
X675358Y-179957D01*
X675339Y-179976D01*
X675314Y-179994D01*
X675288Y-180016D01*
X675256Y-180037D01*
X675219Y-180059D01*
X675183Y-180081D01*
X675096Y-180121D01*
X674994Y-180154D01*
X674939Y-180165D01*
X674881Y-180172D01*
X674841Y-179863D01*
X674844D01*
X674852Y-179859D01*
X674866Y-179856D01*
X674884Y-179852D01*
X674906Y-179848D01*
X674932Y-179841D01*
X674986Y-179823D01*
X675052Y-179797D01*
X675114Y-179764D01*
X675172Y-179728D01*
X675223Y-179684D01*
X675227Y-179677D01*
X675241Y-179663D01*
X675259Y-179633D01*
X675278Y-179597D01*
X675299Y-179553D01*
X675318Y-179499D01*
X675332Y-179437D01*
X675336Y-179371D01*
Y-179350D01*
X675332Y-179335D01*
X675328Y-179295D01*
X675318Y-179244D01*
X675299Y-179186D01*
X675274Y-179124D01*
X675238Y-179062D01*
X675186Y-179004D01*
X675179Y-178997D01*
X675157Y-178978D01*
X675125Y-178956D01*
X675081Y-178927D01*
X675026Y-178898D01*
X674965Y-178876D01*
X674892Y-178858D01*
X674812Y-178851D01*
X674808D01*
X674801D01*
X674790D01*
X674775Y-178855D01*
X674735Y-178858D01*
X674688Y-178869D01*
X674630Y-178884D01*
X674571Y-178909D01*
X674513Y-178946D01*
X674459Y-178993D01*
X674451Y-179000D01*
X674437Y-179018D01*
X674415Y-179047D01*
X674389Y-179087D01*
X674364Y-179138D01*
X674342Y-179200D01*
X674328Y-179270D01*
X674320Y-179346D01*
Y-179379D01*
X674324Y-179404D01*
X674328Y-179437D01*
X674335Y-179473D01*
X674342Y-179517D01*
X674353Y-179564D01*
X674080Y-179528D01*
Y-179510D01*
X674084Y-179495D01*
Y-179448D01*
X674076Y-179408D01*
X674069Y-179360D01*
X674058Y-179306D01*
X674040Y-179244D01*
X674015Y-179186D01*
X673982Y-179124D01*
Y-179120D01*
X673978Y-179117D01*
X673963Y-179098D01*
X673938Y-179073D01*
X673905Y-179044D01*
X673858Y-179015D01*
X673803Y-178989D01*
X673741Y-178971D01*
X673705Y-178964D01*
X673665D01*
X673661D01*
X673658D01*
X673636D01*
X673607Y-178971D01*
X673567Y-178978D01*
X673523Y-178993D01*
X673476Y-179011D01*
X673428Y-179040D01*
X673385Y-179080D01*
X673381Y-179084D01*
X673367Y-179102D01*
X673348Y-179128D01*
X673326Y-179160D01*
X673308Y-179204D01*
X673290Y-179255D01*
X673276Y-179313D01*
X673272Y-179379D01*
Y-179408D01*
X673279Y-179440D01*
X673286Y-179484D01*
X673301Y-179532D01*
X673319Y-179579D01*
X673348Y-179630D01*
X673385Y-179677D01*
X673388Y-179681D01*
X673407Y-179695D01*
X673432Y-179717D01*
X673468Y-179743D01*
X673516Y-179768D01*
X673574Y-179794D01*
X673643Y-179815D01*
X673723Y-179830D01*
X673669Y-180139D01*
X673665D01*
X673654Y-180136D01*
X673639Y-180132D01*
X673618Y-180129D01*
X673592Y-180121D01*
X673563Y-180110D01*
X673494Y-180088D01*
X673414Y-180052D01*
X673334Y-180008D01*
X673257Y-179954D01*
X673188Y-179885D01*
X673185Y-179881D01*
X673181Y-179874D01*
X673174Y-179863D01*
X673163Y-179848D01*
X673148Y-179830D01*
X673134Y-179805D01*
X673119Y-179779D01*
X673101Y-179746D01*
X673072Y-179674D01*
X673043Y-179590D01*
X673024Y-179491D01*
X673017Y-179440D01*
Y-179350D01*
X673021Y-179309D01*
X673028Y-179262D01*
X673039Y-179204D01*
X673057Y-179138D01*
X673079Y-179073D01*
X673108Y-179007D01*
Y-179004D01*
X673112Y-179000D01*
X673123Y-178978D01*
X673144Y-178946D01*
X673170Y-178909D01*
X673206Y-178865D01*
X673246Y-178822D01*
X673294Y-178778D01*
X673348Y-178742D01*
X673356Y-178738D01*
X673374Y-178727D01*
X673407Y-178712D01*
X673447Y-178694D01*
X673494Y-178676D01*
X673549Y-178662D01*
X673610Y-178651D01*
X673672Y-178647D01*
X673680D01*
X673701D01*
X673731Y-178651D01*
X673771Y-178658D01*
X673818Y-178669D01*
X673869Y-178687D01*
X673920Y-178709D01*
X673971Y-178738D01*
X673978Y-178742D01*
X673993Y-178753D01*
X674018Y-178774D01*
X674047Y-178804D01*
X674080Y-178840D01*
X674116Y-178884D01*
X674149Y-178935D01*
X674182Y-178997D01*
Y-178993D01*
X674186Y-178986D01*
X674189Y-178975D01*
X674193Y-178960D01*
X674207Y-178920D01*
X674229Y-178869D01*
X674258Y-178811D01*
X674295Y-178753D01*
X674342Y-178698D01*
X674397Y-178647D01*
X674404Y-178643D01*
X674426Y-178629D01*
X674462Y-178607D01*
X674509Y-178585D01*
X674568Y-178563D01*
X674637Y-178542D01*
X674717Y-178527D01*
X674804Y-178523D01*
X674808D01*
X674819D01*
X674837D01*
X674859Y-178527D01*
D02*
G37*
G36*
X675547Y-181279D02*
X673578D01*
X673581Y-181282D01*
X673596Y-181301D01*
X673618Y-181322D01*
X673643Y-181359D01*
X673676Y-181399D01*
X673712Y-181450D01*
X673752Y-181508D01*
X673792Y-181574D01*
Y-181577D01*
X673796Y-181581D01*
X673811Y-181603D01*
X673829Y-181639D01*
X673851Y-181683D01*
X673876Y-181734D01*
X673902Y-181788D01*
X673927Y-181843D01*
X673949Y-181897D01*
X673651D01*
Y-181894D01*
X673643Y-181887D01*
X673639Y-181872D01*
X673629Y-181854D01*
X673618Y-181832D01*
X673603Y-181807D01*
X673567Y-181745D01*
X673527Y-181672D01*
X673476Y-181599D01*
X673418Y-181523D01*
X673356Y-181446D01*
X673352Y-181442D01*
X673348Y-181439D01*
X673337Y-181428D01*
X673326Y-181413D01*
X673290Y-181381D01*
X673246Y-181337D01*
X673196Y-181293D01*
X673137Y-181246D01*
X673079Y-181206D01*
X673017Y-181169D01*
Y-180969D01*
X675547D01*
Y-181279D01*
D02*
G37*
G36*
X674768Y-182422D02*
X674790Y-182429D01*
X674819Y-182440D01*
X674852Y-182451D01*
X674892Y-182465D01*
X674935Y-182484D01*
X674983Y-182505D01*
X675085Y-182556D01*
X675186Y-182622D01*
X675238Y-182662D01*
X675288Y-182702D01*
X675332Y-182746D01*
X675376Y-182797D01*
X675380Y-182800D01*
X675387Y-182808D01*
X675394Y-182826D01*
X675409Y-182844D01*
X675427Y-182873D01*
X675445Y-182902D01*
X675463Y-182942D01*
X675481Y-182982D01*
X675503Y-183030D01*
X675521Y-183080D01*
X675540Y-183135D01*
X675558Y-183193D01*
X675572Y-183255D01*
X675580Y-183321D01*
X675587Y-183390D01*
X675591Y-183463D01*
Y-183503D01*
X675587Y-183532D01*
Y-183565D01*
X675583Y-183605D01*
X675576Y-183648D01*
X675569Y-183699D01*
X675551Y-183805D01*
X675521Y-183914D01*
X675481Y-184023D01*
X675456Y-184074D01*
X675427Y-184125D01*
X675423Y-184129D01*
X675420Y-184136D01*
X675409Y-184151D01*
X675394Y-184165D01*
X675380Y-184187D01*
X675358Y-184213D01*
X675332Y-184242D01*
X675303Y-184271D01*
X675270Y-184300D01*
X675238Y-184333D01*
X675154Y-184398D01*
X675056Y-184460D01*
X674946Y-184515D01*
X674943D01*
X674932Y-184522D01*
X674914Y-184526D01*
X674892Y-184537D01*
X674863Y-184544D01*
X674826Y-184555D01*
X674786Y-184569D01*
X674743Y-184580D01*
X674695Y-184591D01*
X674641Y-184606D01*
X674528Y-184624D01*
X674400Y-184638D01*
X674269Y-184646D01*
X674266D01*
X674251D01*
X674229D01*
X674204Y-184642D01*
X674167D01*
X674131Y-184638D01*
X674084Y-184635D01*
X674036Y-184627D01*
X673931Y-184609D01*
X673814Y-184584D01*
X673698Y-184547D01*
X673585Y-184496D01*
X673581Y-184493D01*
X673570Y-184489D01*
X673556Y-184482D01*
X673538Y-184467D01*
X673512Y-184453D01*
X673483Y-184435D01*
X673418Y-184387D01*
X673345Y-184325D01*
X673272Y-184253D01*
X673199Y-184169D01*
X673137Y-184071D01*
X673134Y-184067D01*
X673130Y-184056D01*
X673123Y-184042D01*
X673112Y-184023D01*
X673101Y-183994D01*
X673090Y-183965D01*
X673075Y-183929D01*
X673061Y-183889D01*
X673046Y-183845D01*
X673032Y-183798D01*
X673010Y-183696D01*
X672992Y-183579D01*
X672984Y-183459D01*
Y-183423D01*
X672988Y-183397D01*
X672992Y-183364D01*
X672995Y-183324D01*
X672999Y-183284D01*
X673010Y-183237D01*
X673032Y-183139D01*
X673064Y-183030D01*
X673086Y-182975D01*
X673112Y-182924D01*
X673144Y-182873D01*
X673177Y-182822D01*
X673181Y-182818D01*
X673185Y-182811D01*
X673196Y-182797D01*
X673214Y-182778D01*
X673232Y-182760D01*
X673257Y-182735D01*
X673286Y-182709D01*
X673316Y-182680D01*
X673352Y-182651D01*
X673396Y-182622D01*
X673439Y-182589D01*
X673487Y-182560D01*
X673541Y-182535D01*
X673596Y-182505D01*
X673654Y-182484D01*
X673720Y-182462D01*
X673796Y-182789D01*
X673792D01*
X673785Y-182793D01*
X673771Y-182800D01*
X673752Y-182808D01*
X673731Y-182815D01*
X673701Y-182826D01*
X673643Y-182855D01*
X673578Y-182891D01*
X673512Y-182935D01*
X673450Y-182990D01*
X673396Y-183048D01*
X673388Y-183055D01*
X673374Y-183077D01*
X673356Y-183113D01*
X673330Y-183161D01*
X673308Y-183222D01*
X673286Y-183292D01*
X673272Y-183375D01*
X673268Y-183466D01*
Y-183495D01*
X673272Y-183514D01*
Y-183539D01*
X673276Y-183568D01*
X673286Y-183637D01*
X673301Y-183714D01*
X673326Y-183794D01*
X673363Y-183878D01*
X673410Y-183954D01*
Y-183958D01*
X673418Y-183961D01*
X673436Y-183987D01*
X673465Y-184020D01*
X673509Y-184060D01*
X673563Y-184107D01*
X673625Y-184151D01*
X673701Y-184191D01*
X673785Y-184227D01*
X673789D01*
X673796Y-184231D01*
X673807Y-184234D01*
X673825Y-184238D01*
X673847Y-184245D01*
X673873Y-184253D01*
X673934Y-184264D01*
X674007Y-184278D01*
X674087Y-184293D01*
X674175Y-184300D01*
X674269Y-184304D01*
X674273D01*
X674284D01*
X674302D01*
X674324D01*
X674349Y-184300D01*
X674382D01*
X674418Y-184296D01*
X674459Y-184293D01*
X674546Y-184282D01*
X674641Y-184264D01*
X674735Y-184242D01*
X674830Y-184213D01*
X674833D01*
X674841Y-184209D01*
X674852Y-184202D01*
X674870Y-184194D01*
X674914Y-184172D01*
X674965Y-184140D01*
X675023Y-184100D01*
X675085Y-184049D01*
X675139Y-183991D01*
X675190Y-183921D01*
Y-183918D01*
X675194Y-183910D01*
X675201Y-183899D01*
X675208Y-183885D01*
X675216Y-183867D01*
X675227Y-183845D01*
X675248Y-183794D01*
X675270Y-183728D01*
X675288Y-183656D01*
X675303Y-183576D01*
X675307Y-183492D01*
Y-183466D01*
X675303Y-183444D01*
Y-183419D01*
X675299Y-183394D01*
X675285Y-183328D01*
X675267Y-183252D01*
X675238Y-183175D01*
X675198Y-183095D01*
X675176Y-183055D01*
X675146Y-183019D01*
X675143Y-183015D01*
X675139Y-183011D01*
X675128Y-183001D01*
X675117Y-182986D01*
X675099Y-182971D01*
X675077Y-182953D01*
X675056Y-182931D01*
X675026Y-182913D01*
X674994Y-182891D01*
X674957Y-182866D01*
X674921Y-182844D01*
X674877Y-182822D01*
X674830Y-182804D01*
X674779Y-182786D01*
X674724Y-182767D01*
X674666Y-182753D01*
X674750Y-182418D01*
X674753D01*
X674768Y-182422D01*
D02*
G37*
G36*
X668316Y-207484D02*
X668352D01*
X668389Y-207488D01*
X668436Y-207491D01*
X668483Y-207499D01*
X668589Y-207517D01*
X668705Y-207542D01*
X668822Y-207579D01*
X668935Y-207629D01*
X668938Y-207633D01*
X668949Y-207637D01*
X668964Y-207644D01*
X668982Y-207659D01*
X669007Y-207673D01*
X669037Y-207691D01*
X669102Y-207739D01*
X669175Y-207801D01*
X669248Y-207873D01*
X669321Y-207957D01*
X669382Y-208055D01*
X669386Y-208059D01*
X669390Y-208070D01*
X669397Y-208085D01*
X669408Y-208103D01*
X669419Y-208132D01*
X669430Y-208161D01*
X669444Y-208197D01*
X669459Y-208237D01*
X669473Y-208281D01*
X669488Y-208328D01*
X669510Y-208430D01*
X669528Y-208547D01*
X669535Y-208667D01*
Y-208703D01*
X669532Y-208729D01*
X669528Y-208762D01*
X669524Y-208802D01*
X669521Y-208842D01*
X669510Y-208889D01*
X669488Y-208987D01*
X669455Y-209097D01*
X669433Y-209151D01*
X669408Y-209202D01*
X669375Y-209253D01*
X669342Y-209304D01*
X669339Y-209308D01*
X669335Y-209315D01*
X669324Y-209329D01*
X669306Y-209348D01*
X669288Y-209366D01*
X669262Y-209391D01*
X669233Y-209417D01*
X669204Y-209446D01*
X669168Y-209475D01*
X669124Y-209504D01*
X669080Y-209537D01*
X669033Y-209566D01*
X668978Y-209592D01*
X668924Y-209621D01*
X668866Y-209643D01*
X668800Y-209664D01*
X668724Y-209337D01*
X668727D01*
X668735Y-209333D01*
X668749Y-209326D01*
X668767Y-209318D01*
X668789Y-209311D01*
X668818Y-209300D01*
X668877Y-209271D01*
X668942Y-209235D01*
X669007Y-209191D01*
X669069Y-209137D01*
X669124Y-209078D01*
X669131Y-209071D01*
X669146Y-209049D01*
X669164Y-209013D01*
X669190Y-208965D01*
X669211Y-208904D01*
X669233Y-208834D01*
X669248Y-208751D01*
X669251Y-208660D01*
Y-208630D01*
X669248Y-208612D01*
Y-208587D01*
X669244Y-208558D01*
X669233Y-208489D01*
X669219Y-208412D01*
X669193Y-208332D01*
X669157Y-208248D01*
X669109Y-208172D01*
Y-208168D01*
X669102Y-208165D01*
X669084Y-208139D01*
X669055Y-208106D01*
X669011Y-208066D01*
X668957Y-208019D01*
X668895Y-207975D01*
X668818Y-207935D01*
X668735Y-207899D01*
X668731D01*
X668724Y-207895D01*
X668713Y-207892D01*
X668694Y-207888D01*
X668673Y-207881D01*
X668647Y-207873D01*
X668585Y-207862D01*
X668512Y-207848D01*
X668432Y-207833D01*
X668345Y-207826D01*
X668250Y-207822D01*
X668247D01*
X668236D01*
X668218D01*
X668196D01*
X668170Y-207826D01*
X668138D01*
X668101Y-207830D01*
X668061Y-207833D01*
X667974Y-207844D01*
X667879Y-207862D01*
X667785Y-207884D01*
X667690Y-207913D01*
X667686D01*
X667679Y-207917D01*
X667668Y-207924D01*
X667650Y-207932D01*
X667606Y-207954D01*
X667555Y-207986D01*
X667497Y-208026D01*
X667435Y-208077D01*
X667380Y-208136D01*
X667330Y-208205D01*
Y-208208D01*
X667326Y-208216D01*
X667319Y-208226D01*
X667311Y-208241D01*
X667304Y-208259D01*
X667293Y-208281D01*
X667271Y-208332D01*
X667249Y-208398D01*
X667231Y-208470D01*
X667217Y-208551D01*
X667213Y-208634D01*
Y-208660D01*
X667217Y-208682D01*
Y-208707D01*
X667220Y-208733D01*
X667235Y-208798D01*
X667253Y-208874D01*
X667282Y-208951D01*
X667322Y-209031D01*
X667344Y-209071D01*
X667373Y-209107D01*
X667377Y-209111D01*
X667380Y-209115D01*
X667391Y-209126D01*
X667402Y-209140D01*
X667420Y-209155D01*
X667442Y-209173D01*
X667464Y-209195D01*
X667493Y-209213D01*
X667526Y-209235D01*
X667562Y-209260D01*
X667599Y-209282D01*
X667642Y-209304D01*
X667690Y-209322D01*
X667741Y-209340D01*
X667795Y-209359D01*
X667854Y-209373D01*
X667770Y-209708D01*
X667766D01*
X667752Y-209704D01*
X667730Y-209697D01*
X667701Y-209686D01*
X667668Y-209675D01*
X667628Y-209661D01*
X667584Y-209643D01*
X667537Y-209621D01*
X667435Y-209570D01*
X667333Y-209504D01*
X667282Y-209464D01*
X667231Y-209424D01*
X667188Y-209380D01*
X667144Y-209329D01*
X667140Y-209326D01*
X667133Y-209318D01*
X667126Y-209300D01*
X667111Y-209282D01*
X667093Y-209253D01*
X667075Y-209224D01*
X667057Y-209184D01*
X667038Y-209144D01*
X667016Y-209097D01*
X666998Y-209046D01*
X666980Y-208991D01*
X666962Y-208933D01*
X666947Y-208871D01*
X666940Y-208805D01*
X666933Y-208736D01*
X666929Y-208663D01*
Y-208623D01*
X666933Y-208594D01*
Y-208561D01*
X666936Y-208521D01*
X666944Y-208478D01*
X666951Y-208427D01*
X666969Y-208321D01*
X666998Y-208212D01*
X667038Y-208103D01*
X667064Y-208052D01*
X667093Y-208001D01*
X667097Y-207997D01*
X667100Y-207990D01*
X667111Y-207975D01*
X667126Y-207961D01*
X667140Y-207939D01*
X667162Y-207913D01*
X667188Y-207884D01*
X667217Y-207855D01*
X667249Y-207826D01*
X667282Y-207793D01*
X667366Y-207728D01*
X667464Y-207666D01*
X667573Y-207611D01*
X667577D01*
X667588Y-207604D01*
X667606Y-207600D01*
X667628Y-207590D01*
X667657Y-207582D01*
X667694Y-207571D01*
X667733Y-207557D01*
X667777Y-207546D01*
X667825Y-207535D01*
X667879Y-207520D01*
X667992Y-207502D01*
X668119Y-207488D01*
X668250Y-207480D01*
X668254D01*
X668269D01*
X668290D01*
X668316Y-207484D01*
D02*
G37*
G36*
X668869Y-210232D02*
X668877Y-210239D01*
X668880Y-210254D01*
X668891Y-210272D01*
X668902Y-210294D01*
X668917Y-210319D01*
X668953Y-210381D01*
X668993Y-210454D01*
X669044Y-210527D01*
X669102Y-210603D01*
X669164Y-210680D01*
X669168Y-210683D01*
X669171Y-210687D01*
X669182Y-210698D01*
X669193Y-210713D01*
X669230Y-210745D01*
X669273Y-210789D01*
X669324Y-210833D01*
X669382Y-210880D01*
X669441Y-210920D01*
X669503Y-210957D01*
Y-211157D01*
X666973D01*
Y-210847D01*
X668942D01*
X668938Y-210844D01*
X668924Y-210825D01*
X668902Y-210804D01*
X668877Y-210767D01*
X668844Y-210727D01*
X668807Y-210676D01*
X668767Y-210618D01*
X668727Y-210552D01*
Y-210549D01*
X668724Y-210545D01*
X668709Y-210523D01*
X668691Y-210487D01*
X668669Y-210443D01*
X668644Y-210392D01*
X668618Y-210338D01*
X668593Y-210283D01*
X668571Y-210228D01*
X668869D01*
Y-210232D01*
D02*
G37*
G36*
X668218Y-211939D02*
X668269D01*
X668327Y-211943D01*
X668396Y-211950D01*
X668472Y-211958D01*
X668556Y-211968D01*
X668640Y-211983D01*
X668731Y-212001D01*
X668818Y-212023D01*
X668906Y-212049D01*
X668989Y-212081D01*
X669069Y-212118D01*
X669146Y-212158D01*
X669211Y-212205D01*
X669215Y-212209D01*
X669222Y-212216D01*
X669237Y-212230D01*
X669259Y-212249D01*
X669280Y-212270D01*
X669302Y-212300D01*
X669332Y-212336D01*
X669357Y-212372D01*
X669382Y-212416D01*
X669412Y-212463D01*
X669433Y-212518D01*
X669459Y-212573D01*
X669477Y-212634D01*
X669492Y-212700D01*
X669499Y-212769D01*
X669503Y-212842D01*
Y-212871D01*
X669499Y-212893D01*
Y-212918D01*
X669495Y-212948D01*
X669481Y-213017D01*
X669462Y-213093D01*
X669433Y-213173D01*
X669390Y-213253D01*
X669364Y-213293D01*
X669335Y-213330D01*
X669332Y-213333D01*
X669328Y-213337D01*
X669317Y-213348D01*
X669306Y-213359D01*
X669288Y-213377D01*
X669266Y-213392D01*
X669215Y-213432D01*
X669149Y-213472D01*
X669069Y-213508D01*
X668978Y-213541D01*
X668877Y-213563D01*
X668851Y-213253D01*
X668855D01*
X668858Y-213250D01*
X668880Y-213246D01*
X668913Y-213235D01*
X668953Y-213221D01*
X668997Y-213206D01*
X669040Y-213184D01*
X669080Y-213159D01*
X669113Y-213133D01*
X669120Y-213126D01*
X669135Y-213111D01*
X669157Y-213086D01*
X669182Y-213050D01*
X669204Y-213002D01*
X669226Y-212951D01*
X669241Y-212889D01*
X669248Y-212824D01*
Y-212798D01*
X669244Y-212769D01*
X669237Y-212737D01*
X669226Y-212693D01*
X669211Y-212649D01*
X669193Y-212605D01*
X669164Y-212562D01*
X669160Y-212554D01*
X669146Y-212536D01*
X669120Y-212511D01*
X669084Y-212478D01*
X669040Y-212442D01*
X668989Y-212402D01*
X668924Y-212365D01*
X668851Y-212329D01*
X668847D01*
X668840Y-212325D01*
X668829Y-212321D01*
X668815Y-212314D01*
X668793Y-212311D01*
X668767Y-212303D01*
X668738Y-212296D01*
X668702Y-212289D01*
X668662Y-212278D01*
X668618Y-212270D01*
X668571Y-212263D01*
X668520Y-212260D01*
X668462Y-212252D01*
X668403Y-212249D01*
X668338Y-212245D01*
X668272D01*
X668276Y-212249D01*
X668298Y-212263D01*
X668327Y-212289D01*
X668363Y-212321D01*
X668407Y-212358D01*
X668447Y-212405D01*
X668487Y-212456D01*
X668523Y-212514D01*
Y-212518D01*
X668527Y-212522D01*
X668538Y-212544D01*
X668549Y-212576D01*
X668567Y-212620D01*
X668582Y-212671D01*
X668593Y-212729D01*
X668604Y-212791D01*
X668607Y-212857D01*
Y-212886D01*
X668604Y-212908D01*
X668600Y-212937D01*
X668596Y-212966D01*
X668589Y-213002D01*
X668578Y-213039D01*
X668552Y-213122D01*
X668534Y-213166D01*
X668509Y-213210D01*
X668483Y-213253D01*
X668454Y-213301D01*
X668418Y-213344D01*
X668378Y-213384D01*
X668374Y-213388D01*
X668367Y-213395D01*
X668356Y-213406D01*
X668338Y-213417D01*
X668312Y-213435D01*
X668287Y-213454D01*
X668254Y-213472D01*
X668218Y-213494D01*
X668178Y-213515D01*
X668134Y-213534D01*
X668083Y-213552D01*
X668032Y-213570D01*
X667977Y-213581D01*
X667915Y-213592D01*
X667854Y-213599D01*
X667788Y-213603D01*
X667785D01*
X667777D01*
X667766D01*
X667748D01*
X667726Y-213599D01*
X667704D01*
X667646Y-213588D01*
X667577Y-213577D01*
X667504Y-213559D01*
X667424Y-213534D01*
X667348Y-213497D01*
X667344D01*
X667340Y-213494D01*
X667330Y-213486D01*
X667315Y-213479D01*
X667278Y-213457D01*
X667231Y-213424D01*
X667180Y-213384D01*
X667129Y-213337D01*
X667078Y-213279D01*
X667035Y-213217D01*
Y-213213D01*
X667031Y-213210D01*
X667024Y-213199D01*
X667020Y-213184D01*
X667002Y-213148D01*
X666984Y-213101D01*
X666962Y-213039D01*
X666947Y-212969D01*
X666933Y-212893D01*
X666929Y-212809D01*
Y-212791D01*
X666933Y-212773D01*
Y-212744D01*
X666936Y-212711D01*
X666944Y-212675D01*
X666955Y-212631D01*
X666965Y-212587D01*
X666980Y-212536D01*
X666998Y-212485D01*
X667020Y-212434D01*
X667049Y-212380D01*
X667082Y-212329D01*
X667118Y-212278D01*
X667162Y-212227D01*
X667213Y-212179D01*
X667217Y-212176D01*
X667228Y-212169D01*
X667242Y-212158D01*
X667268Y-212143D01*
X667300Y-212121D01*
X667337Y-212103D01*
X667384Y-212081D01*
X667435Y-212059D01*
X667497Y-212034D01*
X667566Y-212012D01*
X667642Y-211994D01*
X667726Y-211976D01*
X667821Y-211958D01*
X667923Y-211947D01*
X668032Y-211939D01*
X668149Y-211936D01*
X668152D01*
X668156D01*
X668167D01*
X668181D01*
X668218Y-211939D01*
D02*
G37*
G36*
X664548Y-228394D02*
Y-228405D01*
Y-228419D01*
X664545Y-228441D01*
Y-228470D01*
X664541Y-228507D01*
X664538Y-228547D01*
X664534Y-228590D01*
X664527Y-228641D01*
X664519Y-228692D01*
X664508Y-228754D01*
X664498Y-228816D01*
X664487Y-228882D01*
X664472Y-228954D01*
X664436Y-229103D01*
Y-229107D01*
X664432Y-229122D01*
X664425Y-229144D01*
X664414Y-229176D01*
X664403Y-229213D01*
X664388Y-229256D01*
X664374Y-229307D01*
X664352Y-229362D01*
X664330Y-229424D01*
X664308Y-229486D01*
X664254Y-229624D01*
X664188Y-229770D01*
X664115Y-229915D01*
X664112Y-229919D01*
X664104Y-229934D01*
X664093Y-229952D01*
X664079Y-229981D01*
X664061Y-230013D01*
X664035Y-230054D01*
X664010Y-230097D01*
X663981Y-230145D01*
X663911Y-230250D01*
X663839Y-230359D01*
X663755Y-230472D01*
X663668Y-230578D01*
X664902D01*
Y-230876D01*
X663271D01*
Y-230632D01*
X663274Y-230629D01*
X663282Y-230621D01*
X663296Y-230607D01*
X663311Y-230585D01*
X663333Y-230559D01*
X663362Y-230530D01*
X663391Y-230494D01*
X663424Y-230450D01*
X663456Y-230407D01*
X663496Y-230356D01*
X663537Y-230297D01*
X663577Y-230239D01*
X663620Y-230174D01*
X663664Y-230105D01*
X663708Y-230028D01*
X663751Y-229952D01*
X663755Y-229948D01*
X663762Y-229934D01*
X663773Y-229912D01*
X663791Y-229879D01*
X663810Y-229839D01*
X663831Y-229795D01*
X663857Y-229744D01*
X663882Y-229686D01*
X663911Y-229620D01*
X663944Y-229555D01*
X663973Y-229482D01*
X664003Y-229406D01*
X664061Y-229249D01*
X664115Y-229082D01*
Y-229078D01*
X664119Y-229067D01*
X664123Y-229049D01*
X664130Y-229027D01*
X664137Y-228998D01*
X664144Y-228962D01*
X664155Y-228922D01*
X664163Y-228878D01*
X664174Y-228827D01*
X664185Y-228772D01*
X664203Y-228656D01*
X664221Y-228528D01*
X664232Y-228390D01*
X664548D01*
Y-228394D01*
D02*
G37*
G36*
X668356Y-228350D02*
X668385D01*
X668421Y-228354D01*
X668462Y-228357D01*
X668502Y-228361D01*
X668593Y-228376D01*
X668691Y-228397D01*
X668785Y-228427D01*
X668876Y-228467D01*
X668880D01*
X668887Y-228474D01*
X668898Y-228481D01*
X668913Y-228488D01*
X668953Y-228518D01*
X669000Y-228557D01*
X669055Y-228608D01*
X669106Y-228667D01*
X669157Y-228740D01*
X669197Y-228820D01*
Y-228823D01*
X669200Y-228831D01*
X669204Y-228845D01*
X669211Y-228863D01*
X669219Y-228885D01*
X669226Y-228914D01*
X669237Y-228947D01*
X669244Y-228987D01*
X669251Y-229031D01*
X669262Y-229078D01*
X669270Y-229129D01*
X669277Y-229184D01*
X669284Y-229245D01*
X669288Y-229311D01*
X669291Y-229380D01*
Y-229453D01*
Y-230909D01*
X668957D01*
Y-229453D01*
Y-229449D01*
Y-229438D01*
Y-229420D01*
Y-229398D01*
X668953Y-229373D01*
Y-229340D01*
X668949Y-229271D01*
X668942Y-229191D01*
X668931Y-229111D01*
X668917Y-229034D01*
X668909Y-229002D01*
X668898Y-228969D01*
X668895Y-228962D01*
X668887Y-228943D01*
X668869Y-228918D01*
X668847Y-228882D01*
X668822Y-228845D01*
X668785Y-228805D01*
X668742Y-228765D01*
X668691Y-228732D01*
X668683Y-228729D01*
X668665Y-228718D01*
X668633Y-228707D01*
X668589Y-228692D01*
X668538Y-228674D01*
X668472Y-228663D01*
X668403Y-228652D01*
X668327Y-228648D01*
X668290D01*
X668268Y-228652D01*
X668236D01*
X668203Y-228656D01*
X668123Y-228670D01*
X668036Y-228689D01*
X667952Y-228718D01*
X667872Y-228758D01*
X667835Y-228783D01*
X667803Y-228812D01*
X667799Y-228816D01*
X667795Y-228820D01*
X667788Y-228831D01*
X667777Y-228845D01*
X667766Y-228867D01*
X667752Y-228889D01*
X667737Y-228922D01*
X667723Y-228954D01*
X667708Y-228994D01*
X667697Y-229042D01*
X667683Y-229096D01*
X667672Y-229154D01*
X667661Y-229220D01*
X667653Y-229289D01*
X667646Y-229369D01*
Y-229453D01*
Y-230909D01*
X667311D01*
Y-229453D01*
Y-229449D01*
Y-229435D01*
Y-229417D01*
Y-229391D01*
X667315Y-229358D01*
Y-229322D01*
X667318Y-229278D01*
X667322Y-229235D01*
X667333Y-229136D01*
X667348Y-229034D01*
X667370Y-228936D01*
X667384Y-228889D01*
X667399Y-228845D01*
Y-228841D01*
X667402Y-228834D01*
X667410Y-228823D01*
X667417Y-228809D01*
X667439Y-228769D01*
X667471Y-228718D01*
X667515Y-228660D01*
X667566Y-228601D01*
X667631Y-228539D01*
X667712Y-228485D01*
X667715D01*
X667723Y-228478D01*
X667733Y-228474D01*
X667752Y-228463D01*
X667773Y-228452D01*
X667803Y-228441D01*
X667832Y-228430D01*
X667868Y-228416D01*
X667908Y-228401D01*
X667952Y-228390D01*
X667999Y-228379D01*
X668054Y-228368D01*
X668108Y-228361D01*
X668167Y-228354D01*
X668298Y-228346D01*
X668330D01*
X668356Y-228350D01*
D02*
G37*
G36*
X666026Y-230359D02*
X666030Y-230356D01*
X666048Y-230341D01*
X666070Y-230319D01*
X666106Y-230294D01*
X666146Y-230261D01*
X666197Y-230225D01*
X666256Y-230185D01*
X666321Y-230145D01*
X666325D01*
X666328Y-230141D01*
X666350Y-230126D01*
X666387Y-230108D01*
X666430Y-230086D01*
X666481Y-230061D01*
X666536Y-230035D01*
X666590Y-230010D01*
X666645Y-229988D01*
Y-230287D01*
X666642D01*
X666634Y-230294D01*
X666620Y-230297D01*
X666601Y-230308D01*
X666580Y-230319D01*
X666554Y-230334D01*
X666492Y-230370D01*
X666419Y-230410D01*
X666347Y-230461D01*
X666270Y-230520D01*
X666194Y-230581D01*
X666190Y-230585D01*
X666187Y-230589D01*
X666176Y-230600D01*
X666161Y-230610D01*
X666128Y-230647D01*
X666085Y-230691D01*
X666041Y-230742D01*
X665993Y-230800D01*
X665953Y-230858D01*
X665917Y-230920D01*
X665717D01*
Y-228390D01*
X666026D01*
Y-230359D01*
D02*
G37*
G36*
X616209Y-190601D02*
X616242D01*
X616282Y-190605D01*
X616326Y-190612D01*
X616376Y-190619D01*
X616482Y-190638D01*
X616591Y-190667D01*
X616700Y-190707D01*
X616751Y-190732D01*
X616802Y-190761D01*
X616806Y-190765D01*
X616813Y-190769D01*
X616828Y-190779D01*
X616842Y-190794D01*
X616864Y-190809D01*
X616890Y-190830D01*
X616919Y-190856D01*
X616948Y-190885D01*
X616977Y-190918D01*
X617010Y-190951D01*
X617075Y-191034D01*
X617137Y-191132D01*
X617192Y-191242D01*
Y-191245D01*
X617199Y-191256D01*
X617203Y-191274D01*
X617214Y-191296D01*
X617221Y-191325D01*
X617232Y-191362D01*
X617246Y-191402D01*
X617257Y-191446D01*
X617268Y-191493D01*
X617283Y-191548D01*
X617301Y-191660D01*
X617315Y-191788D01*
X617323Y-191919D01*
Y-191922D01*
Y-191937D01*
Y-191959D01*
X617319Y-191984D01*
Y-192021D01*
X617315Y-192057D01*
X617312Y-192104D01*
X617305Y-192152D01*
X617286Y-192257D01*
X617261Y-192374D01*
X617225Y-192490D01*
X617174Y-192603D01*
X617170Y-192607D01*
X617166Y-192618D01*
X617159Y-192632D01*
X617144Y-192650D01*
X617130Y-192676D01*
X617112Y-192705D01*
X617064Y-192771D01*
X617002Y-192843D01*
X616930Y-192916D01*
X616846Y-192989D01*
X616748Y-193051D01*
X616744Y-193054D01*
X616733Y-193058D01*
X616719Y-193065D01*
X616700Y-193076D01*
X616671Y-193087D01*
X616642Y-193098D01*
X616606Y-193113D01*
X616566Y-193127D01*
X616522Y-193142D01*
X616475Y-193156D01*
X616373Y-193178D01*
X616256Y-193196D01*
X616136Y-193204D01*
X616100D01*
X616074Y-193200D01*
X616042Y-193196D01*
X616002Y-193193D01*
X615962Y-193189D01*
X615914Y-193178D01*
X615816Y-193156D01*
X615707Y-193124D01*
X615652Y-193102D01*
X615601Y-193076D01*
X615550Y-193043D01*
X615499Y-193011D01*
X615496Y-193007D01*
X615488Y-193003D01*
X615474Y-192993D01*
X615455Y-192974D01*
X615437Y-192956D01*
X615412Y-192931D01*
X615386Y-192902D01*
X615357Y-192873D01*
X615328Y-192836D01*
X615299Y-192792D01*
X615266Y-192749D01*
X615237Y-192701D01*
X615212Y-192647D01*
X615182Y-192592D01*
X615161Y-192534D01*
X615139Y-192468D01*
X615466Y-192392D01*
Y-192396D01*
X615470Y-192403D01*
X615477Y-192418D01*
X615485Y-192436D01*
X615492Y-192457D01*
X615503Y-192487D01*
X615532Y-192545D01*
X615568Y-192610D01*
X615612Y-192676D01*
X615667Y-192738D01*
X615725Y-192792D01*
X615732Y-192800D01*
X615754Y-192814D01*
X615790Y-192832D01*
X615838Y-192858D01*
X615900Y-192880D01*
X615969Y-192902D01*
X616052Y-192916D01*
X616144Y-192920D01*
X616173D01*
X616191Y-192916D01*
X616216D01*
X616245Y-192912D01*
X616315Y-192902D01*
X616391Y-192887D01*
X616471Y-192861D01*
X616555Y-192825D01*
X616631Y-192778D01*
X616635D01*
X616639Y-192771D01*
X616664Y-192752D01*
X616697Y-192723D01*
X616737Y-192680D01*
X616784Y-192625D01*
X616828Y-192563D01*
X616868Y-192487D01*
X616904Y-192403D01*
Y-192399D01*
X616908Y-192392D01*
X616912Y-192381D01*
X616915Y-192363D01*
X616922Y-192341D01*
X616930Y-192315D01*
X616941Y-192254D01*
X616955Y-192181D01*
X616970Y-192101D01*
X616977Y-192013D01*
X616981Y-191919D01*
Y-191915D01*
Y-191904D01*
Y-191886D01*
Y-191864D01*
X616977Y-191839D01*
Y-191806D01*
X616973Y-191770D01*
X616970Y-191729D01*
X616959Y-191642D01*
X616941Y-191548D01*
X616919Y-191453D01*
X616890Y-191358D01*
Y-191355D01*
X616886Y-191347D01*
X616879Y-191336D01*
X616872Y-191318D01*
X616850Y-191274D01*
X616817Y-191224D01*
X616777Y-191165D01*
X616726Y-191103D01*
X616668Y-191049D01*
X616599Y-190998D01*
X616595D01*
X616588Y-190994D01*
X616577Y-190987D01*
X616562Y-190980D01*
X616544Y-190972D01*
X616522Y-190962D01*
X616471Y-190940D01*
X616406Y-190918D01*
X616333Y-190900D01*
X616253Y-190885D01*
X616169Y-190881D01*
X616144D01*
X616122Y-190885D01*
X616096D01*
X616071Y-190889D01*
X616005Y-190903D01*
X615929Y-190921D01*
X615852Y-190951D01*
X615772Y-190991D01*
X615732Y-191012D01*
X615696Y-191042D01*
X615692Y-191045D01*
X615689Y-191049D01*
X615677Y-191060D01*
X615663Y-191071D01*
X615648Y-191089D01*
X615630Y-191111D01*
X615608Y-191132D01*
X615590Y-191162D01*
X615568Y-191194D01*
X615543Y-191231D01*
X615521Y-191267D01*
X615499Y-191311D01*
X615481Y-191358D01*
X615463Y-191409D01*
X615445Y-191464D01*
X615430Y-191522D01*
X615095Y-191438D01*
Y-191435D01*
X615099Y-191420D01*
X615106Y-191398D01*
X615117Y-191369D01*
X615128Y-191336D01*
X615142Y-191296D01*
X615161Y-191253D01*
X615182Y-191205D01*
X615234Y-191103D01*
X615299Y-191001D01*
X615339Y-190951D01*
X615379Y-190900D01*
X615423Y-190856D01*
X615474Y-190812D01*
X615477Y-190809D01*
X615485Y-190801D01*
X615503Y-190794D01*
X615521Y-190779D01*
X615550Y-190761D01*
X615579Y-190743D01*
X615619Y-190725D01*
X615659Y-190707D01*
X615707Y-190685D01*
X615758Y-190667D01*
X615812Y-190648D01*
X615871Y-190630D01*
X615932Y-190616D01*
X615998Y-190608D01*
X616067Y-190601D01*
X616140Y-190597D01*
X616180D01*
X616209Y-190601D01*
D02*
G37*
G36*
X613956Y-192610D02*
X613960Y-192607D01*
X613978Y-192592D01*
X614000Y-192570D01*
X614036Y-192545D01*
X614076Y-192512D01*
X614127Y-192476D01*
X614185Y-192436D01*
X614251Y-192396D01*
X614254D01*
X614258Y-192392D01*
X614280Y-192377D01*
X614316Y-192359D01*
X614360Y-192337D01*
X614411Y-192312D01*
X614465Y-192286D01*
X614520Y-192261D01*
X614575Y-192239D01*
Y-192538D01*
X614571D01*
X614564Y-192545D01*
X614549Y-192549D01*
X614531Y-192559D01*
X614509Y-192570D01*
X614484Y-192585D01*
X614422Y-192621D01*
X614349Y-192661D01*
X614276Y-192712D01*
X614200Y-192771D01*
X614123Y-192832D01*
X614120Y-192836D01*
X614116Y-192840D01*
X614105Y-192851D01*
X614090Y-192861D01*
X614058Y-192898D01*
X614014Y-192942D01*
X613970Y-192993D01*
X613923Y-193051D01*
X613883Y-193109D01*
X613847Y-193171D01*
X613646D01*
Y-190641D01*
X613956D01*
Y-192610D01*
D02*
G37*
G36*
X612092Y-190601D02*
X612121Y-190605D01*
X612158Y-190612D01*
X612198Y-190619D01*
X612241Y-190630D01*
X612285Y-190645D01*
X612332Y-190659D01*
X612380Y-190681D01*
X612427Y-190707D01*
X612474Y-190736D01*
X612522Y-190772D01*
X612565Y-190812D01*
X612605Y-190856D01*
X612609Y-190859D01*
X612616Y-190870D01*
X612627Y-190889D01*
X612645Y-190918D01*
X612664Y-190951D01*
X612682Y-190994D01*
X612707Y-191045D01*
X612729Y-191103D01*
X612751Y-191169D01*
X612773Y-191245D01*
X612795Y-191329D01*
X612813Y-191424D01*
X612831Y-191526D01*
X612842Y-191635D01*
X612849Y-191755D01*
X612853Y-191882D01*
Y-191886D01*
Y-191901D01*
Y-191926D01*
Y-191955D01*
X612849Y-191995D01*
Y-192039D01*
X612846Y-192086D01*
X612842Y-192141D01*
X612831Y-192254D01*
X612813Y-192374D01*
X612791Y-192494D01*
X612777Y-192549D01*
X612762Y-192603D01*
Y-192607D01*
X612758Y-192614D01*
X612751Y-192629D01*
X612744Y-192647D01*
X612736Y-192672D01*
X612722Y-192698D01*
X612693Y-192760D01*
X612656Y-192825D01*
X612609Y-192894D01*
X612554Y-192964D01*
X612489Y-193022D01*
X612485D01*
X612482Y-193029D01*
X612471Y-193036D01*
X612456Y-193043D01*
X612438Y-193058D01*
X612416Y-193069D01*
X612361Y-193098D01*
X612296Y-193124D01*
X612219Y-193149D01*
X612128Y-193164D01*
X612030Y-193171D01*
X611998D01*
X611958Y-193167D01*
X611910Y-193160D01*
X611856Y-193149D01*
X611797Y-193134D01*
X611735Y-193116D01*
X611677Y-193087D01*
X611673D01*
X611670Y-193084D01*
X611652Y-193073D01*
X611623Y-193054D01*
X611586Y-193029D01*
X611546Y-192993D01*
X611503Y-192953D01*
X611462Y-192905D01*
X611422Y-192851D01*
X611419Y-192843D01*
X611404Y-192825D01*
X611390Y-192792D01*
X611364Y-192745D01*
X611342Y-192691D01*
X611313Y-192629D01*
X611288Y-192556D01*
X611266Y-192476D01*
Y-192472D01*
X611262Y-192465D01*
X611259Y-192454D01*
X611255Y-192436D01*
X611251Y-192414D01*
X611248Y-192388D01*
X611240Y-192356D01*
X611237Y-192319D01*
X611230Y-192279D01*
X611226Y-192236D01*
X611222Y-192184D01*
X611215Y-192133D01*
X611211Y-192075D01*
Y-192017D01*
X611208Y-191952D01*
Y-191882D01*
Y-191879D01*
Y-191864D01*
Y-191839D01*
Y-191810D01*
X611211Y-191770D01*
Y-191726D01*
X611215Y-191679D01*
X611219Y-191628D01*
X611230Y-191511D01*
X611248Y-191391D01*
X611270Y-191274D01*
X611284Y-191220D01*
X611302Y-191165D01*
Y-191162D01*
X611306Y-191154D01*
X611313Y-191140D01*
X611320Y-191122D01*
X611328Y-191096D01*
X611342Y-191071D01*
X611371Y-191009D01*
X611408Y-190943D01*
X611455Y-190870D01*
X611510Y-190805D01*
X611575Y-190743D01*
X611579D01*
X611583Y-190736D01*
X611593Y-190728D01*
X611608Y-190721D01*
X611626Y-190710D01*
X611644Y-190696D01*
X611699Y-190670D01*
X611764Y-190645D01*
X611841Y-190619D01*
X611932Y-190605D01*
X612030Y-190597D01*
X612067D01*
X612092Y-190601D01*
D02*
G37*
G36*
X596019Y-183257D02*
X594050D01*
X594054Y-183261D01*
X594068Y-183279D01*
X594090Y-183301D01*
X594116Y-183337D01*
X594148Y-183378D01*
X594185Y-183429D01*
X594225Y-183487D01*
X594265Y-183552D01*
Y-183556D01*
X594269Y-183560D01*
X594283Y-183581D01*
X594301Y-183618D01*
X594323Y-183661D01*
X594349Y-183712D01*
X594374Y-183767D01*
X594400Y-183822D01*
X594421Y-183876D01*
X594123D01*
Y-183873D01*
X594116Y-183865D01*
X594112Y-183851D01*
X594101Y-183833D01*
X594090Y-183811D01*
X594076Y-183785D01*
X594039Y-183723D01*
X593999Y-183651D01*
X593948Y-183578D01*
X593890Y-183501D01*
X593828Y-183425D01*
X593824Y-183421D01*
X593821Y-183418D01*
X593810Y-183407D01*
X593799Y-183392D01*
X593763Y-183359D01*
X593719Y-183316D01*
X593668Y-183272D01*
X593610Y-183225D01*
X593551Y-183185D01*
X593490Y-183148D01*
Y-182948D01*
X596019D01*
Y-183257D01*
D02*
G37*
G36*
Y-185216D02*
X594050D01*
X594054Y-185219D01*
X594068Y-185238D01*
X594090Y-185259D01*
X594116Y-185296D01*
X594148Y-185336D01*
X594185Y-185387D01*
X594225Y-185445D01*
X594265Y-185511D01*
Y-185514D01*
X594269Y-185518D01*
X594283Y-185540D01*
X594301Y-185576D01*
X594323Y-185620D01*
X594349Y-185671D01*
X594374Y-185725D01*
X594400Y-185780D01*
X594421Y-185835D01*
X594123D01*
Y-185831D01*
X594116Y-185824D01*
X594112Y-185809D01*
X594101Y-185791D01*
X594090Y-185769D01*
X594076Y-185743D01*
X594039Y-185682D01*
X593999Y-185609D01*
X593948Y-185536D01*
X593890Y-185460D01*
X593828Y-185383D01*
X593824Y-185380D01*
X593821Y-185376D01*
X593810Y-185365D01*
X593799Y-185350D01*
X593763Y-185318D01*
X593719Y-185274D01*
X593668Y-185230D01*
X593610Y-185183D01*
X593551Y-185143D01*
X593490Y-185107D01*
Y-184906D01*
X596019D01*
Y-185216D01*
D02*
G37*
G36*
X595240Y-186359D02*
X595262Y-186366D01*
X595291Y-186377D01*
X595324Y-186388D01*
X595364Y-186402D01*
X595408Y-186421D01*
X595455Y-186442D01*
X595557Y-186493D01*
X595659Y-186559D01*
X595710Y-186599D01*
X595761Y-186639D01*
X595805Y-186683D01*
X595848Y-186734D01*
X595852Y-186737D01*
X595859Y-186744D01*
X595866Y-186763D01*
X595881Y-186781D01*
X595899Y-186810D01*
X595917Y-186839D01*
X595936Y-186879D01*
X595954Y-186919D01*
X595976Y-186967D01*
X595994Y-187018D01*
X596012Y-187072D01*
X596030Y-187130D01*
X596045Y-187192D01*
X596052Y-187258D01*
X596059Y-187327D01*
X596063Y-187400D01*
Y-187440D01*
X596059Y-187469D01*
Y-187502D01*
X596056Y-187542D01*
X596048Y-187585D01*
X596041Y-187636D01*
X596023Y-187742D01*
X595994Y-187851D01*
X595954Y-187960D01*
X595928Y-188011D01*
X595899Y-188062D01*
X595896Y-188066D01*
X595892Y-188073D01*
X595881Y-188088D01*
X595866Y-188102D01*
X595852Y-188124D01*
X595830Y-188150D01*
X595805Y-188179D01*
X595776Y-188208D01*
X595743Y-188237D01*
X595710Y-188270D01*
X595626Y-188335D01*
X595528Y-188397D01*
X595419Y-188452D01*
X595415D01*
X595404Y-188459D01*
X595386Y-188463D01*
X595364Y-188473D01*
X595335Y-188481D01*
X595299Y-188492D01*
X595259Y-188506D01*
X595215Y-188517D01*
X595168Y-188528D01*
X595113Y-188543D01*
X595000Y-188561D01*
X594873Y-188575D01*
X594742Y-188583D01*
X594738D01*
X594724D01*
X594702D01*
X594676Y-188579D01*
X594640D01*
X594603Y-188575D01*
X594556Y-188572D01*
X594509Y-188565D01*
X594403Y-188546D01*
X594287Y-188521D01*
X594170Y-188484D01*
X594057Y-188434D01*
X594054Y-188430D01*
X594043Y-188426D01*
X594028Y-188419D01*
X594010Y-188404D01*
X593985Y-188390D01*
X593956Y-188372D01*
X593890Y-188324D01*
X593817Y-188262D01*
X593744Y-188190D01*
X593672Y-188106D01*
X593610Y-188008D01*
X593606Y-188004D01*
X593602Y-187993D01*
X593595Y-187978D01*
X593584Y-187960D01*
X593573Y-187931D01*
X593562Y-187902D01*
X593548Y-187866D01*
X593533Y-187826D01*
X593519Y-187782D01*
X593504Y-187735D01*
X593482Y-187633D01*
X593464Y-187516D01*
X593457Y-187396D01*
Y-187360D01*
X593460Y-187334D01*
X593464Y-187301D01*
X593468Y-187261D01*
X593471Y-187221D01*
X593482Y-187174D01*
X593504Y-187076D01*
X593537Y-186967D01*
X593559Y-186912D01*
X593584Y-186861D01*
X593617Y-186810D01*
X593650Y-186759D01*
X593653Y-186755D01*
X593657Y-186748D01*
X593668Y-186734D01*
X593686Y-186715D01*
X593704Y-186697D01*
X593730Y-186672D01*
X593759Y-186646D01*
X593788Y-186617D01*
X593824Y-186588D01*
X593868Y-186559D01*
X593912Y-186526D01*
X593959Y-186497D01*
X594014Y-186471D01*
X594068Y-186442D01*
X594127Y-186421D01*
X594192Y-186399D01*
X594269Y-186726D01*
X594265D01*
X594258Y-186730D01*
X594243Y-186737D01*
X594225Y-186744D01*
X594203Y-186752D01*
X594174Y-186763D01*
X594116Y-186792D01*
X594050Y-186828D01*
X593985Y-186872D01*
X593923Y-186926D01*
X593868Y-186985D01*
X593861Y-186992D01*
X593846Y-187014D01*
X593828Y-187050D01*
X593803Y-187098D01*
X593781Y-187160D01*
X593759Y-187229D01*
X593744Y-187312D01*
X593741Y-187403D01*
Y-187433D01*
X593744Y-187451D01*
Y-187476D01*
X593748Y-187505D01*
X593759Y-187574D01*
X593774Y-187651D01*
X593799Y-187731D01*
X593835Y-187815D01*
X593883Y-187891D01*
Y-187895D01*
X593890Y-187898D01*
X593908Y-187924D01*
X593937Y-187957D01*
X593981Y-187997D01*
X594036Y-188044D01*
X594097Y-188088D01*
X594174Y-188128D01*
X594258Y-188164D01*
X594261D01*
X594269Y-188168D01*
X594279Y-188171D01*
X594298Y-188175D01*
X594319Y-188182D01*
X594345Y-188190D01*
X594407Y-188200D01*
X594480Y-188215D01*
X594560Y-188230D01*
X594647Y-188237D01*
X594742Y-188241D01*
X594745D01*
X594756D01*
X594774D01*
X594796D01*
X594822Y-188237D01*
X594855D01*
X594891Y-188233D01*
X594931Y-188230D01*
X595018Y-188219D01*
X595113Y-188200D01*
X595208Y-188179D01*
X595302Y-188150D01*
X595306D01*
X595313Y-188146D01*
X595324Y-188139D01*
X595342Y-188131D01*
X595386Y-188110D01*
X595437Y-188077D01*
X595495Y-188037D01*
X595557Y-187986D01*
X595612Y-187927D01*
X595663Y-187858D01*
Y-187855D01*
X595666Y-187847D01*
X595674Y-187837D01*
X595681Y-187822D01*
X595688Y-187804D01*
X595699Y-187782D01*
X595721Y-187731D01*
X595743Y-187665D01*
X595761Y-187593D01*
X595776Y-187513D01*
X595779Y-187429D01*
Y-187403D01*
X595776Y-187381D01*
Y-187356D01*
X595772Y-187331D01*
X595757Y-187265D01*
X595739Y-187189D01*
X595710Y-187112D01*
X595670Y-187032D01*
X595648Y-186992D01*
X595619Y-186956D01*
X595615Y-186952D01*
X595612Y-186948D01*
X595601Y-186937D01*
X595590Y-186923D01*
X595572Y-186908D01*
X595550Y-186890D01*
X595528Y-186868D01*
X595499Y-186850D01*
X595466Y-186828D01*
X595430Y-186803D01*
X595393Y-186781D01*
X595350Y-186759D01*
X595302Y-186741D01*
X595251Y-186723D01*
X595197Y-186705D01*
X595139Y-186690D01*
X595222Y-186355D01*
X595226D01*
X595240Y-186359D01*
D02*
G37*
G36*
X675796Y-207484D02*
X675833D01*
X675869Y-207488D01*
X675916Y-207491D01*
X675964Y-207499D01*
X676069Y-207517D01*
X676186Y-207542D01*
X676302Y-207579D01*
X676415Y-207629D01*
X676419Y-207633D01*
X676430Y-207637D01*
X676444Y-207644D01*
X676462Y-207659D01*
X676488Y-207673D01*
X676517Y-207691D01*
X676582Y-207739D01*
X676655Y-207801D01*
X676728Y-207873D01*
X676801Y-207957D01*
X676863Y-208055D01*
X676866Y-208059D01*
X676870Y-208070D01*
X676877Y-208085D01*
X676888Y-208103D01*
X676899Y-208132D01*
X676910Y-208161D01*
X676925Y-208197D01*
X676939Y-208237D01*
X676954Y-208281D01*
X676968Y-208328D01*
X676990Y-208430D01*
X677008Y-208547D01*
X677016Y-208667D01*
Y-208703D01*
X677012Y-208729D01*
X677008Y-208762D01*
X677005Y-208802D01*
X677001Y-208842D01*
X676990Y-208889D01*
X676968Y-208987D01*
X676936Y-209097D01*
X676914Y-209151D01*
X676888Y-209202D01*
X676856Y-209253D01*
X676823Y-209304D01*
X676819Y-209308D01*
X676815Y-209315D01*
X676804Y-209329D01*
X676786Y-209348D01*
X676768Y-209366D01*
X676743Y-209391D01*
X676714Y-209417D01*
X676684Y-209446D01*
X676648Y-209475D01*
X676604Y-209504D01*
X676561Y-209537D01*
X676513Y-209566D01*
X676459Y-209592D01*
X676404Y-209621D01*
X676346Y-209643D01*
X676280Y-209664D01*
X676204Y-209337D01*
X676208D01*
X676215Y-209333D01*
X676229Y-209326D01*
X676248Y-209318D01*
X676269Y-209311D01*
X676299Y-209300D01*
X676357Y-209271D01*
X676422Y-209235D01*
X676488Y-209191D01*
X676550Y-209137D01*
X676604Y-209078D01*
X676612Y-209071D01*
X676626Y-209049D01*
X676644Y-209013D01*
X676670Y-208965D01*
X676692Y-208904D01*
X676714Y-208834D01*
X676728Y-208751D01*
X676732Y-208660D01*
Y-208630D01*
X676728Y-208612D01*
Y-208587D01*
X676724Y-208558D01*
X676714Y-208489D01*
X676699Y-208412D01*
X676674Y-208332D01*
X676637Y-208248D01*
X676590Y-208172D01*
Y-208168D01*
X676582Y-208165D01*
X676564Y-208139D01*
X676535Y-208106D01*
X676491Y-208066D01*
X676437Y-208019D01*
X676375Y-207975D01*
X676299Y-207935D01*
X676215Y-207899D01*
X676211D01*
X676204Y-207895D01*
X676193Y-207892D01*
X676175Y-207888D01*
X676153Y-207881D01*
X676127Y-207873D01*
X676066Y-207862D01*
X675993Y-207848D01*
X675913Y-207833D01*
X675825Y-207826D01*
X675731Y-207822D01*
X675727D01*
X675716D01*
X675698D01*
X675676D01*
X675651Y-207826D01*
X675618D01*
X675582Y-207830D01*
X675541Y-207833D01*
X675454Y-207844D01*
X675359Y-207862D01*
X675265Y-207884D01*
X675170Y-207913D01*
X675167D01*
X675159Y-207917D01*
X675148Y-207924D01*
X675130Y-207932D01*
X675086Y-207954D01*
X675035Y-207986D01*
X674977Y-208026D01*
X674915Y-208077D01*
X674861Y-208136D01*
X674810Y-208205D01*
Y-208208D01*
X674806Y-208216D01*
X674799Y-208226D01*
X674792Y-208241D01*
X674784Y-208259D01*
X674773Y-208281D01*
X674752Y-208332D01*
X674730Y-208398D01*
X674712Y-208470D01*
X674697Y-208551D01*
X674693Y-208634D01*
Y-208660D01*
X674697Y-208682D01*
Y-208707D01*
X674701Y-208733D01*
X674715Y-208798D01*
X674733Y-208874D01*
X674762Y-208951D01*
X674802Y-209031D01*
X674824Y-209071D01*
X674854Y-209107D01*
X674857Y-209111D01*
X674861Y-209115D01*
X674872Y-209126D01*
X674883Y-209140D01*
X674901Y-209155D01*
X674923Y-209173D01*
X674944Y-209195D01*
X674974Y-209213D01*
X675006Y-209235D01*
X675043Y-209260D01*
X675079Y-209282D01*
X675123Y-209304D01*
X675170Y-209322D01*
X675221Y-209340D01*
X675276Y-209359D01*
X675334Y-209373D01*
X675250Y-209708D01*
X675247D01*
X675232Y-209704D01*
X675210Y-209697D01*
X675181Y-209686D01*
X675148Y-209675D01*
X675108Y-209661D01*
X675065Y-209643D01*
X675017Y-209621D01*
X674915Y-209570D01*
X674813Y-209504D01*
X674762Y-209464D01*
X674712Y-209424D01*
X674668Y-209380D01*
X674624Y-209329D01*
X674620Y-209326D01*
X674613Y-209318D01*
X674606Y-209300D01*
X674591Y-209282D01*
X674573Y-209253D01*
X674555Y-209224D01*
X674537Y-209184D01*
X674519Y-209144D01*
X674497Y-209097D01*
X674479Y-209046D01*
X674460Y-208991D01*
X674442Y-208933D01*
X674428Y-208871D01*
X674420Y-208805D01*
X674413Y-208736D01*
X674409Y-208663D01*
Y-208623D01*
X674413Y-208594D01*
Y-208561D01*
X674417Y-208521D01*
X674424Y-208478D01*
X674431Y-208427D01*
X674449Y-208321D01*
X674479Y-208212D01*
X674519Y-208103D01*
X674544Y-208052D01*
X674573Y-208001D01*
X674577Y-207997D01*
X674580Y-207990D01*
X674591Y-207975D01*
X674606Y-207961D01*
X674620Y-207939D01*
X674642Y-207913D01*
X674668Y-207884D01*
X674697Y-207855D01*
X674730Y-207826D01*
X674762Y-207793D01*
X674846Y-207728D01*
X674944Y-207666D01*
X675054Y-207611D01*
X675057D01*
X675068Y-207604D01*
X675086Y-207600D01*
X675108Y-207590D01*
X675137Y-207582D01*
X675174Y-207571D01*
X675214Y-207557D01*
X675257Y-207546D01*
X675305Y-207535D01*
X675359Y-207520D01*
X675472Y-207502D01*
X675600Y-207488D01*
X675731Y-207480D01*
X675734D01*
X675749D01*
X675771D01*
X675796Y-207484D01*
D02*
G37*
G36*
X676349Y-210232D02*
X676357Y-210239D01*
X676360Y-210254D01*
X676371Y-210272D01*
X676382Y-210294D01*
X676397Y-210319D01*
X676433Y-210381D01*
X676473Y-210454D01*
X676524Y-210527D01*
X676582Y-210603D01*
X676644Y-210680D01*
X676648Y-210683D01*
X676652Y-210687D01*
X676663Y-210698D01*
X676674Y-210713D01*
X676710Y-210745D01*
X676754Y-210789D01*
X676804Y-210833D01*
X676863Y-210880D01*
X676921Y-210920D01*
X676983Y-210957D01*
Y-211157D01*
X674453D01*
Y-210847D01*
X676422D01*
X676419Y-210844D01*
X676404Y-210825D01*
X676382Y-210804D01*
X676357Y-210767D01*
X676324Y-210727D01*
X676288Y-210676D01*
X676248Y-210618D01*
X676208Y-210552D01*
Y-210549D01*
X676204Y-210545D01*
X676189Y-210523D01*
X676171Y-210487D01*
X676149Y-210443D01*
X676124Y-210392D01*
X676098Y-210338D01*
X676073Y-210283D01*
X676051Y-210228D01*
X676349D01*
Y-210232D01*
D02*
G37*
G36*
X675137Y-212274D02*
X675134D01*
X675127D01*
X675116Y-212278D01*
X675097Y-212281D01*
X675057Y-212292D01*
X675003Y-212307D01*
X674948Y-212329D01*
X674886Y-212358D01*
X674832Y-212394D01*
X674781Y-212438D01*
X674777Y-212445D01*
X674762Y-212460D01*
X674744Y-212489D01*
X674722Y-212529D01*
X674701Y-212573D01*
X674682Y-212627D01*
X674668Y-212689D01*
X674664Y-212758D01*
Y-212780D01*
X674668Y-212795D01*
X674672Y-212838D01*
X674686Y-212889D01*
X674704Y-212951D01*
X674733Y-213013D01*
X674777Y-213079D01*
X674802Y-213108D01*
X674832Y-213137D01*
X674835Y-213141D01*
X674839Y-213144D01*
X674850Y-213151D01*
X674861Y-213162D01*
X674901Y-213188D01*
X674952Y-213217D01*
X675014Y-213242D01*
X675090Y-213268D01*
X675181Y-213286D01*
X675228Y-213293D01*
X675279D01*
X675283D01*
X675290D01*
X675305D01*
X675323Y-213290D01*
X675345D01*
X675370Y-213286D01*
X675429Y-213275D01*
X675498Y-213257D01*
X675567Y-213231D01*
X675632Y-213195D01*
X675694Y-213144D01*
X675698D01*
X675702Y-213137D01*
X675720Y-213119D01*
X675745Y-213086D01*
X675774Y-213042D01*
X675800Y-212984D01*
X675825Y-212918D01*
X675844Y-212842D01*
X675851Y-212798D01*
Y-212729D01*
X675847Y-212700D01*
X675844Y-212664D01*
X675833Y-212620D01*
X675822Y-212576D01*
X675804Y-212529D01*
X675782Y-212482D01*
X675778Y-212478D01*
X675771Y-212463D01*
X675753Y-212442D01*
X675734Y-212413D01*
X675709Y-212383D01*
X675676Y-212354D01*
X675643Y-212321D01*
X675603Y-212296D01*
X675643Y-212005D01*
X676939Y-212249D01*
Y-213501D01*
X676644D01*
Y-212493D01*
X675964Y-212358D01*
X675967Y-212362D01*
X675971Y-212369D01*
X675978Y-212380D01*
X675989Y-212398D01*
X676000Y-212420D01*
X676015Y-212445D01*
X676044Y-212504D01*
X676073Y-212576D01*
X676098Y-212656D01*
X676117Y-212744D01*
X676124Y-212787D01*
Y-212867D01*
X676120Y-212889D01*
X676117Y-212918D01*
X676113Y-212951D01*
X676106Y-212988D01*
X676095Y-213028D01*
X676069Y-213115D01*
X676051Y-213162D01*
X676026Y-213210D01*
X676000Y-213257D01*
X675971Y-213304D01*
X675935Y-213348D01*
X675894Y-213392D01*
X675891Y-213395D01*
X675884Y-213403D01*
X675873Y-213414D01*
X675854Y-213428D01*
X675829Y-213446D01*
X675804Y-213464D01*
X675771Y-213486D01*
X675734Y-213508D01*
X675694Y-213526D01*
X675651Y-213548D01*
X675600Y-213566D01*
X675549Y-213585D01*
X675494Y-213599D01*
X675432Y-213610D01*
X675370Y-213617D01*
X675305Y-213621D01*
X675301D01*
X675290D01*
X675272D01*
X675247Y-213617D01*
X675217Y-213614D01*
X675185Y-213610D01*
X675145Y-213603D01*
X675105Y-213596D01*
X675010Y-213574D01*
X674912Y-213537D01*
X674861Y-213515D01*
X674813Y-213486D01*
X674762Y-213457D01*
X674715Y-213421D01*
X674712Y-213417D01*
X674701Y-213410D01*
X674686Y-213395D01*
X674668Y-213377D01*
X674646Y-213352D01*
X674617Y-213322D01*
X674591Y-213286D01*
X674562Y-213246D01*
X674533Y-213202D01*
X674508Y-213151D01*
X674482Y-213097D01*
X674457Y-213039D01*
X674438Y-212977D01*
X674424Y-212908D01*
X674413Y-212835D01*
X674409Y-212758D01*
Y-212725D01*
X674413Y-212700D01*
X674417Y-212671D01*
X674420Y-212638D01*
X674424Y-212598D01*
X674435Y-212558D01*
X674457Y-212467D01*
X674489Y-212376D01*
X674511Y-212329D01*
X674537Y-212281D01*
X674566Y-212238D01*
X674599Y-212194D01*
X674602Y-212191D01*
X674606Y-212183D01*
X674620Y-212176D01*
X674635Y-212161D01*
X674653Y-212143D01*
X674675Y-212125D01*
X674704Y-212103D01*
X674737Y-212085D01*
X674770Y-212063D01*
X674810Y-212041D01*
X674897Y-212001D01*
X674999Y-211968D01*
X675054Y-211958D01*
X675112Y-211950D01*
X675137Y-212274D01*
D02*
G37*
G36*
X586571Y-184157D02*
X586567D01*
X586552D01*
X586530D01*
X586501Y-184153D01*
X586469Y-184149D01*
X586432Y-184142D01*
X586396Y-184135D01*
X586356Y-184120D01*
X586352D01*
X586348Y-184116D01*
X586327Y-184109D01*
X586294Y-184095D01*
X586250Y-184073D01*
X586199Y-184044D01*
X586141Y-184007D01*
X586083Y-183967D01*
X586021Y-183916D01*
X586017D01*
X586014Y-183909D01*
X585992Y-183891D01*
X585959Y-183858D01*
X585912Y-183811D01*
X585857Y-183756D01*
X585792Y-183687D01*
X585719Y-183603D01*
X585642Y-183512D01*
X585639Y-183509D01*
X585628Y-183494D01*
X585610Y-183472D01*
X585588Y-183447D01*
X585559Y-183414D01*
X585526Y-183374D01*
X585490Y-183334D01*
X585449Y-183286D01*
X585362Y-183195D01*
X585275Y-183105D01*
X585231Y-183061D01*
X585187Y-183021D01*
X585147Y-182984D01*
X585107Y-182955D01*
X585104D01*
X585100Y-182948D01*
X585089Y-182941D01*
X585075Y-182933D01*
X585035Y-182908D01*
X584987Y-182879D01*
X584929Y-182853D01*
X584867Y-182828D01*
X584798Y-182813D01*
X584732Y-182806D01*
X584729D01*
X584725D01*
X584703Y-182810D01*
X584667Y-182813D01*
X584627Y-182824D01*
X584576Y-182839D01*
X584525Y-182864D01*
X584474Y-182897D01*
X584423Y-182941D01*
X584416Y-182948D01*
X584401Y-182966D01*
X584383Y-182992D01*
X584357Y-183032D01*
X584336Y-183083D01*
X584314Y-183141D01*
X584299Y-183210D01*
X584296Y-183286D01*
Y-183308D01*
X584299Y-183323D01*
X584303Y-183367D01*
X584314Y-183418D01*
X584328Y-183472D01*
X584354Y-183534D01*
X584386Y-183592D01*
X584430Y-183647D01*
X584438Y-183654D01*
X584456Y-183669D01*
X584485Y-183691D01*
X584528Y-183712D01*
X584580Y-183738D01*
X584645Y-183760D01*
X584718Y-183774D01*
X584801Y-183782D01*
X584769Y-184098D01*
X584765D01*
X584754Y-184095D01*
X584736D01*
X584711Y-184091D01*
X584681Y-184084D01*
X584649Y-184076D01*
X584609Y-184065D01*
X584569Y-184055D01*
X584481Y-184025D01*
X584394Y-183982D01*
X584350Y-183956D01*
X584306Y-183923D01*
X584266Y-183891D01*
X584230Y-183854D01*
X584226Y-183851D01*
X584223Y-183843D01*
X584212Y-183833D01*
X584201Y-183814D01*
X584186Y-183792D01*
X584172Y-183767D01*
X584154Y-183738D01*
X584135Y-183702D01*
X584117Y-183661D01*
X584099Y-183618D01*
X584084Y-183570D01*
X584070Y-183519D01*
X584059Y-183465D01*
X584048Y-183407D01*
X584044Y-183345D01*
X584041Y-183279D01*
Y-183243D01*
X584044Y-183217D01*
X584048Y-183188D01*
X584052Y-183152D01*
X584059Y-183112D01*
X584066Y-183072D01*
X584092Y-182977D01*
X584128Y-182882D01*
X584150Y-182835D01*
X584175Y-182788D01*
X584208Y-182744D01*
X584245Y-182704D01*
X584248Y-182701D01*
X584252Y-182693D01*
X584266Y-182686D01*
X584281Y-182671D01*
X584299Y-182653D01*
X584325Y-182635D01*
X584350Y-182617D01*
X584383Y-182595D01*
X584452Y-182559D01*
X584539Y-182522D01*
X584583Y-182508D01*
X584634Y-182500D01*
X584685Y-182493D01*
X584740Y-182489D01*
X584747D01*
X584765D01*
X584794Y-182493D01*
X584834Y-182497D01*
X584878Y-182504D01*
X584929Y-182518D01*
X584983Y-182533D01*
X585038Y-182555D01*
X585045Y-182559D01*
X585064Y-182566D01*
X585093Y-182580D01*
X585133Y-182602D01*
X585176Y-182631D01*
X585231Y-182668D01*
X585286Y-182711D01*
X585348Y-182762D01*
X585355Y-182770D01*
X585377Y-182788D01*
X585395Y-182806D01*
X585413Y-182824D01*
X585435Y-182846D01*
X585464Y-182875D01*
X585493Y-182904D01*
X585526Y-182941D01*
X585562Y-182977D01*
X585602Y-183021D01*
X585642Y-183068D01*
X585690Y-183119D01*
X585737Y-183177D01*
X585788Y-183236D01*
X585792Y-183239D01*
X585799Y-183247D01*
X585810Y-183261D01*
X585824Y-183279D01*
X585846Y-183301D01*
X585868Y-183327D01*
X585915Y-183385D01*
X585970Y-183447D01*
X586025Y-183505D01*
X586072Y-183556D01*
X586090Y-183578D01*
X586108Y-183596D01*
X586112Y-183600D01*
X586123Y-183610D01*
X586137Y-183625D01*
X586159Y-183643D01*
X586185Y-183661D01*
X586210Y-183683D01*
X586272Y-183727D01*
Y-182486D01*
X586571D01*
Y-184157D01*
D02*
G37*
G36*
Y-185216D02*
X584601D01*
X584605Y-185219D01*
X584620Y-185238D01*
X584641Y-185259D01*
X584667Y-185296D01*
X584700Y-185336D01*
X584736Y-185387D01*
X584776Y-185445D01*
X584816Y-185511D01*
Y-185514D01*
X584820Y-185518D01*
X584834Y-185540D01*
X584853Y-185576D01*
X584874Y-185620D01*
X584900Y-185671D01*
X584925Y-185725D01*
X584951Y-185780D01*
X584973Y-185835D01*
X584674D01*
Y-185831D01*
X584667Y-185824D01*
X584663Y-185809D01*
X584652Y-185791D01*
X584641Y-185769D01*
X584627Y-185743D01*
X584590Y-185682D01*
X584550Y-185609D01*
X584499Y-185536D01*
X584441Y-185460D01*
X584379Y-185383D01*
X584376Y-185380D01*
X584372Y-185376D01*
X584361Y-185365D01*
X584350Y-185350D01*
X584314Y-185318D01*
X584270Y-185274D01*
X584219Y-185230D01*
X584161Y-185183D01*
X584103Y-185143D01*
X584041Y-185107D01*
Y-184906D01*
X586571D01*
Y-185216D01*
D02*
G37*
G36*
X585792Y-186359D02*
X585813Y-186366D01*
X585843Y-186377D01*
X585875Y-186388D01*
X585915Y-186402D01*
X585959Y-186421D01*
X586006Y-186442D01*
X586108Y-186493D01*
X586210Y-186559D01*
X586261Y-186599D01*
X586312Y-186639D01*
X586356Y-186683D01*
X586400Y-186734D01*
X586403Y-186737D01*
X586410Y-186744D01*
X586418Y-186763D01*
X586432Y-186781D01*
X586450Y-186810D01*
X586469Y-186839D01*
X586487Y-186879D01*
X586505Y-186919D01*
X586527Y-186967D01*
X586545Y-187018D01*
X586563Y-187072D01*
X586582Y-187130D01*
X586596Y-187192D01*
X586603Y-187258D01*
X586611Y-187327D01*
X586614Y-187400D01*
Y-187440D01*
X586611Y-187469D01*
Y-187502D01*
X586607Y-187542D01*
X586600Y-187585D01*
X586592Y-187636D01*
X586574Y-187742D01*
X586545Y-187851D01*
X586505Y-187960D01*
X586480Y-188011D01*
X586450Y-188062D01*
X586447Y-188066D01*
X586443Y-188073D01*
X586432Y-188088D01*
X586418Y-188102D01*
X586403Y-188124D01*
X586381Y-188150D01*
X586356Y-188179D01*
X586327Y-188208D01*
X586294Y-188237D01*
X586261Y-188270D01*
X586177Y-188335D01*
X586079Y-188397D01*
X585970Y-188452D01*
X585966D01*
X585955Y-188459D01*
X585937Y-188463D01*
X585915Y-188473D01*
X585886Y-188481D01*
X585850Y-188492D01*
X585810Y-188506D01*
X585766Y-188517D01*
X585719Y-188528D01*
X585664Y-188543D01*
X585551Y-188561D01*
X585424Y-188575D01*
X585293Y-188583D01*
X585289D01*
X585275D01*
X585253D01*
X585227Y-188579D01*
X585191D01*
X585155Y-188575D01*
X585107Y-188572D01*
X585060Y-188565D01*
X584954Y-188546D01*
X584838Y-188521D01*
X584721Y-188484D01*
X584609Y-188434D01*
X584605Y-188430D01*
X584594Y-188426D01*
X584580Y-188419D01*
X584561Y-188404D01*
X584536Y-188390D01*
X584507Y-188372D01*
X584441Y-188324D01*
X584368Y-188262D01*
X584296Y-188190D01*
X584223Y-188106D01*
X584161Y-188008D01*
X584157Y-188004D01*
X584154Y-187993D01*
X584146Y-187978D01*
X584135Y-187960D01*
X584125Y-187931D01*
X584114Y-187902D01*
X584099Y-187866D01*
X584084Y-187826D01*
X584070Y-187782D01*
X584055Y-187735D01*
X584033Y-187633D01*
X584015Y-187516D01*
X584008Y-187396D01*
Y-187360D01*
X584012Y-187334D01*
X584015Y-187301D01*
X584019Y-187261D01*
X584023Y-187221D01*
X584033Y-187174D01*
X584055Y-187076D01*
X584088Y-186967D01*
X584110Y-186912D01*
X584135Y-186861D01*
X584168Y-186810D01*
X584201Y-186759D01*
X584204Y-186755D01*
X584208Y-186748D01*
X584219Y-186734D01*
X584237Y-186715D01*
X584256Y-186697D01*
X584281Y-186672D01*
X584310Y-186646D01*
X584339Y-186617D01*
X584376Y-186588D01*
X584419Y-186559D01*
X584463Y-186526D01*
X584510Y-186497D01*
X584565Y-186471D01*
X584620Y-186442D01*
X584678Y-186421D01*
X584743Y-186399D01*
X584820Y-186726D01*
X584816D01*
X584809Y-186730D01*
X584794Y-186737D01*
X584776Y-186744D01*
X584754Y-186752D01*
X584725Y-186763D01*
X584667Y-186792D01*
X584601Y-186828D01*
X584536Y-186872D01*
X584474Y-186926D01*
X584419Y-186985D01*
X584412Y-186992D01*
X584398Y-187014D01*
X584379Y-187050D01*
X584354Y-187098D01*
X584332Y-187160D01*
X584310Y-187229D01*
X584296Y-187312D01*
X584292Y-187403D01*
Y-187433D01*
X584296Y-187451D01*
Y-187476D01*
X584299Y-187505D01*
X584310Y-187574D01*
X584325Y-187651D01*
X584350Y-187731D01*
X584386Y-187815D01*
X584434Y-187891D01*
Y-187895D01*
X584441Y-187898D01*
X584459Y-187924D01*
X584488Y-187957D01*
X584532Y-187997D01*
X584587Y-188044D01*
X584649Y-188088D01*
X584725Y-188128D01*
X584809Y-188164D01*
X584812D01*
X584820Y-188168D01*
X584831Y-188171D01*
X584849Y-188175D01*
X584871Y-188182D01*
X584896Y-188190D01*
X584958Y-188200D01*
X585031Y-188215D01*
X585111Y-188230D01*
X585198Y-188237D01*
X585293Y-188241D01*
X585296D01*
X585308D01*
X585326D01*
X585348D01*
X585373Y-188237D01*
X585406D01*
X585442Y-188233D01*
X585482Y-188230D01*
X585569Y-188219D01*
X585664Y-188200D01*
X585759Y-188179D01*
X585853Y-188150D01*
X585857D01*
X585864Y-188146D01*
X585875Y-188139D01*
X585893Y-188131D01*
X585937Y-188110D01*
X585988Y-188077D01*
X586046Y-188037D01*
X586108Y-187986D01*
X586163Y-187927D01*
X586214Y-187858D01*
Y-187855D01*
X586217Y-187847D01*
X586225Y-187837D01*
X586232Y-187822D01*
X586239Y-187804D01*
X586250Y-187782D01*
X586272Y-187731D01*
X586294Y-187665D01*
X586312Y-187593D01*
X586327Y-187513D01*
X586330Y-187429D01*
Y-187403D01*
X586327Y-187381D01*
Y-187356D01*
X586323Y-187331D01*
X586308Y-187265D01*
X586290Y-187189D01*
X586261Y-187112D01*
X586221Y-187032D01*
X586199Y-186992D01*
X586170Y-186956D01*
X586166Y-186952D01*
X586163Y-186948D01*
X586152Y-186937D01*
X586141Y-186923D01*
X586123Y-186908D01*
X586101Y-186890D01*
X586079Y-186868D01*
X586050Y-186850D01*
X586017Y-186828D01*
X585981Y-186803D01*
X585945Y-186781D01*
X585901Y-186759D01*
X585853Y-186741D01*
X585803Y-186723D01*
X585748Y-186705D01*
X585690Y-186690D01*
X585773Y-186355D01*
X585777D01*
X585792Y-186359D01*
D02*
G37*
G36*
X561623Y-199610D02*
X561659D01*
X561696Y-199613D01*
X561743Y-199617D01*
X561790Y-199625D01*
X561896Y-199643D01*
X562012Y-199668D01*
X562129Y-199705D01*
X562242Y-199756D01*
X562245Y-199759D01*
X562256Y-199763D01*
X562271Y-199770D01*
X562289Y-199785D01*
X562315Y-199799D01*
X562344Y-199817D01*
X562409Y-199865D01*
X562482Y-199927D01*
X562555Y-199999D01*
X562628Y-200083D01*
X562689Y-200181D01*
X562693Y-200185D01*
X562697Y-200196D01*
X562704Y-200210D01*
X562715Y-200229D01*
X562726Y-200258D01*
X562737Y-200287D01*
X562751Y-200323D01*
X562766Y-200363D01*
X562781Y-200407D01*
X562795Y-200454D01*
X562817Y-200556D01*
X562835Y-200673D01*
X562842Y-200793D01*
Y-200829D01*
X562839Y-200855D01*
X562835Y-200887D01*
X562831Y-200928D01*
X562828Y-200968D01*
X562817Y-201015D01*
X562795Y-201113D01*
X562762Y-201222D01*
X562741Y-201277D01*
X562715Y-201328D01*
X562682Y-201379D01*
X562649Y-201430D01*
X562646Y-201433D01*
X562642Y-201441D01*
X562631Y-201455D01*
X562613Y-201474D01*
X562595Y-201492D01*
X562569Y-201517D01*
X562540Y-201543D01*
X562511Y-201572D01*
X562475Y-201601D01*
X562431Y-201630D01*
X562387Y-201663D01*
X562340Y-201692D01*
X562286Y-201717D01*
X562231Y-201747D01*
X562173Y-201768D01*
X562107Y-201790D01*
X562031Y-201463D01*
X562034D01*
X562042Y-201459D01*
X562056Y-201452D01*
X562074Y-201445D01*
X562096Y-201437D01*
X562125Y-201426D01*
X562184Y-201397D01*
X562249Y-201361D01*
X562315Y-201317D01*
X562376Y-201262D01*
X562431Y-201204D01*
X562438Y-201197D01*
X562453Y-201175D01*
X562471Y-201139D01*
X562497Y-201091D01*
X562518Y-201029D01*
X562540Y-200960D01*
X562555Y-200877D01*
X562559Y-200786D01*
Y-200757D01*
X562555Y-200738D01*
Y-200713D01*
X562551Y-200684D01*
X562540Y-200615D01*
X562526Y-200538D01*
X562500Y-200458D01*
X562464Y-200374D01*
X562417Y-200298D01*
Y-200294D01*
X562409Y-200291D01*
X562391Y-200265D01*
X562362Y-200232D01*
X562318Y-200192D01*
X562264Y-200145D01*
X562202Y-200101D01*
X562125Y-200061D01*
X562042Y-200025D01*
X562038D01*
X562031Y-200021D01*
X562020Y-200018D01*
X562002Y-200014D01*
X561980Y-200007D01*
X561954Y-199999D01*
X561892Y-199988D01*
X561820Y-199974D01*
X561739Y-199959D01*
X561652Y-199952D01*
X561557Y-199948D01*
X561554D01*
X561543D01*
X561525D01*
X561503D01*
X561477Y-199952D01*
X561445D01*
X561408Y-199956D01*
X561368Y-199959D01*
X561281Y-199970D01*
X561186Y-199988D01*
X561092Y-200010D01*
X560997Y-200039D01*
X560993D01*
X560986Y-200043D01*
X560975Y-200050D01*
X560957Y-200058D01*
X560913Y-200079D01*
X560862Y-200112D01*
X560804Y-200152D01*
X560742Y-200203D01*
X560687Y-200261D01*
X560637Y-200331D01*
Y-200334D01*
X560633Y-200342D01*
X560626Y-200353D01*
X560618Y-200367D01*
X560611Y-200385D01*
X560600Y-200407D01*
X560578Y-200458D01*
X560557Y-200523D01*
X560538Y-200596D01*
X560524Y-200676D01*
X560520Y-200760D01*
Y-200786D01*
X560524Y-200807D01*
Y-200833D01*
X560527Y-200858D01*
X560542Y-200924D01*
X560560Y-201000D01*
X560589Y-201077D01*
X560629Y-201157D01*
X560651Y-201197D01*
X560680Y-201233D01*
X560684Y-201237D01*
X560687Y-201241D01*
X560698Y-201252D01*
X560709Y-201266D01*
X560728Y-201281D01*
X560749Y-201299D01*
X560771Y-201321D01*
X560800Y-201339D01*
X560833Y-201361D01*
X560870Y-201386D01*
X560906Y-201408D01*
X560950Y-201430D01*
X560997Y-201448D01*
X561048Y-201466D01*
X561102Y-201484D01*
X561161Y-201499D01*
X561077Y-201834D01*
X561073D01*
X561059Y-201830D01*
X561037Y-201823D01*
X561008Y-201812D01*
X560975Y-201801D01*
X560935Y-201787D01*
X560891Y-201768D01*
X560844Y-201747D01*
X560742Y-201696D01*
X560640Y-201630D01*
X560589Y-201590D01*
X560538Y-201550D01*
X560495Y-201506D01*
X560451Y-201455D01*
X560447Y-201452D01*
X560440Y-201445D01*
X560433Y-201426D01*
X560418Y-201408D01*
X560400Y-201379D01*
X560382Y-201350D01*
X560364Y-201310D01*
X560345Y-201270D01*
X560323Y-201222D01*
X560305Y-201171D01*
X560287Y-201117D01*
X560269Y-201059D01*
X560254Y-200997D01*
X560247Y-200931D01*
X560240Y-200862D01*
X560236Y-200789D01*
Y-200749D01*
X560240Y-200720D01*
Y-200687D01*
X560243Y-200647D01*
X560251Y-200604D01*
X560258Y-200553D01*
X560276Y-200447D01*
X560305Y-200338D01*
X560345Y-200229D01*
X560371Y-200178D01*
X560400Y-200127D01*
X560404Y-200123D01*
X560407Y-200116D01*
X560418Y-200101D01*
X560433Y-200087D01*
X560447Y-200065D01*
X560469Y-200039D01*
X560495Y-200010D01*
X560524Y-199981D01*
X560557Y-199952D01*
X560589Y-199919D01*
X560673Y-199854D01*
X560771Y-199792D01*
X560880Y-199737D01*
X560884D01*
X560895Y-199730D01*
X560913Y-199726D01*
X560935Y-199715D01*
X560964Y-199708D01*
X561001Y-199697D01*
X561041Y-199683D01*
X561084Y-199672D01*
X561132Y-199661D01*
X561186Y-199646D01*
X561299Y-199628D01*
X561426Y-199613D01*
X561557Y-199606D01*
X561561D01*
X561576D01*
X561597D01*
X561623Y-199610D01*
D02*
G37*
G36*
X561044Y-202118D02*
X561066D01*
X561092Y-202121D01*
X561150Y-202129D01*
X561215Y-202143D01*
X561281Y-202165D01*
X561350Y-202198D01*
X561415Y-202238D01*
X561419D01*
X561423Y-202245D01*
X561441Y-202260D01*
X561470Y-202289D01*
X561507Y-202329D01*
X561543Y-202380D01*
X561583Y-202442D01*
X561616Y-202511D01*
X561641Y-202595D01*
Y-202591D01*
X561645Y-202587D01*
X561649Y-202576D01*
X561656Y-202562D01*
X561670Y-202529D01*
X561692Y-202485D01*
X561721Y-202438D01*
X561758Y-202391D01*
X561798Y-202347D01*
X561841Y-202307D01*
X561849Y-202304D01*
X561863Y-202293D01*
X561892Y-202278D01*
X561929Y-202263D01*
X561976Y-202245D01*
X562031Y-202231D01*
X562093Y-202220D01*
X562158Y-202216D01*
X562162D01*
X562169D01*
X562184D01*
X562205Y-202220D01*
X562227Y-202223D01*
X562256Y-202227D01*
X562318Y-202242D01*
X562391Y-202263D01*
X562467Y-202300D01*
X562507Y-202322D01*
X562548Y-202347D01*
X562584Y-202380D01*
X562620Y-202413D01*
X562624Y-202416D01*
X562628Y-202424D01*
X562639Y-202434D01*
X562649Y-202449D01*
X562664Y-202467D01*
X562679Y-202493D01*
X562697Y-202522D01*
X562715Y-202551D01*
X562733Y-202587D01*
X562751Y-202627D01*
X562766Y-202671D01*
X562781Y-202718D01*
X562802Y-202820D01*
X562806Y-202879D01*
X562810Y-202937D01*
Y-202970D01*
X562806Y-202992D01*
X562802Y-203021D01*
X562799Y-203053D01*
X562795Y-203090D01*
X562784Y-203126D01*
X562762Y-203214D01*
X562730Y-203301D01*
X562708Y-203344D01*
X562682Y-203388D01*
X562649Y-203428D01*
X562617Y-203468D01*
X562613Y-203472D01*
X562609Y-203476D01*
X562599Y-203486D01*
X562584Y-203501D01*
X562562Y-203516D01*
X562540Y-203534D01*
X562486Y-203570D01*
X562417Y-203607D01*
X562336Y-203639D01*
X562245Y-203665D01*
X562198Y-203668D01*
X562147Y-203672D01*
X562144D01*
X562140D01*
X562118D01*
X562085Y-203668D01*
X562045Y-203661D01*
X561994Y-203650D01*
X561943Y-203632D01*
X561892Y-203610D01*
X561841Y-203577D01*
X561834Y-203574D01*
X561820Y-203559D01*
X561798Y-203538D01*
X561769Y-203508D01*
X561736Y-203468D01*
X561703Y-203421D01*
X561670Y-203366D01*
X561641Y-203301D01*
Y-203305D01*
X561638Y-203312D01*
X561634Y-203323D01*
X561627Y-203337D01*
X561608Y-203381D01*
X561583Y-203432D01*
X561547Y-203486D01*
X561507Y-203545D01*
X561456Y-203599D01*
X561397Y-203650D01*
X561394D01*
X561390Y-203654D01*
X561368Y-203668D01*
X561332Y-203690D01*
X561284Y-203712D01*
X561226Y-203734D01*
X561157Y-203756D01*
X561081Y-203770D01*
X560997Y-203774D01*
X560993D01*
X560982D01*
X560964D01*
X560942Y-203770D01*
X560917Y-203767D01*
X560884Y-203763D01*
X560848Y-203756D01*
X560808Y-203745D01*
X560724Y-203719D01*
X560677Y-203701D01*
X560633Y-203676D01*
X560586Y-203650D01*
X560542Y-203621D01*
X560498Y-203585D01*
X560455Y-203545D01*
X560451Y-203541D01*
X560444Y-203534D01*
X560433Y-203523D01*
X560422Y-203505D01*
X560404Y-203479D01*
X560385Y-203454D01*
X560367Y-203421D01*
X560345Y-203385D01*
X560323Y-203344D01*
X560305Y-203297D01*
X560287Y-203246D01*
X560269Y-203195D01*
X560258Y-203137D01*
X560247Y-203075D01*
X560240Y-203013D01*
X560236Y-202944D01*
Y-202908D01*
X560240Y-202882D01*
X560243Y-202850D01*
X560247Y-202813D01*
X560254Y-202773D01*
X560265Y-202729D01*
X560291Y-202631D01*
X560309Y-202580D01*
X560327Y-202533D01*
X560353Y-202482D01*
X560382Y-202431D01*
X560415Y-202384D01*
X560455Y-202340D01*
X560458Y-202336D01*
X560465Y-202329D01*
X560476Y-202318D01*
X560495Y-202304D01*
X560516Y-202289D01*
X560542Y-202267D01*
X560571Y-202249D01*
X560607Y-202227D01*
X560644Y-202205D01*
X560687Y-202187D01*
X560779Y-202151D01*
X560833Y-202136D01*
X560888Y-202125D01*
X560946Y-202118D01*
X561004Y-202114D01*
X561008D01*
X561015D01*
X561030D01*
X561044Y-202118D01*
D02*
G37*
G36*
X552706Y-219050D02*
X552735Y-219053D01*
X552768Y-219057D01*
X552808Y-219064D01*
X552848Y-219072D01*
X552943Y-219093D01*
X553041Y-219130D01*
X553092Y-219152D01*
X553139Y-219181D01*
X553190Y-219210D01*
X553238Y-219246D01*
X553241Y-219250D01*
X553252Y-219257D01*
X553267Y-219272D01*
X553285Y-219290D01*
X553307Y-219315D01*
X553336Y-219344D01*
X553361Y-219381D01*
X553391Y-219421D01*
X553420Y-219465D01*
X553445Y-219516D01*
X553471Y-219570D01*
X553496Y-219628D01*
X553514Y-219690D01*
X553529Y-219759D01*
X553540Y-219832D01*
X553543Y-219909D01*
Y-219941D01*
X553540Y-219967D01*
X553536Y-219996D01*
X553532Y-220029D01*
X553529Y-220069D01*
X553518Y-220109D01*
X553496Y-220200D01*
X553463Y-220291D01*
X553441Y-220338D01*
X553416Y-220386D01*
X553387Y-220429D01*
X553354Y-220473D01*
X553350Y-220477D01*
X553347Y-220484D01*
X553332Y-220491D01*
X553318Y-220506D01*
X553300Y-220524D01*
X553278Y-220542D01*
X553249Y-220564D01*
X553216Y-220582D01*
X553183Y-220604D01*
X553143Y-220626D01*
X553056Y-220666D01*
X552954Y-220699D01*
X552899Y-220709D01*
X552841Y-220717D01*
X552815Y-220393D01*
X552819D01*
X552826D01*
X552837Y-220389D01*
X552855Y-220386D01*
X552895Y-220375D01*
X552950Y-220360D01*
X553005Y-220338D01*
X553066Y-220309D01*
X553121Y-220273D01*
X553172Y-220229D01*
X553176Y-220222D01*
X553190Y-220207D01*
X553208Y-220178D01*
X553230Y-220138D01*
X553252Y-220094D01*
X553270Y-220040D01*
X553285Y-219978D01*
X553289Y-219909D01*
Y-219887D01*
X553285Y-219872D01*
X553281Y-219829D01*
X553267Y-219778D01*
X553249Y-219716D01*
X553219Y-219654D01*
X553176Y-219588D01*
X553150Y-219559D01*
X553121Y-219530D01*
X553118Y-219527D01*
X553114Y-219523D01*
X553103Y-219516D01*
X553092Y-219505D01*
X553052Y-219479D01*
X553001Y-219450D01*
X552939Y-219425D01*
X552863Y-219399D01*
X552772Y-219381D01*
X552724Y-219374D01*
X552673D01*
X552670D01*
X552663D01*
X552648D01*
X552630Y-219377D01*
X552608D01*
X552582Y-219381D01*
X552524Y-219392D01*
X552455Y-219410D01*
X552386Y-219436D01*
X552320Y-219472D01*
X552258Y-219523D01*
X552255D01*
X552251Y-219530D01*
X552233Y-219548D01*
X552208Y-219581D01*
X552178Y-219625D01*
X552153Y-219683D01*
X552127Y-219749D01*
X552109Y-219825D01*
X552102Y-219869D01*
Y-219938D01*
X552106Y-219967D01*
X552109Y-220003D01*
X552120Y-220047D01*
X552131Y-220091D01*
X552149Y-220138D01*
X552171Y-220185D01*
X552175Y-220189D01*
X552182Y-220204D01*
X552200Y-220225D01*
X552218Y-220254D01*
X552244Y-220284D01*
X552277Y-220313D01*
X552309Y-220345D01*
X552349Y-220371D01*
X552309Y-220662D01*
X551014Y-220418D01*
Y-219166D01*
X551308D01*
Y-220174D01*
X551989Y-220309D01*
X551986Y-220305D01*
X551982Y-220298D01*
X551974Y-220287D01*
X551964Y-220269D01*
X551953Y-220247D01*
X551938Y-220222D01*
X551909Y-220163D01*
X551880Y-220091D01*
X551854Y-220011D01*
X551836Y-219923D01*
X551829Y-219880D01*
Y-219799D01*
X551833Y-219778D01*
X551836Y-219749D01*
X551840Y-219716D01*
X551847Y-219679D01*
X551858Y-219639D01*
X551884Y-219552D01*
X551902Y-219505D01*
X551927Y-219457D01*
X551953Y-219410D01*
X551982Y-219363D01*
X552018Y-219319D01*
X552058Y-219275D01*
X552062Y-219272D01*
X552069Y-219264D01*
X552080Y-219253D01*
X552098Y-219239D01*
X552124Y-219221D01*
X552149Y-219203D01*
X552182Y-219181D01*
X552218Y-219159D01*
X552258Y-219141D01*
X552302Y-219119D01*
X552353Y-219101D01*
X552404Y-219082D01*
X552459Y-219068D01*
X552521Y-219057D01*
X552582Y-219050D01*
X552648Y-219046D01*
X552652D01*
X552663D01*
X552681D01*
X552706Y-219050D01*
D02*
G37*
G36*
X552721Y-221004D02*
X552743Y-221012D01*
X552772Y-221023D01*
X552804Y-221034D01*
X552844Y-221048D01*
X552888Y-221066D01*
X552936Y-221088D01*
X553037Y-221139D01*
X553139Y-221205D01*
X553190Y-221245D01*
X553241Y-221285D01*
X553285Y-221328D01*
X553329Y-221379D01*
X553332Y-221383D01*
X553339Y-221390D01*
X553347Y-221408D01*
X553361Y-221427D01*
X553380Y-221456D01*
X553398Y-221485D01*
X553416Y-221525D01*
X553434Y-221565D01*
X553456Y-221612D01*
X553474Y-221663D01*
X553492Y-221718D01*
X553511Y-221776D01*
X553525Y-221838D01*
X553532Y-221903D01*
X553540Y-221973D01*
X553543Y-222045D01*
Y-222085D01*
X553540Y-222115D01*
Y-222147D01*
X553536Y-222187D01*
X553529Y-222231D01*
X553521Y-222282D01*
X553503Y-222388D01*
X553474Y-222497D01*
X553434Y-222606D01*
X553409Y-222657D01*
X553380Y-222708D01*
X553376Y-222711D01*
X553372Y-222719D01*
X553361Y-222733D01*
X553347Y-222748D01*
X553332Y-222770D01*
X553310Y-222795D01*
X553285Y-222824D01*
X553256Y-222853D01*
X553223Y-222883D01*
X553190Y-222915D01*
X553107Y-222981D01*
X553008Y-223043D01*
X552899Y-223097D01*
X552895D01*
X552884Y-223105D01*
X552866Y-223108D01*
X552844Y-223119D01*
X552815Y-223127D01*
X552779Y-223137D01*
X552739Y-223152D01*
X552695Y-223163D01*
X552648Y-223174D01*
X552593Y-223188D01*
X552481Y-223207D01*
X552353Y-223221D01*
X552222Y-223228D01*
X552218D01*
X552204D01*
X552182D01*
X552156Y-223225D01*
X552120D01*
X552084Y-223221D01*
X552036Y-223218D01*
X551989Y-223210D01*
X551884Y-223192D01*
X551767Y-223166D01*
X551651Y-223130D01*
X551538Y-223079D01*
X551534Y-223076D01*
X551523Y-223072D01*
X551509Y-223065D01*
X551490Y-223050D01*
X551465Y-223036D01*
X551436Y-223017D01*
X551370Y-222970D01*
X551298Y-222908D01*
X551225Y-222835D01*
X551152Y-222752D01*
X551090Y-222653D01*
X551086Y-222650D01*
X551083Y-222639D01*
X551076Y-222624D01*
X551064Y-222606D01*
X551054Y-222577D01*
X551043Y-222548D01*
X551028Y-222511D01*
X551014Y-222471D01*
X550999Y-222428D01*
X550984Y-222380D01*
X550963Y-222278D01*
X550944Y-222162D01*
X550937Y-222042D01*
Y-222005D01*
X550941Y-221980D01*
X550944Y-221947D01*
X550948Y-221907D01*
X550952Y-221867D01*
X550963Y-221820D01*
X550984Y-221721D01*
X551017Y-221612D01*
X551039Y-221558D01*
X551064Y-221507D01*
X551097Y-221456D01*
X551130Y-221405D01*
X551134Y-221401D01*
X551137Y-221394D01*
X551148Y-221379D01*
X551166Y-221361D01*
X551185Y-221343D01*
X551210Y-221317D01*
X551239Y-221292D01*
X551268Y-221263D01*
X551305Y-221234D01*
X551348Y-221205D01*
X551392Y-221172D01*
X551440Y-221143D01*
X551494Y-221117D01*
X551549Y-221088D01*
X551607Y-221066D01*
X551672Y-221044D01*
X551749Y-221372D01*
X551745D01*
X551738Y-221376D01*
X551723Y-221383D01*
X551705Y-221390D01*
X551683Y-221397D01*
X551654Y-221408D01*
X551596Y-221438D01*
X551531Y-221474D01*
X551465Y-221518D01*
X551403Y-221572D01*
X551348Y-221630D01*
X551341Y-221638D01*
X551327Y-221660D01*
X551308Y-221696D01*
X551283Y-221743D01*
X551261Y-221805D01*
X551239Y-221874D01*
X551225Y-221958D01*
X551221Y-222049D01*
Y-222078D01*
X551225Y-222096D01*
Y-222122D01*
X551228Y-222151D01*
X551239Y-222220D01*
X551254Y-222297D01*
X551279Y-222377D01*
X551316Y-222460D01*
X551363Y-222537D01*
Y-222540D01*
X551370Y-222544D01*
X551389Y-222570D01*
X551418Y-222602D01*
X551461Y-222642D01*
X551516Y-222690D01*
X551578Y-222733D01*
X551654Y-222773D01*
X551738Y-222810D01*
X551742D01*
X551749Y-222813D01*
X551760Y-222817D01*
X551778Y-222821D01*
X551800Y-222828D01*
X551825Y-222835D01*
X551887Y-222846D01*
X551960Y-222861D01*
X552040Y-222875D01*
X552127Y-222883D01*
X552222Y-222886D01*
X552226D01*
X552237D01*
X552255D01*
X552277D01*
X552302Y-222883D01*
X552335D01*
X552371Y-222879D01*
X552411Y-222875D01*
X552499Y-222864D01*
X552593Y-222846D01*
X552688Y-222824D01*
X552783Y-222795D01*
X552786D01*
X552794Y-222792D01*
X552804Y-222784D01*
X552823Y-222777D01*
X552866Y-222755D01*
X552917Y-222722D01*
X552976Y-222682D01*
X553037Y-222631D01*
X553092Y-222573D01*
X553143Y-222504D01*
Y-222500D01*
X553147Y-222493D01*
X553154Y-222482D01*
X553161Y-222468D01*
X553168Y-222449D01*
X553179Y-222428D01*
X553201Y-222377D01*
X553223Y-222311D01*
X553241Y-222238D01*
X553256Y-222158D01*
X553260Y-222075D01*
Y-222049D01*
X553256Y-222027D01*
Y-222002D01*
X553252Y-221976D01*
X553238Y-221911D01*
X553219Y-221834D01*
X553190Y-221758D01*
X553150Y-221678D01*
X553128Y-221638D01*
X553099Y-221601D01*
X553096Y-221598D01*
X553092Y-221594D01*
X553081Y-221583D01*
X553070Y-221569D01*
X553052Y-221554D01*
X553030Y-221536D01*
X553008Y-221514D01*
X552979Y-221496D01*
X552946Y-221474D01*
X552910Y-221448D01*
X552874Y-221427D01*
X552830Y-221405D01*
X552783Y-221387D01*
X552732Y-221368D01*
X552677Y-221350D01*
X552619Y-221336D01*
X552703Y-221001D01*
X552706D01*
X552721Y-221004D01*
D02*
G37*
G36*
X561801Y-210406D02*
X561823D01*
X561881Y-210417D01*
X561951Y-210428D01*
X562023Y-210447D01*
X562103Y-210472D01*
X562180Y-210508D01*
X562184D01*
X562187Y-210512D01*
X562198Y-210519D01*
X562213Y-210527D01*
X562249Y-210548D01*
X562296Y-210581D01*
X562347Y-210621D01*
X562398Y-210669D01*
X562449Y-210727D01*
X562493Y-210789D01*
Y-210792D01*
X562497Y-210796D01*
X562504Y-210807D01*
X562507Y-210821D01*
X562526Y-210858D01*
X562544Y-210905D01*
X562566Y-210967D01*
X562580Y-211036D01*
X562595Y-211113D01*
X562599Y-211196D01*
Y-211215D01*
X562595Y-211233D01*
Y-211262D01*
X562591Y-211295D01*
X562584Y-211331D01*
X562573Y-211375D01*
X562562Y-211418D01*
X562547Y-211469D01*
X562529Y-211520D01*
X562507Y-211571D01*
X562478Y-211626D01*
X562446Y-211677D01*
X562409Y-211728D01*
X562365Y-211779D01*
X562315Y-211826D01*
X562311Y-211830D01*
X562300Y-211837D01*
X562285Y-211848D01*
X562260Y-211862D01*
X562227Y-211884D01*
X562191Y-211902D01*
X562144Y-211924D01*
X562092Y-211946D01*
X562031Y-211972D01*
X561962Y-211994D01*
X561885Y-212012D01*
X561801Y-212030D01*
X561707Y-212048D01*
X561605Y-212059D01*
X561496Y-212066D01*
X561379Y-212070D01*
X561375D01*
X561372D01*
X561361D01*
X561346D01*
X561310Y-212066D01*
X561259D01*
X561201Y-212063D01*
X561131Y-212055D01*
X561055Y-212048D01*
X560971Y-212037D01*
X560888Y-212023D01*
X560797Y-212004D01*
X560709Y-211983D01*
X560622Y-211957D01*
X560538Y-211924D01*
X560458Y-211888D01*
X560382Y-211848D01*
X560316Y-211801D01*
X560313Y-211797D01*
X560305Y-211790D01*
X560291Y-211775D01*
X560269Y-211757D01*
X560247Y-211735D01*
X560225Y-211706D01*
X560196Y-211669D01*
X560171Y-211633D01*
X560145Y-211590D01*
X560116Y-211542D01*
X560094Y-211488D01*
X560069Y-211433D01*
X560050Y-211371D01*
X560036Y-211305D01*
X560029Y-211236D01*
X560025Y-211164D01*
Y-211135D01*
X560029Y-211113D01*
Y-211087D01*
X560032Y-211058D01*
X560047Y-210989D01*
X560065Y-210912D01*
X560094Y-210832D01*
X560138Y-210752D01*
X560163Y-210712D01*
X560192Y-210676D01*
X560196Y-210672D01*
X560200Y-210669D01*
X560211Y-210658D01*
X560222Y-210647D01*
X560240Y-210629D01*
X560262Y-210614D01*
X560313Y-210574D01*
X560378Y-210534D01*
X560458Y-210497D01*
X560549Y-210465D01*
X560651Y-210443D01*
X560677Y-210752D01*
X560673D01*
X560669Y-210756D01*
X560647Y-210759D01*
X560615Y-210771D01*
X560575Y-210785D01*
X560531Y-210800D01*
X560487Y-210821D01*
X560447Y-210847D01*
X560415Y-210872D01*
X560407Y-210880D01*
X560393Y-210894D01*
X560371Y-210920D01*
X560345Y-210956D01*
X560323Y-211003D01*
X560302Y-211054D01*
X560287Y-211116D01*
X560280Y-211182D01*
Y-211207D01*
X560283Y-211236D01*
X560291Y-211269D01*
X560302Y-211313D01*
X560316Y-211356D01*
X560334Y-211400D01*
X560363Y-211444D01*
X560367Y-211451D01*
X560382Y-211469D01*
X560407Y-211495D01*
X560444Y-211528D01*
X560487Y-211564D01*
X560538Y-211604D01*
X560604Y-211640D01*
X560677Y-211677D01*
X560680D01*
X560687Y-211681D01*
X560698Y-211684D01*
X560713Y-211691D01*
X560735Y-211695D01*
X560760Y-211702D01*
X560789Y-211710D01*
X560826Y-211717D01*
X560866Y-211728D01*
X560910Y-211735D01*
X560957Y-211742D01*
X561008Y-211746D01*
X561066Y-211753D01*
X561124Y-211757D01*
X561190Y-211761D01*
X561255D01*
X561252Y-211757D01*
X561230Y-211742D01*
X561201Y-211717D01*
X561164Y-211684D01*
X561121Y-211648D01*
X561081Y-211600D01*
X561040Y-211549D01*
X561004Y-211491D01*
Y-211488D01*
X561000Y-211484D01*
X560990Y-211462D01*
X560979Y-211429D01*
X560960Y-211386D01*
X560946Y-211335D01*
X560935Y-211276D01*
X560924Y-211215D01*
X560920Y-211149D01*
Y-211120D01*
X560924Y-211098D01*
X560928Y-211069D01*
X560931Y-211040D01*
X560939Y-211003D01*
X560950Y-210967D01*
X560975Y-210883D01*
X560993Y-210840D01*
X561019Y-210796D01*
X561044Y-210752D01*
X561073Y-210705D01*
X561110Y-210661D01*
X561150Y-210621D01*
X561153Y-210618D01*
X561161Y-210610D01*
X561172Y-210599D01*
X561190Y-210589D01*
X561215Y-210570D01*
X561241Y-210552D01*
X561273Y-210534D01*
X561310Y-210512D01*
X561350Y-210490D01*
X561394Y-210472D01*
X561445Y-210454D01*
X561496Y-210436D01*
X561550Y-210425D01*
X561612Y-210414D01*
X561674Y-210406D01*
X561739Y-210403D01*
X561743D01*
X561750D01*
X561761D01*
X561779D01*
X561801Y-210406D01*
D02*
G37*
G36*
X561776Y-212343D02*
X561798Y-212350D01*
X561827Y-212361D01*
X561860Y-212372D01*
X561900Y-212387D01*
X561943Y-212405D01*
X561991Y-212427D01*
X562092Y-212478D01*
X562194Y-212543D01*
X562245Y-212583D01*
X562296Y-212623D01*
X562340Y-212667D01*
X562384Y-212718D01*
X562387Y-212721D01*
X562395Y-212729D01*
X562402Y-212747D01*
X562417Y-212765D01*
X562435Y-212794D01*
X562453Y-212823D01*
X562471Y-212863D01*
X562489Y-212903D01*
X562511Y-212951D01*
X562529Y-213002D01*
X562547Y-213056D01*
X562566Y-213115D01*
X562580Y-213176D01*
X562588Y-213242D01*
X562595Y-213311D01*
X562599Y-213384D01*
Y-213424D01*
X562595Y-213453D01*
Y-213486D01*
X562591Y-213526D01*
X562584Y-213570D01*
X562577Y-213621D01*
X562558Y-213726D01*
X562529Y-213835D01*
X562489Y-213945D01*
X562464Y-213996D01*
X562435Y-214047D01*
X562431Y-214050D01*
X562427Y-214057D01*
X562417Y-214072D01*
X562402Y-214087D01*
X562387Y-214108D01*
X562365Y-214134D01*
X562340Y-214163D01*
X562311Y-214192D01*
X562278Y-214221D01*
X562245Y-214254D01*
X562162Y-214319D01*
X562063Y-214381D01*
X561954Y-214436D01*
X561951D01*
X561940Y-214443D01*
X561921Y-214447D01*
X561900Y-214458D01*
X561870Y-214465D01*
X561834Y-214476D01*
X561794Y-214491D01*
X561750Y-214502D01*
X561703Y-214512D01*
X561648Y-214527D01*
X561536Y-214545D01*
X561408Y-214560D01*
X561277Y-214567D01*
X561273D01*
X561259D01*
X561237D01*
X561212Y-214563D01*
X561175D01*
X561139Y-214560D01*
X561092Y-214556D01*
X561044Y-214549D01*
X560939Y-214531D01*
X560822Y-214505D01*
X560706Y-214469D01*
X560593Y-214418D01*
X560589Y-214414D01*
X560578Y-214410D01*
X560564Y-214403D01*
X560545Y-214389D01*
X560520Y-214374D01*
X560491Y-214356D01*
X560425Y-214309D01*
X560353Y-214247D01*
X560280Y-214174D01*
X560207Y-214090D01*
X560145Y-213992D01*
X560142Y-213988D01*
X560138Y-213977D01*
X560131Y-213963D01*
X560120Y-213945D01*
X560109Y-213915D01*
X560098Y-213886D01*
X560083Y-213850D01*
X560069Y-213810D01*
X560054Y-213766D01*
X560040Y-213719D01*
X560018Y-213617D01*
X560000Y-213500D01*
X559992Y-213380D01*
Y-213344D01*
X559996Y-213318D01*
X560000Y-213286D01*
X560003Y-213246D01*
X560007Y-213206D01*
X560018Y-213158D01*
X560040Y-213060D01*
X560072Y-212951D01*
X560094Y-212896D01*
X560120Y-212845D01*
X560152Y-212794D01*
X560185Y-212743D01*
X560189Y-212740D01*
X560192Y-212732D01*
X560203Y-212718D01*
X560222Y-212700D01*
X560240Y-212682D01*
X560265Y-212656D01*
X560294Y-212631D01*
X560323Y-212601D01*
X560360Y-212572D01*
X560403Y-212543D01*
X560447Y-212510D01*
X560495Y-212481D01*
X560549Y-212456D01*
X560604Y-212427D01*
X560662Y-212405D01*
X560728Y-212383D01*
X560804Y-212711D01*
X560800D01*
X560793Y-212714D01*
X560779Y-212721D01*
X560760Y-212729D01*
X560738Y-212736D01*
X560709Y-212747D01*
X560651Y-212776D01*
X560585Y-212812D01*
X560520Y-212856D01*
X560458Y-212911D01*
X560403Y-212969D01*
X560396Y-212976D01*
X560382Y-212998D01*
X560363Y-213035D01*
X560338Y-213082D01*
X560316Y-213144D01*
X560294Y-213213D01*
X560280Y-213297D01*
X560276Y-213388D01*
Y-213417D01*
X560280Y-213435D01*
Y-213460D01*
X560283Y-213490D01*
X560294Y-213559D01*
X560309Y-213635D01*
X560334Y-213715D01*
X560371Y-213799D01*
X560418Y-213875D01*
Y-213879D01*
X560425Y-213883D01*
X560444Y-213908D01*
X560473Y-213941D01*
X560516Y-213981D01*
X560571Y-214028D01*
X560633Y-214072D01*
X560709Y-214112D01*
X560793Y-214148D01*
X560797D01*
X560804Y-214152D01*
X560815Y-214156D01*
X560833Y-214159D01*
X560855Y-214167D01*
X560880Y-214174D01*
X560942Y-214185D01*
X561015Y-214199D01*
X561095Y-214214D01*
X561182Y-214221D01*
X561277Y-214225D01*
X561281D01*
X561292D01*
X561310D01*
X561332D01*
X561357Y-214221D01*
X561390D01*
X561426Y-214217D01*
X561466Y-214214D01*
X561554Y-214203D01*
X561648Y-214185D01*
X561743Y-214163D01*
X561838Y-214134D01*
X561841D01*
X561849Y-214130D01*
X561860Y-214123D01*
X561878Y-214116D01*
X561921Y-214094D01*
X561972Y-214061D01*
X562031Y-214021D01*
X562092Y-213970D01*
X562147Y-213912D01*
X562198Y-213843D01*
Y-213839D01*
X562202Y-213832D01*
X562209Y-213821D01*
X562216Y-213806D01*
X562223Y-213788D01*
X562234Y-213766D01*
X562256Y-213715D01*
X562278Y-213650D01*
X562296Y-213577D01*
X562311Y-213497D01*
X562315Y-213413D01*
Y-213388D01*
X562311Y-213366D01*
Y-213340D01*
X562307Y-213315D01*
X562293Y-213249D01*
X562275Y-213173D01*
X562245Y-213096D01*
X562205Y-213016D01*
X562184Y-212976D01*
X562154Y-212940D01*
X562151Y-212936D01*
X562147Y-212933D01*
X562136Y-212922D01*
X562125Y-212907D01*
X562107Y-212893D01*
X562085Y-212874D01*
X562063Y-212853D01*
X562034Y-212834D01*
X562002Y-212812D01*
X561965Y-212787D01*
X561929Y-212765D01*
X561885Y-212743D01*
X561838Y-212725D01*
X561787Y-212707D01*
X561732Y-212689D01*
X561674Y-212674D01*
X561758Y-212339D01*
X561761D01*
X561776Y-212343D01*
D02*
G37*
G36*
X596063Y-129924D02*
X596059D01*
X596045D01*
X596023D01*
X595994Y-129920D01*
X595961Y-129917D01*
X595925Y-129910D01*
X595888Y-129902D01*
X595848Y-129888D01*
X595845D01*
X595841Y-129884D01*
X595819Y-129877D01*
X595786Y-129862D01*
X595743Y-129840D01*
X595692Y-129811D01*
X595634Y-129775D01*
X595575Y-129735D01*
X595513Y-129684D01*
X595510D01*
X595506Y-129676D01*
X595484Y-129658D01*
X595451Y-129626D01*
X595404Y-129578D01*
X595350Y-129524D01*
X595284Y-129455D01*
X595211Y-129371D01*
X595135Y-129280D01*
X595131Y-129276D01*
X595120Y-129262D01*
X595102Y-129240D01*
X595080Y-129214D01*
X595051Y-129182D01*
X595018Y-129141D01*
X594982Y-129101D01*
X594942Y-129054D01*
X594855Y-128963D01*
X594767Y-128872D01*
X594724Y-128828D01*
X594680Y-128788D01*
X594640Y-128752D01*
X594600Y-128723D01*
X594596D01*
X594593Y-128716D01*
X594582Y-128708D01*
X594567Y-128701D01*
X594527Y-128675D01*
X594480Y-128646D01*
X594421Y-128621D01*
X594359Y-128595D01*
X594290Y-128581D01*
X594225Y-128574D01*
X594221D01*
X594218D01*
X594196Y-128577D01*
X594159Y-128581D01*
X594119Y-128592D01*
X594068Y-128606D01*
X594017Y-128632D01*
X593966Y-128665D01*
X593915Y-128708D01*
X593908Y-128716D01*
X593894Y-128734D01*
X593875Y-128759D01*
X593850Y-128799D01*
X593828Y-128850D01*
X593806Y-128909D01*
X593792Y-128978D01*
X593788Y-129054D01*
Y-129076D01*
X593792Y-129090D01*
X593795Y-129134D01*
X593806Y-129185D01*
X593821Y-129240D01*
X593846Y-129302D01*
X593879Y-129360D01*
X593923Y-129414D01*
X593930Y-129422D01*
X593948Y-129436D01*
X593977Y-129458D01*
X594021Y-129480D01*
X594072Y-129506D01*
X594137Y-129527D01*
X594210Y-129542D01*
X594294Y-129549D01*
X594261Y-129866D01*
X594258D01*
X594247Y-129862D01*
X594229D01*
X594203Y-129859D01*
X594174Y-129851D01*
X594141Y-129844D01*
X594101Y-129833D01*
X594061Y-129822D01*
X593974Y-129793D01*
X593886Y-129749D01*
X593843Y-129724D01*
X593799Y-129691D01*
X593759Y-129658D01*
X593722Y-129622D01*
X593719Y-129618D01*
X593715Y-129611D01*
X593704Y-129600D01*
X593693Y-129582D01*
X593679Y-129560D01*
X593664Y-129535D01*
X593646Y-129506D01*
X593628Y-129469D01*
X593610Y-129429D01*
X593591Y-129385D01*
X593577Y-129338D01*
X593562Y-129287D01*
X593551Y-129233D01*
X593540Y-129174D01*
X593537Y-129112D01*
X593533Y-129047D01*
Y-129010D01*
X593537Y-128985D01*
X593540Y-128956D01*
X593544Y-128919D01*
X593551Y-128879D01*
X593559Y-128839D01*
X593584Y-128745D01*
X593621Y-128650D01*
X593642Y-128603D01*
X593668Y-128555D01*
X593701Y-128512D01*
X593737Y-128472D01*
X593741Y-128468D01*
X593744Y-128461D01*
X593759Y-128454D01*
X593774Y-128439D01*
X593792Y-128421D01*
X593817Y-128402D01*
X593843Y-128384D01*
X593875Y-128363D01*
X593945Y-128326D01*
X594032Y-128290D01*
X594076Y-128275D01*
X594127Y-128268D01*
X594177Y-128261D01*
X594232Y-128257D01*
X594239D01*
X594258D01*
X594287Y-128261D01*
X594327Y-128264D01*
X594370Y-128271D01*
X594421Y-128286D01*
X594476Y-128301D01*
X594531Y-128323D01*
X594538Y-128326D01*
X594556Y-128333D01*
X594585Y-128348D01*
X594625Y-128370D01*
X594669Y-128399D01*
X594724Y-128435D01*
X594778Y-128479D01*
X594840Y-128530D01*
X594847Y-128537D01*
X594869Y-128555D01*
X594887Y-128574D01*
X594906Y-128592D01*
X594927Y-128614D01*
X594956Y-128643D01*
X594986Y-128672D01*
X595018Y-128708D01*
X595055Y-128745D01*
X595095Y-128788D01*
X595135Y-128836D01*
X595182Y-128887D01*
X595229Y-128945D01*
X595280Y-129003D01*
X595284Y-129007D01*
X595291Y-129014D01*
X595302Y-129029D01*
X595317Y-129047D01*
X595339Y-129069D01*
X595361Y-129094D01*
X595408Y-129152D01*
X595462Y-129214D01*
X595517Y-129272D01*
X595564Y-129323D01*
X595582Y-129345D01*
X595601Y-129364D01*
X595604Y-129367D01*
X595615Y-129378D01*
X595630Y-129393D01*
X595652Y-129411D01*
X595677Y-129429D01*
X595703Y-129451D01*
X595764Y-129495D01*
Y-128253D01*
X596063D01*
Y-129924D01*
D02*
G37*
G36*
Y-130983D02*
X594094D01*
X594097Y-130987D01*
X594112Y-131005D01*
X594134Y-131027D01*
X594159Y-131063D01*
X594192Y-131103D01*
X594229Y-131154D01*
X594269Y-131213D01*
X594309Y-131278D01*
Y-131282D01*
X594312Y-131285D01*
X594327Y-131307D01*
X594345Y-131344D01*
X594367Y-131387D01*
X594392Y-131438D01*
X594418Y-131493D01*
X594443Y-131547D01*
X594465Y-131602D01*
X594167D01*
Y-131598D01*
X594159Y-131591D01*
X594156Y-131577D01*
X594145Y-131558D01*
X594134Y-131537D01*
X594119Y-131511D01*
X594083Y-131449D01*
X594043Y-131376D01*
X593992Y-131304D01*
X593934Y-131227D01*
X593872Y-131151D01*
X593868Y-131147D01*
X593864Y-131143D01*
X593854Y-131132D01*
X593843Y-131118D01*
X593806Y-131085D01*
X593763Y-131042D01*
X593712Y-130998D01*
X593653Y-130950D01*
X593595Y-130911D01*
X593533Y-130874D01*
Y-130674D01*
X596063D01*
Y-130983D01*
D02*
G37*
G36*
X594866Y-132174D02*
X594895D01*
X594964Y-132177D01*
X595044Y-132188D01*
X595127Y-132199D01*
X595215Y-132217D01*
X595302Y-132239D01*
X595306D01*
X595313Y-132243D01*
X595324Y-132246D01*
X595339Y-132250D01*
X595379Y-132265D01*
X595430Y-132286D01*
X595488Y-132308D01*
X595546Y-132337D01*
X595608Y-132374D01*
X595666Y-132410D01*
X595674Y-132414D01*
X595692Y-132428D01*
X595717Y-132450D01*
X595750Y-132479D01*
X595786Y-132512D01*
X595823Y-132552D01*
X595863Y-132592D01*
X595896Y-132640D01*
X595899Y-132647D01*
X595910Y-132661D01*
X595925Y-132687D01*
X595943Y-132723D01*
X595965Y-132767D01*
X595983Y-132818D01*
X596005Y-132876D01*
X596023Y-132942D01*
Y-132949D01*
X596027Y-132960D01*
X596030Y-132971D01*
X596034Y-133007D01*
X596041Y-133058D01*
X596048Y-133116D01*
X596056Y-133186D01*
X596059Y-133262D01*
X596063Y-133346D01*
Y-134252D01*
X593544D01*
Y-133284D01*
X593548Y-133218D01*
X593551Y-133145D01*
X593559Y-133073D01*
X593570Y-133000D01*
X593581Y-132938D01*
Y-132934D01*
X593584Y-132927D01*
Y-132916D01*
X593591Y-132902D01*
X593602Y-132862D01*
X593621Y-132811D01*
X593646Y-132752D01*
X593679Y-132691D01*
X593715Y-132629D01*
X593763Y-132570D01*
X593766Y-132567D01*
X593770Y-132563D01*
X593781Y-132552D01*
X593792Y-132538D01*
X593828Y-132501D01*
X593879Y-132457D01*
X593941Y-132410D01*
X594014Y-132359D01*
X594097Y-132312D01*
X594192Y-132272D01*
X594196D01*
X594203Y-132268D01*
X594218Y-132261D01*
X594239Y-132257D01*
X594265Y-132246D01*
X594294Y-132239D01*
X594327Y-132232D01*
X594367Y-132221D01*
X594407Y-132210D01*
X594454Y-132203D01*
X594556Y-132185D01*
X594669Y-132174D01*
X594793Y-132170D01*
X594796D01*
X594804D01*
X594822D01*
X594840D01*
X594866Y-132174D01*
D02*
G37*
G36*
X658279Y-130279D02*
X658305Y-130282D01*
X658337Y-130286D01*
X658374Y-130293D01*
X658414Y-130304D01*
X658497Y-130330D01*
X658545Y-130348D01*
X658589Y-130373D01*
X658636Y-130399D01*
X658679Y-130428D01*
X658723Y-130464D01*
X658767Y-130504D01*
X658770Y-130508D01*
X658778Y-130515D01*
X658789Y-130526D01*
X658800Y-130544D01*
X658818Y-130570D01*
X658836Y-130595D01*
X658854Y-130628D01*
X658876Y-130664D01*
X658898Y-130704D01*
X658916Y-130752D01*
X658934Y-130803D01*
X658953Y-130854D01*
X658963Y-130912D01*
X658974Y-130974D01*
X658982Y-131036D01*
X658985Y-131105D01*
Y-131141D01*
X658982Y-131167D01*
X658978Y-131200D01*
X658974Y-131236D01*
X658967Y-131276D01*
X658956Y-131320D01*
X658931Y-131418D01*
X658912Y-131469D01*
X658894Y-131516D01*
X658869Y-131567D01*
X658840Y-131618D01*
X658807Y-131665D01*
X658767Y-131709D01*
X658763Y-131713D01*
X658756Y-131720D01*
X658745Y-131731D01*
X658727Y-131746D01*
X658705Y-131760D01*
X658679Y-131782D01*
X658650Y-131800D01*
X658614Y-131822D01*
X658577Y-131844D01*
X658534Y-131862D01*
X658443Y-131898D01*
X658388Y-131913D01*
X658334Y-131924D01*
X658275Y-131931D01*
X658217Y-131935D01*
X658214D01*
X658206D01*
X658192D01*
X658177Y-131931D01*
X658155D01*
X658130Y-131928D01*
X658072Y-131920D01*
X658006Y-131906D01*
X657940Y-131884D01*
X657871Y-131851D01*
X657806Y-131811D01*
X657802D01*
X657799Y-131804D01*
X657780Y-131789D01*
X657751Y-131760D01*
X657715Y-131720D01*
X657678Y-131669D01*
X657638Y-131607D01*
X657606Y-131538D01*
X657580Y-131454D01*
Y-131458D01*
X657577Y-131462D01*
X657573Y-131473D01*
X657566Y-131487D01*
X657551Y-131520D01*
X657529Y-131563D01*
X657500Y-131611D01*
X657464Y-131658D01*
X657424Y-131702D01*
X657380Y-131742D01*
X657373Y-131746D01*
X657358Y-131756D01*
X657329Y-131771D01*
X657293Y-131786D01*
X657245Y-131804D01*
X657191Y-131818D01*
X657129Y-131829D01*
X657063Y-131833D01*
X657060D01*
X657052D01*
X657038D01*
X657016Y-131829D01*
X656994Y-131826D01*
X656965Y-131822D01*
X656903Y-131807D01*
X656830Y-131786D01*
X656754Y-131749D01*
X656714Y-131727D01*
X656674Y-131702D01*
X656637Y-131669D01*
X656601Y-131636D01*
X656597Y-131633D01*
X656594Y-131625D01*
X656583Y-131614D01*
X656572Y-131600D01*
X656557Y-131582D01*
X656543Y-131556D01*
X656525Y-131527D01*
X656506Y-131498D01*
X656488Y-131462D01*
X656470Y-131422D01*
X656455Y-131378D01*
X656441Y-131331D01*
X656419Y-131229D01*
X656415Y-131170D01*
X656412Y-131112D01*
Y-131079D01*
X656415Y-131058D01*
X656419Y-131028D01*
X656423Y-130996D01*
X656426Y-130959D01*
X656437Y-130923D01*
X656459Y-130835D01*
X656492Y-130748D01*
X656514Y-130704D01*
X656539Y-130661D01*
X656572Y-130621D01*
X656605Y-130581D01*
X656608Y-130577D01*
X656612Y-130573D01*
X656623Y-130562D01*
X656637Y-130548D01*
X656659Y-130533D01*
X656681Y-130515D01*
X656736Y-130479D01*
X656805Y-130442D01*
X656885Y-130410D01*
X656976Y-130384D01*
X657023Y-130380D01*
X657074Y-130377D01*
X657078D01*
X657082D01*
X657103D01*
X657136Y-130380D01*
X657176Y-130388D01*
X657227Y-130399D01*
X657278Y-130417D01*
X657329Y-130439D01*
X657380Y-130472D01*
X657387Y-130475D01*
X657402Y-130490D01*
X657424Y-130512D01*
X657453Y-130541D01*
X657485Y-130581D01*
X657518Y-130628D01*
X657551Y-130683D01*
X657580Y-130748D01*
Y-130745D01*
X657584Y-130737D01*
X657587Y-130726D01*
X657595Y-130712D01*
X657613Y-130668D01*
X657638Y-130617D01*
X657675Y-130562D01*
X657715Y-130504D01*
X657766Y-130450D01*
X657824Y-130399D01*
X657828D01*
X657831Y-130395D01*
X657853Y-130380D01*
X657890Y-130359D01*
X657937Y-130337D01*
X657995Y-130315D01*
X658064Y-130293D01*
X658141Y-130279D01*
X658224Y-130275D01*
X658228D01*
X658239D01*
X658257D01*
X658279Y-130279D01*
D02*
G37*
G36*
X658254Y-132241D02*
X658283Y-132244D01*
X658315Y-132252D01*
X658352Y-132259D01*
X658392Y-132266D01*
X658479Y-132295D01*
X658527Y-132317D01*
X658570Y-132339D01*
X658618Y-132368D01*
X658665Y-132401D01*
X658712Y-132437D01*
X658756Y-132481D01*
X658759Y-132484D01*
X658767Y-132492D01*
X658778Y-132506D01*
X658792Y-132525D01*
X658811Y-132546D01*
X658829Y-132575D01*
X658850Y-132608D01*
X658869Y-132648D01*
X658891Y-132688D01*
X658912Y-132736D01*
X658931Y-132783D01*
X658949Y-132837D01*
X658963Y-132896D01*
X658974Y-132958D01*
X658982Y-133019D01*
X658985Y-133089D01*
Y-133121D01*
X658982Y-133143D01*
X658978Y-133172D01*
X658974Y-133205D01*
X658967Y-133242D01*
X658960Y-133282D01*
X658938Y-133369D01*
X658902Y-133460D01*
X658880Y-133507D01*
X658854Y-133551D01*
X658821Y-133595D01*
X658789Y-133638D01*
X658785Y-133642D01*
X658778Y-133649D01*
X658767Y-133660D01*
X658752Y-133671D01*
X658734Y-133689D01*
X658709Y-133707D01*
X658683Y-133729D01*
X658650Y-133751D01*
X658614Y-133773D01*
X658577Y-133795D01*
X658490Y-133835D01*
X658388Y-133868D01*
X658334Y-133879D01*
X658275Y-133886D01*
X658235Y-133576D01*
X658239D01*
X658246Y-133573D01*
X658261Y-133569D01*
X658279Y-133565D01*
X658301Y-133562D01*
X658326Y-133555D01*
X658381Y-133536D01*
X658447Y-133511D01*
X658508Y-133478D01*
X658567Y-133442D01*
X658618Y-133398D01*
X658621Y-133391D01*
X658636Y-133376D01*
X658654Y-133347D01*
X658672Y-133311D01*
X658694Y-133267D01*
X658712Y-133212D01*
X658727Y-133150D01*
X658730Y-133085D01*
Y-133063D01*
X658727Y-133049D01*
X658723Y-133009D01*
X658712Y-132958D01*
X658694Y-132899D01*
X658669Y-132837D01*
X658632Y-132776D01*
X658581Y-132717D01*
X658574Y-132710D01*
X658552Y-132692D01*
X658519Y-132670D01*
X658476Y-132641D01*
X658421Y-132612D01*
X658359Y-132590D01*
X658286Y-132572D01*
X658206Y-132564D01*
X658203D01*
X658195D01*
X658184D01*
X658170Y-132568D01*
X658130Y-132572D01*
X658082Y-132583D01*
X658024Y-132597D01*
X657966Y-132623D01*
X657908Y-132659D01*
X657853Y-132706D01*
X657846Y-132714D01*
X657831Y-132732D01*
X657809Y-132761D01*
X657784Y-132801D01*
X657759Y-132852D01*
X657737Y-132914D01*
X657722Y-132983D01*
X657715Y-133060D01*
Y-133092D01*
X657719Y-133118D01*
X657722Y-133150D01*
X657729Y-133187D01*
X657737Y-133231D01*
X657748Y-133278D01*
X657475Y-133242D01*
Y-133223D01*
X657478Y-133209D01*
Y-133161D01*
X657471Y-133121D01*
X657464Y-133074D01*
X657453Y-133019D01*
X657435Y-132958D01*
X657409Y-132899D01*
X657376Y-132837D01*
Y-132834D01*
X657373Y-132830D01*
X657358Y-132812D01*
X657333Y-132787D01*
X657300Y-132757D01*
X657253Y-132728D01*
X657198Y-132703D01*
X657136Y-132685D01*
X657100Y-132677D01*
X657060D01*
X657056D01*
X657052D01*
X657030D01*
X657001Y-132685D01*
X656961Y-132692D01*
X656918Y-132706D01*
X656870Y-132725D01*
X656823Y-132754D01*
X656779Y-132794D01*
X656776Y-132798D01*
X656761Y-132816D01*
X656743Y-132841D01*
X656721Y-132874D01*
X656703Y-132918D01*
X656685Y-132969D01*
X656670Y-133027D01*
X656667Y-133092D01*
Y-133121D01*
X656674Y-133154D01*
X656681Y-133198D01*
X656696Y-133245D01*
X656714Y-133292D01*
X656743Y-133344D01*
X656779Y-133391D01*
X656783Y-133394D01*
X656801Y-133409D01*
X656827Y-133431D01*
X656863Y-133456D01*
X656910Y-133482D01*
X656969Y-133507D01*
X657038Y-133529D01*
X657118Y-133544D01*
X657063Y-133853D01*
X657060D01*
X657049Y-133849D01*
X657034Y-133846D01*
X657012Y-133842D01*
X656987Y-133835D01*
X656958Y-133824D01*
X656889Y-133802D01*
X656809Y-133766D01*
X656728Y-133722D01*
X656652Y-133667D01*
X656583Y-133598D01*
X656579Y-133595D01*
X656575Y-133587D01*
X656568Y-133576D01*
X656557Y-133562D01*
X656543Y-133544D01*
X656528Y-133518D01*
X656514Y-133493D01*
X656495Y-133460D01*
X656466Y-133387D01*
X656437Y-133303D01*
X656419Y-133205D01*
X656412Y-133154D01*
Y-133063D01*
X656415Y-133023D01*
X656423Y-132976D01*
X656434Y-132918D01*
X656452Y-132852D01*
X656474Y-132787D01*
X656503Y-132721D01*
Y-132717D01*
X656506Y-132714D01*
X656517Y-132692D01*
X656539Y-132659D01*
X656565Y-132623D01*
X656601Y-132579D01*
X656641Y-132535D01*
X656688Y-132492D01*
X656743Y-132455D01*
X656750Y-132452D01*
X656769Y-132441D01*
X656801Y-132426D01*
X656841Y-132408D01*
X656889Y-132390D01*
X656943Y-132375D01*
X657005Y-132364D01*
X657067Y-132361D01*
X657074D01*
X657096D01*
X657125Y-132364D01*
X657165Y-132372D01*
X657212Y-132383D01*
X657264Y-132401D01*
X657314Y-132423D01*
X657365Y-132452D01*
X657373Y-132455D01*
X657387Y-132466D01*
X657413Y-132488D01*
X657442Y-132517D01*
X657475Y-132554D01*
X657511Y-132597D01*
X657544Y-132648D01*
X657577Y-132710D01*
Y-132706D01*
X657580Y-132699D01*
X657584Y-132688D01*
X657587Y-132674D01*
X657602Y-132634D01*
X657624Y-132583D01*
X657653Y-132525D01*
X657689Y-132466D01*
X657737Y-132412D01*
X657791Y-132361D01*
X657799Y-132357D01*
X657820Y-132343D01*
X657857Y-132321D01*
X657904Y-132299D01*
X657962Y-132277D01*
X658032Y-132255D01*
X658112Y-132241D01*
X658199Y-132237D01*
X658203D01*
X658214D01*
X658232D01*
X658254Y-132241D01*
D02*
G37*
G36*
X658221Y-134312D02*
X658250D01*
X658319Y-134319D01*
X658399Y-134326D01*
X658483Y-134341D01*
X658559Y-134363D01*
X658632Y-134388D01*
X658636D01*
X658639Y-134392D01*
X658661Y-134403D01*
X658690Y-134421D01*
X658730Y-134446D01*
X658770Y-134483D01*
X658814Y-134523D01*
X658858Y-134574D01*
X658894Y-134632D01*
X658898Y-134639D01*
X658909Y-134661D01*
X658923Y-134694D01*
X658938Y-134741D01*
X658956Y-134800D01*
X658971Y-134865D01*
X658982Y-134938D01*
X658985Y-135018D01*
Y-135051D01*
X658982Y-135073D01*
X658978Y-135102D01*
X658974Y-135131D01*
X658960Y-135207D01*
X658938Y-135287D01*
X658905Y-135371D01*
X658883Y-135415D01*
X658858Y-135455D01*
X658829Y-135491D01*
X658796Y-135528D01*
X658792Y-135531D01*
X658789Y-135535D01*
X658774Y-135542D01*
X658759Y-135553D01*
X658741Y-135567D01*
X658716Y-135582D01*
X658687Y-135597D01*
X658654Y-135615D01*
X658618Y-135629D01*
X658574Y-135644D01*
X658530Y-135659D01*
X658479Y-135673D01*
X658425Y-135680D01*
X658363Y-135691D01*
X658301Y-135695D01*
X658232D01*
X658188Y-135393D01*
X658192D01*
X658199D01*
X658214D01*
X658235Y-135389D01*
X658257Y-135386D01*
X658283D01*
X658345Y-135375D01*
X658410Y-135364D01*
X658476Y-135342D01*
X658534Y-135320D01*
X658559Y-135305D01*
X658581Y-135287D01*
X658585Y-135284D01*
X658596Y-135269D01*
X658614Y-135247D01*
X658632Y-135218D01*
X658654Y-135178D01*
X658669Y-135134D01*
X658683Y-135080D01*
X658687Y-135021D01*
Y-135000D01*
X658683Y-134978D01*
X658679Y-134945D01*
X658672Y-134912D01*
X658665Y-134876D01*
X658650Y-134839D01*
X658632Y-134803D01*
X658629Y-134800D01*
X658621Y-134789D01*
X658607Y-134774D01*
X658592Y-134752D01*
X658567Y-134734D01*
X658541Y-134712D01*
X658512Y-134694D01*
X658476Y-134679D01*
X658472D01*
X658457Y-134672D01*
X658432Y-134668D01*
X658399Y-134661D01*
X658356Y-134654D01*
X658301Y-134650D01*
X658235Y-134643D01*
X658159D01*
X656423D01*
Y-134308D01*
X658141D01*
X658144D01*
X658155D01*
X658170D01*
X658192D01*
X658221Y-134312D01*
D02*
G37*
G36*
X559843Y-169295D02*
X559872Y-169299D01*
X559905Y-169302D01*
X559941Y-169309D01*
X559981Y-169317D01*
X560069Y-169339D01*
X560159Y-169375D01*
X560207Y-169397D01*
X560251Y-169422D01*
X560294Y-169455D01*
X560338Y-169488D01*
X560342Y-169492D01*
X560349Y-169499D01*
X560360Y-169510D01*
X560371Y-169524D01*
X560389Y-169543D01*
X560407Y-169568D01*
X560429Y-169593D01*
X560451Y-169626D01*
X560472Y-169663D01*
X560494Y-169699D01*
X560534Y-169786D01*
X560567Y-169888D01*
X560578Y-169943D01*
X560585Y-170001D01*
X560276Y-170041D01*
Y-170037D01*
X560272Y-170030D01*
X560269Y-170016D01*
X560265Y-169998D01*
X560261Y-169976D01*
X560254Y-169950D01*
X560236Y-169896D01*
X560211Y-169830D01*
X560178Y-169768D01*
X560141Y-169710D01*
X560098Y-169659D01*
X560090Y-169655D01*
X560076Y-169641D01*
X560047Y-169623D01*
X560010Y-169604D01*
X559967Y-169582D01*
X559912Y-169564D01*
X559850Y-169550D01*
X559785Y-169546D01*
X559763D01*
X559748Y-169550D01*
X559708Y-169553D01*
X559657Y-169564D01*
X559599Y-169582D01*
X559537Y-169608D01*
X559475Y-169644D01*
X559417Y-169695D01*
X559410Y-169703D01*
X559391Y-169725D01*
X559370Y-169757D01*
X559340Y-169801D01*
X559311Y-169855D01*
X559290Y-169917D01*
X559271Y-169990D01*
X559264Y-170070D01*
Y-170074D01*
Y-170081D01*
Y-170092D01*
X559268Y-170107D01*
X559271Y-170147D01*
X559282Y-170194D01*
X559297Y-170252D01*
X559322Y-170310D01*
X559359Y-170369D01*
X559406Y-170423D01*
X559413Y-170431D01*
X559432Y-170445D01*
X559461Y-170467D01*
X559501Y-170492D01*
X559552Y-170518D01*
X559614Y-170540D01*
X559683Y-170554D01*
X559759Y-170562D01*
X559792D01*
X559817Y-170558D01*
X559850Y-170554D01*
X559887Y-170547D01*
X559930Y-170540D01*
X559977Y-170529D01*
X559941Y-170802D01*
X559923D01*
X559908Y-170798D01*
X559861D01*
X559821Y-170806D01*
X559774Y-170813D01*
X559719Y-170824D01*
X559657Y-170842D01*
X559599Y-170867D01*
X559537Y-170900D01*
X559533D01*
X559530Y-170904D01*
X559512Y-170918D01*
X559486Y-170944D01*
X559457Y-170977D01*
X559428Y-171024D01*
X559402Y-171079D01*
X559384Y-171140D01*
X559377Y-171177D01*
Y-171217D01*
Y-171221D01*
Y-171224D01*
Y-171246D01*
X559384Y-171275D01*
X559391Y-171315D01*
X559406Y-171359D01*
X559424Y-171406D01*
X559453Y-171453D01*
X559493Y-171497D01*
X559497Y-171501D01*
X559515Y-171515D01*
X559541Y-171534D01*
X559574Y-171555D01*
X559617Y-171574D01*
X559668Y-171592D01*
X559726Y-171606D01*
X559792Y-171610D01*
X559821D01*
X559854Y-171603D01*
X559897Y-171595D01*
X559945Y-171581D01*
X559992Y-171563D01*
X560043Y-171534D01*
X560090Y-171497D01*
X560094Y-171493D01*
X560109Y-171475D01*
X560130Y-171450D01*
X560156Y-171413D01*
X560181Y-171366D01*
X560207Y-171308D01*
X560229Y-171239D01*
X560243Y-171159D01*
X560553Y-171213D01*
Y-171217D01*
X560549Y-171228D01*
X560545Y-171242D01*
X560542Y-171264D01*
X560534Y-171290D01*
X560524Y-171319D01*
X560502Y-171388D01*
X560465Y-171468D01*
X560422Y-171548D01*
X560367Y-171625D01*
X560298Y-171694D01*
X560294Y-171697D01*
X560287Y-171701D01*
X560276Y-171708D01*
X560261Y-171719D01*
X560243Y-171734D01*
X560218Y-171748D01*
X560192Y-171763D01*
X560159Y-171781D01*
X560087Y-171810D01*
X560003Y-171839D01*
X559905Y-171858D01*
X559854Y-171865D01*
X559763D01*
X559723Y-171861D01*
X559675Y-171854D01*
X559617Y-171843D01*
X559552Y-171825D01*
X559486Y-171803D01*
X559421Y-171774D01*
X559417D01*
X559413Y-171770D01*
X559391Y-171759D01*
X559359Y-171737D01*
X559322Y-171712D01*
X559279Y-171676D01*
X559235Y-171635D01*
X559191Y-171588D01*
X559155Y-171534D01*
X559151Y-171526D01*
X559140Y-171508D01*
X559126Y-171475D01*
X559107Y-171435D01*
X559089Y-171388D01*
X559075Y-171333D01*
X559064Y-171272D01*
X559060Y-171210D01*
Y-171202D01*
Y-171180D01*
X559064Y-171151D01*
X559071Y-171111D01*
X559082Y-171064D01*
X559100Y-171013D01*
X559122Y-170962D01*
X559151Y-170911D01*
X559155Y-170904D01*
X559166Y-170889D01*
X559188Y-170864D01*
X559217Y-170835D01*
X559253Y-170802D01*
X559297Y-170765D01*
X559348Y-170733D01*
X559410Y-170700D01*
X559406D01*
X559399Y-170696D01*
X559388Y-170693D01*
X559373Y-170689D01*
X559333Y-170675D01*
X559282Y-170653D01*
X559224Y-170624D01*
X559166Y-170587D01*
X559111Y-170540D01*
X559060Y-170485D01*
X559057Y-170478D01*
X559042Y-170456D01*
X559020Y-170420D01*
X558998Y-170372D01*
X558977Y-170314D01*
X558955Y-170245D01*
X558940Y-170165D01*
X558937Y-170078D01*
Y-170074D01*
Y-170063D01*
Y-170045D01*
X558940Y-170023D01*
X558944Y-169994D01*
X558951Y-169961D01*
X558958Y-169925D01*
X558966Y-169885D01*
X558995Y-169797D01*
X559017Y-169750D01*
X559038Y-169706D01*
X559067Y-169659D01*
X559100Y-169612D01*
X559137Y-169564D01*
X559180Y-169521D01*
X559184Y-169517D01*
X559191Y-169510D01*
X559206Y-169499D01*
X559224Y-169484D01*
X559246Y-169466D01*
X559275Y-169448D01*
X559308Y-169426D01*
X559348Y-169408D01*
X559388Y-169386D01*
X559435Y-169364D01*
X559482Y-169346D01*
X559537Y-169328D01*
X559595Y-169313D01*
X559657Y-169302D01*
X559719Y-169295D01*
X559788Y-169291D01*
X559821D01*
X559843Y-169295D01*
D02*
G37*
G36*
X564961Y-171854D02*
X563992D01*
X563927Y-171850D01*
X563854Y-171847D01*
X563781Y-171839D01*
X563708Y-171828D01*
X563647Y-171818D01*
X563643D01*
X563636Y-171814D01*
X563625D01*
X563610Y-171807D01*
X563570Y-171796D01*
X563519Y-171777D01*
X563461Y-171752D01*
X563399Y-171719D01*
X563337Y-171683D01*
X563279Y-171635D01*
X563275Y-171632D01*
X563272Y-171628D01*
X563261Y-171617D01*
X563246Y-171606D01*
X563210Y-171570D01*
X563166Y-171519D01*
X563119Y-171457D01*
X563068Y-171384D01*
X563021Y-171301D01*
X562981Y-171206D01*
Y-171202D01*
X562977Y-171195D01*
X562970Y-171180D01*
X562966Y-171159D01*
X562955Y-171133D01*
X562948Y-171104D01*
X562941Y-171071D01*
X562929Y-171031D01*
X562919Y-170991D01*
X562911Y-170944D01*
X562893Y-170842D01*
X562882Y-170729D01*
X562879Y-170605D01*
Y-170602D01*
Y-170594D01*
Y-170576D01*
Y-170558D01*
X562882Y-170533D01*
Y-170503D01*
X562886Y-170434D01*
X562897Y-170354D01*
X562908Y-170271D01*
X562926Y-170183D01*
X562948Y-170096D01*
Y-170092D01*
X562951Y-170085D01*
X562955Y-170074D01*
X562959Y-170059D01*
X562973Y-170019D01*
X562995Y-169968D01*
X563017Y-169910D01*
X563046Y-169852D01*
X563082Y-169790D01*
X563119Y-169732D01*
X563123Y-169725D01*
X563137Y-169706D01*
X563159Y-169681D01*
X563188Y-169648D01*
X563221Y-169612D01*
X563261Y-169575D01*
X563301Y-169535D01*
X563348Y-169502D01*
X563355Y-169499D01*
X563370Y-169488D01*
X563396Y-169473D01*
X563432Y-169455D01*
X563476Y-169433D01*
X563526Y-169415D01*
X563585Y-169393D01*
X563650Y-169375D01*
X563658D01*
X563668Y-169371D01*
X563679Y-169368D01*
X563716Y-169364D01*
X563767Y-169357D01*
X563825Y-169350D01*
X563894Y-169342D01*
X563971Y-169339D01*
X564054Y-169335D01*
X564961D01*
Y-171854D01*
D02*
G37*
G36*
X562591Y-169339D02*
Y-169353D01*
Y-169375D01*
X562587Y-169404D01*
X562584Y-169437D01*
X562576Y-169473D01*
X562569Y-169510D01*
X562555Y-169550D01*
Y-169553D01*
X562551Y-169557D01*
X562544Y-169579D01*
X562529Y-169612D01*
X562507Y-169655D01*
X562478Y-169706D01*
X562442Y-169764D01*
X562402Y-169823D01*
X562351Y-169885D01*
Y-169888D01*
X562344Y-169892D01*
X562325Y-169914D01*
X562292Y-169947D01*
X562245Y-169994D01*
X562191Y-170048D01*
X562121Y-170114D01*
X562038Y-170187D01*
X561947Y-170263D01*
X561943Y-170267D01*
X561929Y-170278D01*
X561907Y-170296D01*
X561881Y-170318D01*
X561848Y-170347D01*
X561808Y-170380D01*
X561768Y-170416D01*
X561721Y-170456D01*
X561630Y-170544D01*
X561539Y-170631D01*
X561495Y-170675D01*
X561455Y-170718D01*
X561419Y-170758D01*
X561390Y-170798D01*
Y-170802D01*
X561382Y-170806D01*
X561375Y-170817D01*
X561368Y-170831D01*
X561342Y-170871D01*
X561313Y-170918D01*
X561288Y-170977D01*
X561262Y-171038D01*
X561248Y-171108D01*
X561241Y-171173D01*
Y-171177D01*
Y-171180D01*
X561244Y-171202D01*
X561248Y-171239D01*
X561259Y-171279D01*
X561273Y-171330D01*
X561299Y-171381D01*
X561332Y-171432D01*
X561375Y-171483D01*
X561382Y-171490D01*
X561401Y-171504D01*
X561426Y-171523D01*
X561466Y-171548D01*
X561517Y-171570D01*
X561576Y-171592D01*
X561645Y-171606D01*
X561721Y-171610D01*
X561743D01*
X561758Y-171606D01*
X561801Y-171603D01*
X561852Y-171592D01*
X561907Y-171577D01*
X561969Y-171552D01*
X562027Y-171519D01*
X562081Y-171475D01*
X562089Y-171468D01*
X562103Y-171450D01*
X562125Y-171421D01*
X562147Y-171377D01*
X562172Y-171326D01*
X562194Y-171260D01*
X562209Y-171188D01*
X562216Y-171104D01*
X562533Y-171137D01*
Y-171140D01*
X562529Y-171151D01*
Y-171170D01*
X562526Y-171195D01*
X562518Y-171224D01*
X562511Y-171257D01*
X562500Y-171297D01*
X562489Y-171337D01*
X562460Y-171424D01*
X562416Y-171512D01*
X562391Y-171555D01*
X562358Y-171599D01*
X562325Y-171639D01*
X562289Y-171676D01*
X562285Y-171679D01*
X562278Y-171683D01*
X562267Y-171694D01*
X562249Y-171705D01*
X562227Y-171719D01*
X562201Y-171734D01*
X562172Y-171752D01*
X562136Y-171770D01*
X562096Y-171788D01*
X562052Y-171807D01*
X562005Y-171821D01*
X561954Y-171836D01*
X561899Y-171847D01*
X561841Y-171858D01*
X561779Y-171861D01*
X561714Y-171865D01*
X561677D01*
X561652Y-171861D01*
X561623Y-171858D01*
X561586Y-171854D01*
X561546Y-171847D01*
X561506Y-171839D01*
X561412Y-171814D01*
X561317Y-171777D01*
X561270Y-171756D01*
X561222Y-171730D01*
X561179Y-171697D01*
X561139Y-171661D01*
X561135Y-171657D01*
X561128Y-171654D01*
X561121Y-171639D01*
X561106Y-171625D01*
X561088Y-171606D01*
X561069Y-171581D01*
X561051Y-171555D01*
X561029Y-171523D01*
X560993Y-171453D01*
X560957Y-171366D01*
X560942Y-171322D01*
X560935Y-171272D01*
X560927Y-171221D01*
X560924Y-171166D01*
Y-171159D01*
Y-171140D01*
X560927Y-171111D01*
X560931Y-171071D01*
X560939Y-171028D01*
X560953Y-170977D01*
X560968Y-170922D01*
X560989Y-170867D01*
X560993Y-170860D01*
X561000Y-170842D01*
X561015Y-170813D01*
X561037Y-170773D01*
X561066Y-170729D01*
X561102Y-170675D01*
X561146Y-170620D01*
X561197Y-170558D01*
X561204Y-170551D01*
X561222Y-170529D01*
X561241Y-170511D01*
X561259Y-170492D01*
X561281Y-170471D01*
X561310Y-170442D01*
X561339Y-170412D01*
X561375Y-170380D01*
X561412Y-170343D01*
X561455Y-170303D01*
X561503Y-170263D01*
X561554Y-170216D01*
X561612Y-170169D01*
X561670Y-170118D01*
X561674Y-170114D01*
X561681Y-170107D01*
X561696Y-170096D01*
X561714Y-170081D01*
X561736Y-170059D01*
X561761Y-170037D01*
X561819Y-169990D01*
X561881Y-169936D01*
X561939Y-169881D01*
X561990Y-169834D01*
X562012Y-169816D01*
X562031Y-169797D01*
X562034Y-169794D01*
X562045Y-169783D01*
X562060Y-169768D01*
X562078Y-169746D01*
X562096Y-169721D01*
X562118Y-169695D01*
X562161Y-169633D01*
X560920D01*
Y-169335D01*
X562591D01*
Y-169339D01*
D02*
G37*
G36*
X624952Y-293537D02*
X624981Y-293541D01*
X625018Y-293544D01*
X625058Y-293551D01*
X625098Y-293559D01*
X625192Y-293584D01*
X625287Y-293621D01*
X625334Y-293642D01*
X625382Y-293668D01*
X625425Y-293701D01*
X625465Y-293737D01*
X625469Y-293741D01*
X625476Y-293744D01*
X625484Y-293759D01*
X625498Y-293774D01*
X625516Y-293792D01*
X625534Y-293817D01*
X625553Y-293843D01*
X625574Y-293875D01*
X625611Y-293945D01*
X625647Y-294032D01*
X625662Y-294076D01*
X625669Y-294127D01*
X625676Y-294178D01*
X625680Y-294232D01*
Y-294239D01*
Y-294258D01*
X625676Y-294287D01*
X625673Y-294327D01*
X625666Y-294370D01*
X625651Y-294421D01*
X625636Y-294476D01*
X625615Y-294531D01*
X625611Y-294538D01*
X625604Y-294556D01*
X625589Y-294585D01*
X625567Y-294625D01*
X625538Y-294669D01*
X625502Y-294724D01*
X625458Y-294778D01*
X625407Y-294840D01*
X625400Y-294847D01*
X625382Y-294869D01*
X625363Y-294887D01*
X625345Y-294905D01*
X625323Y-294927D01*
X625294Y-294956D01*
X625265Y-294986D01*
X625229Y-295018D01*
X625192Y-295055D01*
X625149Y-295095D01*
X625101Y-295135D01*
X625050Y-295182D01*
X624992Y-295230D01*
X624934Y-295280D01*
X624930Y-295284D01*
X624923Y-295291D01*
X624908Y-295302D01*
X624890Y-295317D01*
X624868Y-295339D01*
X624843Y-295360D01*
X624785Y-295408D01*
X624723Y-295462D01*
X624664Y-295517D01*
X624614Y-295564D01*
X624592Y-295583D01*
X624574Y-295601D01*
X624570Y-295604D01*
X624559Y-295615D01*
X624544Y-295630D01*
X624526Y-295652D01*
X624508Y-295677D01*
X624486Y-295703D01*
X624442Y-295765D01*
X625684D01*
Y-296063D01*
X624013D01*
Y-296059D01*
Y-296045D01*
Y-296023D01*
X624017Y-295994D01*
X624020Y-295961D01*
X624027Y-295925D01*
X624035Y-295888D01*
X624049Y-295848D01*
Y-295845D01*
X624053Y-295841D01*
X624060Y-295819D01*
X624075Y-295786D01*
X624097Y-295743D01*
X624126Y-295692D01*
X624162Y-295634D01*
X624202Y-295575D01*
X624253Y-295513D01*
Y-295510D01*
X624261Y-295506D01*
X624279Y-295484D01*
X624311Y-295451D01*
X624359Y-295404D01*
X624413Y-295350D01*
X624482Y-295284D01*
X624566Y-295211D01*
X624657Y-295135D01*
X624661Y-295131D01*
X624675Y-295120D01*
X624697Y-295102D01*
X624723Y-295080D01*
X624755Y-295051D01*
X624796Y-295018D01*
X624836Y-294982D01*
X624883Y-294942D01*
X624974Y-294855D01*
X625065Y-294767D01*
X625109Y-294724D01*
X625149Y-294680D01*
X625185Y-294640D01*
X625214Y-294600D01*
Y-294596D01*
X625221Y-294592D01*
X625229Y-294582D01*
X625236Y-294567D01*
X625261Y-294527D01*
X625291Y-294480D01*
X625316Y-294421D01*
X625342Y-294359D01*
X625356Y-294290D01*
X625363Y-294225D01*
Y-294221D01*
Y-294218D01*
X625360Y-294196D01*
X625356Y-294159D01*
X625345Y-294119D01*
X625331Y-294068D01*
X625305Y-294017D01*
X625272Y-293966D01*
X625229Y-293915D01*
X625221Y-293908D01*
X625203Y-293894D01*
X625178Y-293875D01*
X625138Y-293850D01*
X625087Y-293828D01*
X625029Y-293806D01*
X624959Y-293792D01*
X624883Y-293788D01*
X624861D01*
X624847Y-293792D01*
X624803Y-293795D01*
X624752Y-293806D01*
X624697Y-293821D01*
X624635Y-293846D01*
X624577Y-293879D01*
X624522Y-293923D01*
X624515Y-293930D01*
X624501Y-293948D01*
X624479Y-293977D01*
X624457Y-294021D01*
X624432Y-294072D01*
X624410Y-294138D01*
X624395Y-294210D01*
X624388Y-294294D01*
X624071Y-294261D01*
Y-294258D01*
X624075Y-294247D01*
Y-294229D01*
X624079Y-294203D01*
X624086Y-294174D01*
X624093Y-294141D01*
X624104Y-294101D01*
X624115Y-294061D01*
X624144Y-293974D01*
X624188Y-293886D01*
X624213Y-293843D01*
X624246Y-293799D01*
X624279Y-293759D01*
X624315Y-293723D01*
X624319Y-293719D01*
X624326Y-293715D01*
X624337Y-293704D01*
X624355Y-293693D01*
X624377Y-293679D01*
X624402Y-293664D01*
X624432Y-293646D01*
X624468Y-293628D01*
X624508Y-293610D01*
X624552Y-293591D01*
X624599Y-293577D01*
X624650Y-293562D01*
X624705Y-293551D01*
X624763Y-293541D01*
X624825Y-293537D01*
X624890Y-293533D01*
X624927D01*
X624952Y-293537D01*
D02*
G37*
G36*
X622994D02*
X623023Y-293541D01*
X623059Y-293544D01*
X623099Y-293551D01*
X623139Y-293559D01*
X623234Y-293584D01*
X623329Y-293621D01*
X623376Y-293642D01*
X623423Y-293668D01*
X623467Y-293701D01*
X623507Y-293737D01*
X623511Y-293741D01*
X623518Y-293744D01*
X623525Y-293759D01*
X623540Y-293774D01*
X623558Y-293792D01*
X623576Y-293817D01*
X623594Y-293843D01*
X623616Y-293875D01*
X623653Y-293945D01*
X623689Y-294032D01*
X623703Y-294076D01*
X623711Y-294127D01*
X623718Y-294178D01*
X623722Y-294232D01*
Y-294239D01*
Y-294258D01*
X623718Y-294287D01*
X623714Y-294327D01*
X623707Y-294370D01*
X623693Y-294421D01*
X623678Y-294476D01*
X623656Y-294531D01*
X623653Y-294538D01*
X623645Y-294556D01*
X623631Y-294585D01*
X623609Y-294625D01*
X623580Y-294669D01*
X623543Y-294724D01*
X623500Y-294778D01*
X623449Y-294840D01*
X623442Y-294847D01*
X623423Y-294869D01*
X623405Y-294887D01*
X623387Y-294905D01*
X623365Y-294927D01*
X623336Y-294956D01*
X623307Y-294986D01*
X623270Y-295018D01*
X623234Y-295055D01*
X623190Y-295095D01*
X623143Y-295135D01*
X623092Y-295182D01*
X623034Y-295230D01*
X622976Y-295280D01*
X622972Y-295284D01*
X622965Y-295291D01*
X622950Y-295302D01*
X622932Y-295317D01*
X622910Y-295339D01*
X622885Y-295360D01*
X622826Y-295408D01*
X622764Y-295462D01*
X622706Y-295517D01*
X622655Y-295564D01*
X622633Y-295583D01*
X622615Y-295601D01*
X622612Y-295604D01*
X622601Y-295615D01*
X622586Y-295630D01*
X622568Y-295652D01*
X622550Y-295677D01*
X622528Y-295703D01*
X622484Y-295765D01*
X623725D01*
Y-296063D01*
X622055D01*
Y-296059D01*
Y-296045D01*
Y-296023D01*
X622058Y-295994D01*
X622062Y-295961D01*
X622069Y-295925D01*
X622077Y-295888D01*
X622091Y-295848D01*
Y-295845D01*
X622095Y-295841D01*
X622102Y-295819D01*
X622117Y-295786D01*
X622138Y-295743D01*
X622167Y-295692D01*
X622204Y-295634D01*
X622244Y-295575D01*
X622295Y-295513D01*
Y-295510D01*
X622302Y-295506D01*
X622320Y-295484D01*
X622353Y-295451D01*
X622400Y-295404D01*
X622455Y-295350D01*
X622524Y-295284D01*
X622608Y-295211D01*
X622699Y-295135D01*
X622703Y-295131D01*
X622717Y-295120D01*
X622739Y-295102D01*
X622764Y-295080D01*
X622797Y-295051D01*
X622837Y-295018D01*
X622877Y-294982D01*
X622925Y-294942D01*
X623016Y-294855D01*
X623107Y-294767D01*
X623150Y-294724D01*
X623190Y-294680D01*
X623227Y-294640D01*
X623256Y-294600D01*
Y-294596D01*
X623263Y-294592D01*
X623270Y-294582D01*
X623278Y-294567D01*
X623303Y-294527D01*
X623332Y-294480D01*
X623358Y-294421D01*
X623383Y-294359D01*
X623398Y-294290D01*
X623405Y-294225D01*
Y-294221D01*
Y-294218D01*
X623401Y-294196D01*
X623398Y-294159D01*
X623387Y-294119D01*
X623372Y-294068D01*
X623347Y-294017D01*
X623314Y-293966D01*
X623270Y-293915D01*
X623263Y-293908D01*
X623245Y-293894D01*
X623219Y-293875D01*
X623179Y-293850D01*
X623128Y-293828D01*
X623070Y-293806D01*
X623001Y-293792D01*
X622925Y-293788D01*
X622903D01*
X622888Y-293792D01*
X622845Y-293795D01*
X622793Y-293806D01*
X622739Y-293821D01*
X622677Y-293846D01*
X622619Y-293879D01*
X622564Y-293923D01*
X622557Y-293930D01*
X622542Y-293948D01*
X622521Y-293977D01*
X622499Y-294021D01*
X622473Y-294072D01*
X622451Y-294138D01*
X622437Y-294210D01*
X622430Y-294294D01*
X622113Y-294261D01*
Y-294258D01*
X622117Y-294247D01*
Y-294229D01*
X622120Y-294203D01*
X622127Y-294174D01*
X622135Y-294141D01*
X622146Y-294101D01*
X622156Y-294061D01*
X622186Y-293974D01*
X622229Y-293886D01*
X622255Y-293843D01*
X622288Y-293799D01*
X622320Y-293759D01*
X622357Y-293723D01*
X622360Y-293719D01*
X622368Y-293715D01*
X622379Y-293704D01*
X622397Y-293693D01*
X622419Y-293679D01*
X622444Y-293664D01*
X622473Y-293646D01*
X622510Y-293628D01*
X622550Y-293610D01*
X622593Y-293591D01*
X622641Y-293577D01*
X622692Y-293562D01*
X622746Y-293551D01*
X622804Y-293541D01*
X622866Y-293537D01*
X622932Y-293533D01*
X622968D01*
X622994Y-293537D01*
D02*
G37*
G36*
X620719Y-293548D02*
X620792Y-293551D01*
X620864Y-293559D01*
X620937Y-293570D01*
X620999Y-293581D01*
X621003D01*
X621010Y-293584D01*
X621021D01*
X621035Y-293591D01*
X621075Y-293602D01*
X621126Y-293621D01*
X621185Y-293646D01*
X621247Y-293679D01*
X621308Y-293715D01*
X621367Y-293763D01*
X621370Y-293766D01*
X621374Y-293770D01*
X621385Y-293781D01*
X621399Y-293792D01*
X621436Y-293828D01*
X621480Y-293879D01*
X621527Y-293941D01*
X621578Y-294014D01*
X621625Y-294097D01*
X621665Y-294192D01*
Y-294196D01*
X621669Y-294203D01*
X621676Y-294218D01*
X621680Y-294239D01*
X621691Y-294265D01*
X621698Y-294294D01*
X621705Y-294327D01*
X621716Y-294367D01*
X621727Y-294407D01*
X621734Y-294454D01*
X621753Y-294556D01*
X621763Y-294669D01*
X621767Y-294793D01*
Y-294796D01*
Y-294804D01*
Y-294822D01*
Y-294840D01*
X621763Y-294865D01*
Y-294895D01*
X621760Y-294964D01*
X621749Y-295044D01*
X621738Y-295128D01*
X621720Y-295215D01*
X621698Y-295302D01*
Y-295306D01*
X621694Y-295313D01*
X621691Y-295324D01*
X621687Y-295339D01*
X621672Y-295379D01*
X621651Y-295430D01*
X621629Y-295488D01*
X621600Y-295546D01*
X621563Y-295608D01*
X621527Y-295666D01*
X621523Y-295674D01*
X621509Y-295692D01*
X621487Y-295717D01*
X621458Y-295750D01*
X621425Y-295786D01*
X621385Y-295823D01*
X621345Y-295863D01*
X621298Y-295896D01*
X621290Y-295899D01*
X621276Y-295910D01*
X621250Y-295925D01*
X621214Y-295943D01*
X621170Y-295965D01*
X621119Y-295983D01*
X621061Y-296005D01*
X620995Y-296023D01*
X620988D01*
X620977Y-296027D01*
X620966Y-296030D01*
X620930Y-296034D01*
X620879Y-296041D01*
X620821Y-296048D01*
X620751Y-296056D01*
X620675Y-296059D01*
X620591Y-296063D01*
X619685D01*
Y-293544D01*
X620653D01*
X620719Y-293548D01*
D02*
G37*
G36*
X597059Y-295673D02*
X597089D01*
X597121Y-295676D01*
X597158Y-295684D01*
X597201Y-295695D01*
X597245Y-295706D01*
X597296Y-295720D01*
X597347Y-295738D01*
X597398Y-295760D01*
X597453Y-295789D01*
X597504Y-295822D01*
X597555Y-295859D01*
X597606Y-295902D01*
X597653Y-295953D01*
X597656Y-295957D01*
X597664Y-295968D01*
X597675Y-295982D01*
X597689Y-296008D01*
X597711Y-296041D01*
X597729Y-296077D01*
X597751Y-296124D01*
X597773Y-296175D01*
X597798Y-296237D01*
X597820Y-296306D01*
X597838Y-296383D01*
X597857Y-296466D01*
X597875Y-296561D01*
X597886Y-296663D01*
X597893Y-296772D01*
X597897Y-296889D01*
Y-296892D01*
Y-296896D01*
Y-296907D01*
Y-296921D01*
X597893Y-296958D01*
Y-297009D01*
X597889Y-297067D01*
X597882Y-297136D01*
X597875Y-297213D01*
X597864Y-297296D01*
X597849Y-297380D01*
X597831Y-297471D01*
X597809Y-297558D01*
X597784Y-297646D01*
X597751Y-297729D01*
X597715Y-297810D01*
X597675Y-297886D01*
X597627Y-297952D01*
X597624Y-297955D01*
X597616Y-297962D01*
X597602Y-297977D01*
X597584Y-297999D01*
X597562Y-298021D01*
X597533Y-298042D01*
X597496Y-298072D01*
X597460Y-298097D01*
X597416Y-298123D01*
X597369Y-298152D01*
X597314Y-298174D01*
X597260Y-298199D01*
X597198Y-298217D01*
X597132Y-298232D01*
X597063Y-298239D01*
X596990Y-298243D01*
X596961D01*
X596939Y-298239D01*
X596914D01*
X596885Y-298235D01*
X596816Y-298221D01*
X596739Y-298203D01*
X596659Y-298174D01*
X596579Y-298130D01*
X596539Y-298104D01*
X596503Y-298075D01*
X596499Y-298072D01*
X596495Y-298068D01*
X596484Y-298057D01*
X596474Y-298046D01*
X596455Y-298028D01*
X596441Y-298006D01*
X596401Y-297955D01*
X596361Y-297890D01*
X596324Y-297810D01*
X596291Y-297719D01*
X596270Y-297617D01*
X596579Y-297591D01*
Y-297595D01*
X596583Y-297598D01*
X596586Y-297620D01*
X596597Y-297653D01*
X596612Y-297693D01*
X596626Y-297737D01*
X596648Y-297780D01*
X596674Y-297820D01*
X596699Y-297853D01*
X596706Y-297861D01*
X596721Y-297875D01*
X596746Y-297897D01*
X596783Y-297922D01*
X596830Y-297944D01*
X596881Y-297966D01*
X596943Y-297981D01*
X597009Y-297988D01*
X597034D01*
X597063Y-297984D01*
X597096Y-297977D01*
X597140Y-297966D01*
X597183Y-297952D01*
X597227Y-297933D01*
X597271Y-297904D01*
X597278Y-297901D01*
X597296Y-297886D01*
X597322Y-297861D01*
X597354Y-297824D01*
X597391Y-297780D01*
X597431Y-297729D01*
X597467Y-297664D01*
X597504Y-297591D01*
Y-297587D01*
X597507Y-297580D01*
X597511Y-297569D01*
X597518Y-297555D01*
X597522Y-297533D01*
X597529Y-297507D01*
X597536Y-297478D01*
X597544Y-297442D01*
X597555Y-297402D01*
X597562Y-297358D01*
X597569Y-297311D01*
X597573Y-297260D01*
X597580Y-297202D01*
X597584Y-297143D01*
X597587Y-297078D01*
Y-297012D01*
X597584Y-297016D01*
X597569Y-297038D01*
X597544Y-297067D01*
X597511Y-297103D01*
X597474Y-297147D01*
X597427Y-297187D01*
X597376Y-297227D01*
X597318Y-297264D01*
X597314D01*
X597311Y-297267D01*
X597289Y-297278D01*
X597256Y-297289D01*
X597212Y-297307D01*
X597161Y-297322D01*
X597103Y-297333D01*
X597041Y-297344D01*
X596976Y-297347D01*
X596947D01*
X596925Y-297344D01*
X596896Y-297340D01*
X596867Y-297336D01*
X596830Y-297329D01*
X596794Y-297318D01*
X596710Y-297293D01*
X596666Y-297274D01*
X596623Y-297249D01*
X596579Y-297223D01*
X596532Y-297194D01*
X596488Y-297158D01*
X596448Y-297118D01*
X596444Y-297114D01*
X596437Y-297107D01*
X596426Y-297096D01*
X596415Y-297078D01*
X596397Y-297052D01*
X596379Y-297027D01*
X596361Y-296994D01*
X596339Y-296958D01*
X596317Y-296918D01*
X596299Y-296874D01*
X596281Y-296823D01*
X596262Y-296772D01*
X596251Y-296718D01*
X596241Y-296656D01*
X596233Y-296594D01*
X596230Y-296528D01*
Y-296525D01*
Y-296517D01*
Y-296506D01*
Y-296488D01*
X596233Y-296466D01*
Y-296445D01*
X596244Y-296386D01*
X596255Y-296317D01*
X596273Y-296244D01*
X596299Y-296164D01*
X596335Y-296088D01*
Y-296084D01*
X596339Y-296081D01*
X596346Y-296070D01*
X596353Y-296055D01*
X596375Y-296019D01*
X596408Y-295971D01*
X596448Y-295920D01*
X596495Y-295869D01*
X596554Y-295818D01*
X596615Y-295775D01*
X596619D01*
X596623Y-295771D01*
X596634Y-295764D01*
X596648Y-295760D01*
X596685Y-295742D01*
X596732Y-295724D01*
X596794Y-295702D01*
X596863Y-295687D01*
X596939Y-295673D01*
X597023Y-295669D01*
X597041D01*
X597059Y-295673D01*
D02*
G37*
G36*
X599280D02*
X599313D01*
X599353Y-295676D01*
X599396Y-295684D01*
X599447Y-295691D01*
X599553Y-295709D01*
X599662Y-295738D01*
X599771Y-295778D01*
X599822Y-295804D01*
X599873Y-295833D01*
X599877Y-295837D01*
X599884Y-295840D01*
X599899Y-295851D01*
X599913Y-295866D01*
X599935Y-295880D01*
X599961Y-295902D01*
X599990Y-295928D01*
X600019Y-295957D01*
X600048Y-295990D01*
X600081Y-296022D01*
X600146Y-296106D01*
X600208Y-296204D01*
X600263Y-296314D01*
Y-296317D01*
X600270Y-296328D01*
X600274Y-296346D01*
X600285Y-296368D01*
X600292Y-296397D01*
X600303Y-296434D01*
X600317Y-296474D01*
X600328Y-296517D01*
X600339Y-296565D01*
X600354Y-296619D01*
X600372Y-296732D01*
X600386Y-296860D01*
X600394Y-296991D01*
Y-296994D01*
Y-297009D01*
Y-297031D01*
X600390Y-297056D01*
Y-297093D01*
X600386Y-297129D01*
X600383Y-297176D01*
X600376Y-297223D01*
X600357Y-297329D01*
X600332Y-297446D01*
X600295Y-297562D01*
X600245Y-297675D01*
X600241Y-297678D01*
X600237Y-297689D01*
X600230Y-297704D01*
X600215Y-297722D01*
X600201Y-297748D01*
X600183Y-297777D01*
X600135Y-297842D01*
X600073Y-297915D01*
X600001Y-297988D01*
X599917Y-298061D01*
X599819Y-298123D01*
X599815Y-298126D01*
X599804Y-298130D01*
X599789Y-298137D01*
X599771Y-298148D01*
X599742Y-298159D01*
X599713Y-298170D01*
X599677Y-298184D01*
X599637Y-298199D01*
X599593Y-298214D01*
X599546Y-298228D01*
X599444Y-298250D01*
X599327Y-298268D01*
X599207Y-298275D01*
X599171D01*
X599145Y-298272D01*
X599113Y-298268D01*
X599072Y-298265D01*
X599032Y-298261D01*
X598985Y-298250D01*
X598887Y-298228D01*
X598778Y-298195D01*
X598723Y-298174D01*
X598672Y-298148D01*
X598621Y-298115D01*
X598570Y-298083D01*
X598566Y-298079D01*
X598559Y-298075D01*
X598545Y-298064D01*
X598526Y-298046D01*
X598508Y-298028D01*
X598483Y-298003D01*
X598457Y-297973D01*
X598428Y-297944D01*
X598399Y-297908D01*
X598370Y-297864D01*
X598337Y-297820D01*
X598308Y-297773D01*
X598282Y-297719D01*
X598253Y-297664D01*
X598232Y-297606D01*
X598210Y-297540D01*
X598537Y-297464D01*
Y-297467D01*
X598541Y-297475D01*
X598548Y-297489D01*
X598556Y-297507D01*
X598563Y-297529D01*
X598574Y-297558D01*
X598603Y-297617D01*
X598639Y-297682D01*
X598683Y-297748D01*
X598738Y-297810D01*
X598796Y-297864D01*
X598803Y-297871D01*
X598825Y-297886D01*
X598861Y-297904D01*
X598909Y-297930D01*
X598971Y-297952D01*
X599040Y-297973D01*
X599123Y-297988D01*
X599214Y-297992D01*
X599243D01*
X599262Y-297988D01*
X599287D01*
X599316Y-297984D01*
X599385Y-297973D01*
X599462Y-297959D01*
X599542Y-297933D01*
X599626Y-297897D01*
X599702Y-297850D01*
X599706D01*
X599709Y-297842D01*
X599735Y-297824D01*
X599768Y-297795D01*
X599808Y-297751D01*
X599855Y-297697D01*
X599899Y-297635D01*
X599939Y-297558D01*
X599975Y-297475D01*
Y-297471D01*
X599979Y-297464D01*
X599982Y-297453D01*
X599986Y-297435D01*
X599993Y-297413D01*
X600001Y-297387D01*
X600011Y-297325D01*
X600026Y-297253D01*
X600041Y-297173D01*
X600048Y-297085D01*
X600052Y-296991D01*
Y-296987D01*
Y-296976D01*
Y-296958D01*
Y-296936D01*
X600048Y-296911D01*
Y-296878D01*
X600044Y-296841D01*
X600041Y-296801D01*
X600030Y-296714D01*
X600011Y-296619D01*
X599990Y-296525D01*
X599961Y-296430D01*
Y-296426D01*
X599957Y-296419D01*
X599950Y-296408D01*
X599942Y-296390D01*
X599921Y-296346D01*
X599888Y-296295D01*
X599848Y-296237D01*
X599797Y-296175D01*
X599739Y-296121D01*
X599669Y-296070D01*
X599666D01*
X599658Y-296066D01*
X599648Y-296059D01*
X599633Y-296051D01*
X599615Y-296044D01*
X599593Y-296033D01*
X599542Y-296011D01*
X599476Y-295990D01*
X599404Y-295971D01*
X599324Y-295957D01*
X599240Y-295953D01*
X599214D01*
X599193Y-295957D01*
X599167D01*
X599142Y-295960D01*
X599076Y-295975D01*
X599000Y-295993D01*
X598923Y-296022D01*
X598843Y-296062D01*
X598803Y-296084D01*
X598767Y-296113D01*
X598763Y-296117D01*
X598759Y-296121D01*
X598748Y-296131D01*
X598734Y-296142D01*
X598719Y-296161D01*
X598701Y-296182D01*
X598679Y-296204D01*
X598661Y-296233D01*
X598639Y-296266D01*
X598614Y-296303D01*
X598592Y-296339D01*
X598570Y-296383D01*
X598552Y-296430D01*
X598534Y-296481D01*
X598516Y-296536D01*
X598501Y-296594D01*
X598166Y-296510D01*
Y-296506D01*
X598170Y-296492D01*
X598177Y-296470D01*
X598188Y-296441D01*
X598199Y-296408D01*
X598213Y-296368D01*
X598232Y-296324D01*
X598253Y-296277D01*
X598304Y-296175D01*
X598370Y-296073D01*
X598410Y-296022D01*
X598450Y-295971D01*
X598494Y-295928D01*
X598545Y-295884D01*
X598548Y-295880D01*
X598556Y-295873D01*
X598574Y-295866D01*
X598592Y-295851D01*
X598621Y-295833D01*
X598650Y-295815D01*
X598690Y-295797D01*
X598730Y-295778D01*
X598778Y-295757D01*
X598829Y-295738D01*
X598883Y-295720D01*
X598941Y-295702D01*
X599003Y-295687D01*
X599069Y-295680D01*
X599138Y-295673D01*
X599211Y-295669D01*
X599251D01*
X599280Y-295673D01*
D02*
G37*
G36*
X595159D02*
X595192Y-295676D01*
X595229Y-295680D01*
X595269Y-295687D01*
X595312Y-295698D01*
X595411Y-295724D01*
X595462Y-295742D01*
X595509Y-295760D01*
X595560Y-295786D01*
X595611Y-295815D01*
X595658Y-295848D01*
X595702Y-295888D01*
X595705Y-295891D01*
X595713Y-295899D01*
X595724Y-295910D01*
X595738Y-295928D01*
X595753Y-295950D01*
X595775Y-295975D01*
X595793Y-296004D01*
X595815Y-296041D01*
X595836Y-296077D01*
X595855Y-296121D01*
X595891Y-296212D01*
X595906Y-296266D01*
X595917Y-296321D01*
X595924Y-296379D01*
X595927Y-296437D01*
Y-296441D01*
Y-296448D01*
Y-296463D01*
X595924Y-296477D01*
Y-296499D01*
X595920Y-296525D01*
X595913Y-296583D01*
X595898Y-296648D01*
X595877Y-296714D01*
X595844Y-296783D01*
X595804Y-296849D01*
Y-296852D01*
X595796Y-296856D01*
X595782Y-296874D01*
X595753Y-296903D01*
X595713Y-296940D01*
X595662Y-296976D01*
X595600Y-297016D01*
X595531Y-297049D01*
X595447Y-297074D01*
X595451D01*
X595454Y-297078D01*
X595465Y-297082D01*
X595480Y-297089D01*
X595512Y-297103D01*
X595556Y-297125D01*
X595604Y-297154D01*
X595651Y-297191D01*
X595694Y-297231D01*
X595735Y-297274D01*
X595738Y-297282D01*
X595749Y-297296D01*
X595764Y-297325D01*
X595778Y-297362D01*
X595796Y-297409D01*
X595811Y-297464D01*
X595822Y-297526D01*
X595826Y-297591D01*
Y-297595D01*
Y-297602D01*
Y-297617D01*
X595822Y-297639D01*
X595818Y-297660D01*
X595815Y-297689D01*
X595800Y-297751D01*
X595778Y-297824D01*
X595742Y-297901D01*
X595720Y-297941D01*
X595694Y-297981D01*
X595662Y-298017D01*
X595629Y-298053D01*
X595625Y-298057D01*
X595618Y-298061D01*
X595607Y-298072D01*
X595593Y-298083D01*
X595574Y-298097D01*
X595549Y-298112D01*
X595520Y-298130D01*
X595491Y-298148D01*
X595454Y-298166D01*
X595414Y-298184D01*
X595371Y-298199D01*
X595323Y-298214D01*
X595221Y-298235D01*
X595163Y-298239D01*
X595105Y-298243D01*
X595072D01*
X595050Y-298239D01*
X595021Y-298235D01*
X594988Y-298232D01*
X594952Y-298228D01*
X594915Y-298217D01*
X594828Y-298195D01*
X594741Y-298163D01*
X594697Y-298141D01*
X594654Y-298115D01*
X594613Y-298083D01*
X594573Y-298050D01*
X594570Y-298046D01*
X594566Y-298042D01*
X594555Y-298032D01*
X594541Y-298017D01*
X594526Y-297995D01*
X594508Y-297973D01*
X594472Y-297919D01*
X594435Y-297850D01*
X594402Y-297769D01*
X594377Y-297678D01*
X594373Y-297631D01*
X594370Y-297580D01*
Y-297577D01*
Y-297573D01*
Y-297551D01*
X594373Y-297518D01*
X594381Y-297478D01*
X594391Y-297427D01*
X594410Y-297376D01*
X594431Y-297325D01*
X594464Y-297274D01*
X594468Y-297267D01*
X594482Y-297253D01*
X594504Y-297231D01*
X594533Y-297202D01*
X594573Y-297169D01*
X594621Y-297136D01*
X594675Y-297103D01*
X594741Y-297074D01*
X594737D01*
X594730Y-297071D01*
X594719Y-297067D01*
X594704Y-297060D01*
X594661Y-297042D01*
X594610Y-297016D01*
X594555Y-296980D01*
X594497Y-296940D01*
X594442Y-296889D01*
X594391Y-296830D01*
Y-296827D01*
X594388Y-296823D01*
X594373Y-296801D01*
X594351Y-296765D01*
X594330Y-296718D01*
X594308Y-296659D01*
X594286Y-296590D01*
X594271Y-296514D01*
X594268Y-296430D01*
Y-296426D01*
Y-296415D01*
Y-296397D01*
X594271Y-296375D01*
X594275Y-296350D01*
X594278Y-296317D01*
X594286Y-296281D01*
X594297Y-296241D01*
X594322Y-296157D01*
X594340Y-296110D01*
X594366Y-296066D01*
X594391Y-296019D01*
X594420Y-295975D01*
X594457Y-295931D01*
X594497Y-295888D01*
X594501Y-295884D01*
X594508Y-295877D01*
X594519Y-295866D01*
X594537Y-295855D01*
X594562Y-295837D01*
X594588Y-295818D01*
X594621Y-295800D01*
X594657Y-295778D01*
X594697Y-295757D01*
X594744Y-295738D01*
X594795Y-295720D01*
X594846Y-295702D01*
X594905Y-295691D01*
X594967Y-295680D01*
X595028Y-295673D01*
X595097Y-295669D01*
X595134D01*
X595159Y-295673D01*
D02*
G37*
G36*
X558860Y-292523D02*
X558893D01*
X558933Y-292527D01*
X558977Y-292534D01*
X559028Y-292542D01*
X559133Y-292560D01*
X559242Y-292589D01*
X559352Y-292629D01*
X559403Y-292654D01*
X559454Y-292683D01*
X559457Y-292687D01*
X559465Y-292691D01*
X559479Y-292702D01*
X559494Y-292716D01*
X559515Y-292731D01*
X559541Y-292753D01*
X559570Y-292778D01*
X559599Y-292807D01*
X559628Y-292840D01*
X559661Y-292873D01*
X559727Y-292956D01*
X559789Y-293055D01*
X559843Y-293164D01*
Y-293168D01*
X559850Y-293179D01*
X559854Y-293197D01*
X559865Y-293218D01*
X559872Y-293248D01*
X559883Y-293284D01*
X559898Y-293324D01*
X559909Y-293368D01*
X559920Y-293415D01*
X559934Y-293470D01*
X559952Y-293583D01*
X559967Y-293710D01*
X559974Y-293841D01*
Y-293845D01*
Y-293859D01*
Y-293881D01*
X559971Y-293906D01*
Y-293943D01*
X559967Y-293979D01*
X559963Y-294027D01*
X559956Y-294074D01*
X559938Y-294180D01*
X559912Y-294296D01*
X559876Y-294412D01*
X559825Y-294525D01*
X559821Y-294529D01*
X559818Y-294540D01*
X559810Y-294554D01*
X559796Y-294573D01*
X559781Y-294598D01*
X559763Y-294627D01*
X559716Y-294693D01*
X559654Y-294765D01*
X559581Y-294838D01*
X559497Y-294911D01*
X559399Y-294973D01*
X559395Y-294977D01*
X559384Y-294980D01*
X559370Y-294988D01*
X559352Y-294999D01*
X559323Y-295009D01*
X559294Y-295020D01*
X559257Y-295035D01*
X559217Y-295049D01*
X559173Y-295064D01*
X559126Y-295079D01*
X559024Y-295100D01*
X558908Y-295119D01*
X558787Y-295126D01*
X558751D01*
X558726Y-295122D01*
X558693Y-295119D01*
X558653Y-295115D01*
X558613Y-295111D01*
X558566Y-295100D01*
X558467Y-295079D01*
X558358Y-295046D01*
X558303Y-295024D01*
X558252Y-294999D01*
X558202Y-294966D01*
X558150Y-294933D01*
X558147Y-294929D01*
X558140Y-294926D01*
X558125Y-294915D01*
X558107Y-294897D01*
X558089Y-294878D01*
X558063Y-294853D01*
X558038Y-294824D01*
X558008Y-294795D01*
X557979Y-294758D01*
X557950Y-294715D01*
X557917Y-294671D01*
X557888Y-294624D01*
X557863Y-294569D01*
X557834Y-294514D01*
X557812Y-294456D01*
X557790Y-294391D01*
X558118Y-294314D01*
Y-294318D01*
X558121Y-294325D01*
X558129Y-294340D01*
X558136Y-294358D01*
X558143Y-294380D01*
X558154Y-294409D01*
X558183Y-294467D01*
X558220Y-294533D01*
X558263Y-294598D01*
X558318Y-294660D01*
X558376Y-294715D01*
X558384Y-294722D01*
X558405Y-294736D01*
X558442Y-294755D01*
X558489Y-294780D01*
X558551Y-294802D01*
X558620Y-294824D01*
X558704Y-294838D01*
X558795Y-294842D01*
X558824D01*
X558842Y-294838D01*
X558868D01*
X558897Y-294835D01*
X558966Y-294824D01*
X559042Y-294809D01*
X559122Y-294784D01*
X559206Y-294747D01*
X559282Y-294700D01*
X559286D01*
X559290Y-294693D01*
X559315Y-294674D01*
X559348Y-294645D01*
X559388Y-294602D01*
X559435Y-294547D01*
X559479Y-294485D01*
X559519Y-294409D01*
X559555Y-294325D01*
Y-294321D01*
X559559Y-294314D01*
X559563Y-294303D01*
X559566Y-294285D01*
X559574Y-294263D01*
X559581Y-294238D01*
X559592Y-294176D01*
X559607Y-294103D01*
X559621Y-294023D01*
X559628Y-293936D01*
X559632Y-293841D01*
Y-293837D01*
Y-293826D01*
Y-293808D01*
Y-293786D01*
X559628Y-293761D01*
Y-293728D01*
X559625Y-293692D01*
X559621Y-293652D01*
X559610Y-293564D01*
X559592Y-293470D01*
X559570Y-293375D01*
X559541Y-293280D01*
Y-293277D01*
X559537Y-293269D01*
X559530Y-293259D01*
X559523Y-293240D01*
X559501Y-293197D01*
X559468Y-293146D01*
X559428Y-293088D01*
X559377Y-293026D01*
X559319Y-292971D01*
X559250Y-292920D01*
X559246D01*
X559239Y-292916D01*
X559228Y-292909D01*
X559213Y-292902D01*
X559195Y-292895D01*
X559173Y-292884D01*
X559122Y-292862D01*
X559057Y-292840D01*
X558984Y-292822D01*
X558904Y-292807D01*
X558820Y-292804D01*
X558795D01*
X558773Y-292807D01*
X558747D01*
X558722Y-292811D01*
X558657Y-292825D01*
X558580Y-292844D01*
X558504Y-292873D01*
X558424Y-292913D01*
X558384Y-292935D01*
X558347Y-292964D01*
X558343Y-292967D01*
X558340Y-292971D01*
X558329Y-292982D01*
X558314Y-292993D01*
X558300Y-293011D01*
X558282Y-293033D01*
X558260Y-293055D01*
X558242Y-293084D01*
X558220Y-293117D01*
X558194Y-293153D01*
X558172Y-293189D01*
X558150Y-293233D01*
X558132Y-293280D01*
X558114Y-293331D01*
X558096Y-293386D01*
X558081Y-293444D01*
X557747Y-293360D01*
Y-293357D01*
X557750Y-293342D01*
X557757Y-293320D01*
X557768Y-293291D01*
X557779Y-293259D01*
X557794Y-293218D01*
X557812Y-293175D01*
X557834Y-293127D01*
X557885Y-293026D01*
X557950Y-292924D01*
X557990Y-292873D01*
X558030Y-292822D01*
X558074Y-292778D01*
X558125Y-292734D01*
X558129Y-292731D01*
X558136Y-292723D01*
X558154Y-292716D01*
X558172Y-292702D01*
X558202Y-292683D01*
X558231Y-292665D01*
X558271Y-292647D01*
X558311Y-292629D01*
X558358Y-292607D01*
X558409Y-292589D01*
X558463Y-292571D01*
X558522Y-292552D01*
X558584Y-292538D01*
X558649Y-292531D01*
X558718Y-292523D01*
X558791Y-292520D01*
X558831D01*
X558860Y-292523D01*
D02*
G37*
G36*
X557088Y-292567D02*
Y-292578D01*
Y-292592D01*
X557084Y-292614D01*
Y-292643D01*
X557080Y-292680D01*
X557077Y-292720D01*
X557073Y-292763D01*
X557066Y-292814D01*
X557058Y-292865D01*
X557048Y-292927D01*
X557037Y-292989D01*
X557026Y-293055D01*
X557011Y-293127D01*
X556975Y-293277D01*
Y-293280D01*
X556971Y-293295D01*
X556964Y-293317D01*
X556953Y-293350D01*
X556942Y-293386D01*
X556927Y-293430D01*
X556913Y-293481D01*
X556891Y-293535D01*
X556869Y-293597D01*
X556847Y-293659D01*
X556793Y-293797D01*
X556727Y-293943D01*
X556655Y-294089D01*
X556651Y-294092D01*
X556643Y-294107D01*
X556633Y-294125D01*
X556618Y-294154D01*
X556600Y-294187D01*
X556574Y-294227D01*
X556549Y-294270D01*
X556520Y-294318D01*
X556451Y-294423D01*
X556378Y-294533D01*
X556294Y-294645D01*
X556207Y-294751D01*
X557441D01*
Y-295049D01*
X555810D01*
Y-294806D01*
X555814Y-294802D01*
X555821Y-294795D01*
X555835Y-294780D01*
X555850Y-294758D01*
X555872Y-294733D01*
X555901Y-294704D01*
X555930Y-294667D01*
X555963Y-294624D01*
X555996Y-294580D01*
X556036Y-294529D01*
X556076Y-294471D01*
X556116Y-294412D01*
X556159Y-294347D01*
X556203Y-294278D01*
X556247Y-294201D01*
X556290Y-294125D01*
X556294Y-294121D01*
X556301Y-294107D01*
X556312Y-294085D01*
X556330Y-294052D01*
X556349Y-294012D01*
X556370Y-293968D01*
X556396Y-293917D01*
X556422Y-293859D01*
X556451Y-293794D01*
X556483Y-293728D01*
X556512Y-293655D01*
X556542Y-293579D01*
X556600Y-293422D01*
X556655Y-293255D01*
Y-293251D01*
X556658Y-293240D01*
X556662Y-293222D01*
X556669Y-293200D01*
X556676Y-293171D01*
X556684Y-293135D01*
X556695Y-293095D01*
X556702Y-293051D01*
X556713Y-293000D01*
X556724Y-292946D01*
X556742Y-292829D01*
X556760Y-292702D01*
X556771Y-292563D01*
X557088D01*
Y-292567D01*
D02*
G37*
G36*
X554743Y-292523D02*
X554773Y-292527D01*
X554809Y-292534D01*
X554849Y-292542D01*
X554893Y-292552D01*
X554936Y-292567D01*
X554984Y-292582D01*
X555031Y-292603D01*
X555078Y-292629D01*
X555126Y-292658D01*
X555173Y-292694D01*
X555217Y-292734D01*
X555257Y-292778D01*
X555260Y-292782D01*
X555268Y-292793D01*
X555278Y-292811D01*
X555297Y-292840D01*
X555315Y-292873D01*
X555333Y-292916D01*
X555359Y-292967D01*
X555380Y-293026D01*
X555402Y-293091D01*
X555424Y-293168D01*
X555446Y-293251D01*
X555464Y-293346D01*
X555482Y-293448D01*
X555493Y-293557D01*
X555501Y-293677D01*
X555504Y-293805D01*
Y-293808D01*
Y-293823D01*
Y-293848D01*
Y-293877D01*
X555501Y-293917D01*
Y-293961D01*
X555497Y-294008D01*
X555493Y-294063D01*
X555482Y-294176D01*
X555464Y-294296D01*
X555442Y-294416D01*
X555428Y-294471D01*
X555413Y-294525D01*
Y-294529D01*
X555410Y-294536D01*
X555402Y-294551D01*
X555395Y-294569D01*
X555388Y-294594D01*
X555373Y-294620D01*
X555344Y-294682D01*
X555308Y-294747D01*
X555260Y-294816D01*
X555206Y-294886D01*
X555140Y-294944D01*
X555137D01*
X555133Y-294951D01*
X555122Y-294958D01*
X555107Y-294966D01*
X555089Y-294980D01*
X555067Y-294991D01*
X555013Y-295020D01*
X554947Y-295046D01*
X554871Y-295071D01*
X554780Y-295086D01*
X554682Y-295093D01*
X554649D01*
X554609Y-295090D01*
X554562Y-295082D01*
X554507Y-295071D01*
X554449Y-295057D01*
X554387Y-295039D01*
X554328Y-295009D01*
X554325D01*
X554321Y-295006D01*
X554303Y-294995D01*
X554274Y-294977D01*
X554238Y-294951D01*
X554198Y-294915D01*
X554154Y-294875D01*
X554114Y-294827D01*
X554074Y-294773D01*
X554070Y-294765D01*
X554056Y-294747D01*
X554041Y-294715D01*
X554015Y-294667D01*
X553994Y-294613D01*
X553965Y-294551D01*
X553939Y-294478D01*
X553917Y-294398D01*
Y-294394D01*
X553913Y-294387D01*
X553910Y-294376D01*
X553906Y-294358D01*
X553903Y-294336D01*
X553899Y-294310D01*
X553892Y-294278D01*
X553888Y-294241D01*
X553881Y-294201D01*
X553877Y-294158D01*
X553873Y-294107D01*
X553866Y-294056D01*
X553863Y-293998D01*
Y-293939D01*
X553859Y-293874D01*
Y-293805D01*
Y-293801D01*
Y-293786D01*
Y-293761D01*
Y-293732D01*
X553863Y-293692D01*
Y-293648D01*
X553866Y-293601D01*
X553870Y-293550D01*
X553881Y-293433D01*
X553899Y-293313D01*
X553921Y-293197D01*
X553935Y-293142D01*
X553954Y-293088D01*
Y-293084D01*
X553957Y-293077D01*
X553965Y-293062D01*
X553972Y-293044D01*
X553979Y-293018D01*
X553994Y-292993D01*
X554023Y-292931D01*
X554059Y-292865D01*
X554107Y-292793D01*
X554161Y-292727D01*
X554227Y-292665D01*
X554230D01*
X554234Y-292658D01*
X554245Y-292651D01*
X554259Y-292643D01*
X554278Y-292633D01*
X554296Y-292618D01*
X554350Y-292592D01*
X554416Y-292567D01*
X554492Y-292542D01*
X554583Y-292527D01*
X554682Y-292520D01*
X554718D01*
X554743Y-292523D01*
D02*
G37*
G36*
X544824Y-291736D02*
X544849D01*
X544879Y-291740D01*
X544948Y-291754D01*
X545024Y-291772D01*
X545104Y-291801D01*
X545184Y-291841D01*
X545224Y-291867D01*
X545261Y-291896D01*
X545264Y-291900D01*
X545268Y-291903D01*
X545279Y-291914D01*
X545290Y-291925D01*
X545304Y-291943D01*
X545323Y-291965D01*
X545359Y-292016D01*
X545395Y-292082D01*
X545432Y-292162D01*
X545461Y-292253D01*
X545483Y-292358D01*
X545184Y-292384D01*
Y-292380D01*
X545181Y-292373D01*
Y-292366D01*
X545177Y-292351D01*
X545166Y-292311D01*
X545152Y-292267D01*
X545133Y-292216D01*
X545108Y-292165D01*
X545079Y-292118D01*
X545042Y-292078D01*
X545039Y-292074D01*
X545024Y-292063D01*
X544999Y-292049D01*
X544970Y-292034D01*
X544930Y-292016D01*
X544882Y-292002D01*
X544828Y-291991D01*
X544769Y-291987D01*
X544744D01*
X544718Y-291991D01*
X544686Y-291994D01*
X544646Y-292002D01*
X544606Y-292013D01*
X544562Y-292027D01*
X544522Y-292049D01*
X544518Y-292053D01*
X544504Y-292060D01*
X544482Y-292074D01*
X544460Y-292096D01*
X544431Y-292122D01*
X544402Y-292151D01*
X544373Y-292184D01*
X544344Y-292224D01*
X544340Y-292227D01*
X544333Y-292246D01*
X544318Y-292271D01*
X544303Y-292304D01*
X544285Y-292347D01*
X544267Y-292398D01*
X544249Y-292457D01*
X544231Y-292522D01*
Y-292526D01*
X544227Y-292529D01*
Y-292540D01*
X544223Y-292555D01*
X544216Y-292591D01*
X544205Y-292639D01*
X544198Y-292697D01*
X544191Y-292759D01*
X544187Y-292828D01*
X544183Y-292901D01*
Y-292904D01*
Y-292915D01*
Y-292933D01*
Y-292963D01*
X544187Y-292955D01*
X544202Y-292937D01*
X544223Y-292912D01*
X544249Y-292875D01*
X544285Y-292839D01*
X544329Y-292799D01*
X544380Y-292759D01*
X544438Y-292722D01*
X544445Y-292719D01*
X544467Y-292708D01*
X544500Y-292693D01*
X544540Y-292679D01*
X544595Y-292660D01*
X544653Y-292646D01*
X544718Y-292635D01*
X544788Y-292631D01*
X544817D01*
X544838Y-292635D01*
X544868Y-292639D01*
X544897Y-292642D01*
X544933Y-292650D01*
X544970Y-292660D01*
X545053Y-292686D01*
X545097Y-292704D01*
X545141Y-292726D01*
X545188Y-292752D01*
X545232Y-292784D01*
X545275Y-292817D01*
X545315Y-292857D01*
X545319Y-292861D01*
X545326Y-292868D01*
X545334Y-292879D01*
X545348Y-292897D01*
X545366Y-292922D01*
X545385Y-292948D01*
X545403Y-292981D01*
X545421Y-293017D01*
X545443Y-293057D01*
X545461Y-293101D01*
X545479Y-293152D01*
X545497Y-293203D01*
X545512Y-293261D01*
X545519Y-293323D01*
X545527Y-293385D01*
X545530Y-293454D01*
Y-293458D01*
Y-293472D01*
Y-293490D01*
X545527Y-293516D01*
X545523Y-293549D01*
X545519Y-293589D01*
X545512Y-293629D01*
X545501Y-293676D01*
X545475Y-293771D01*
X545457Y-293822D01*
X545435Y-293876D01*
X545410Y-293927D01*
X545377Y-293974D01*
X545344Y-294025D01*
X545304Y-294069D01*
X545301Y-294073D01*
X545294Y-294080D01*
X545283Y-294091D01*
X545264Y-294106D01*
X545243Y-294124D01*
X545214Y-294146D01*
X545184Y-294164D01*
X545148Y-294189D01*
X545112Y-294211D01*
X545068Y-294229D01*
X544970Y-294269D01*
X544919Y-294284D01*
X544860Y-294295D01*
X544802Y-294302D01*
X544740Y-294306D01*
X544715D01*
X544697Y-294302D01*
X544678D01*
X544653Y-294299D01*
X544591Y-294287D01*
X544522Y-294273D01*
X544445Y-294248D01*
X544369Y-294215D01*
X544292Y-294171D01*
X544289D01*
X544285Y-294164D01*
X544274Y-294157D01*
X544260Y-294146D01*
X544223Y-294116D01*
X544176Y-294076D01*
X544129Y-294022D01*
X544074Y-293956D01*
X544027Y-293880D01*
X543983Y-293793D01*
Y-293789D01*
X543980Y-293782D01*
X543972Y-293767D01*
X543965Y-293749D01*
X543958Y-293723D01*
X543947Y-293691D01*
X543939Y-293654D01*
X543928Y-293614D01*
X543918Y-293567D01*
X543907Y-293512D01*
X543899Y-293454D01*
X543892Y-293392D01*
X543885Y-293323D01*
X543878Y-293250D01*
X543874Y-293170D01*
Y-293086D01*
Y-293083D01*
Y-293064D01*
Y-293039D01*
Y-293006D01*
X543878Y-292966D01*
Y-292919D01*
X543881Y-292864D01*
X543889Y-292810D01*
X543899Y-292686D01*
X543918Y-292555D01*
X543943Y-292431D01*
X543961Y-292369D01*
X543980Y-292315D01*
Y-292311D01*
X543983Y-292304D01*
X543990Y-292289D01*
X543998Y-292267D01*
X544009Y-292246D01*
X544023Y-292216D01*
X544060Y-292155D01*
X544103Y-292085D01*
X544154Y-292013D01*
X544220Y-291943D01*
X544292Y-291881D01*
X544296D01*
X544303Y-291874D01*
X544314Y-291867D01*
X544329Y-291860D01*
X544351Y-291849D01*
X544373Y-291834D01*
X544402Y-291820D01*
X544431Y-291809D01*
X544500Y-291780D01*
X544584Y-291754D01*
X544675Y-291740D01*
X544777Y-291732D01*
X544806D01*
X544824Y-291736D01*
D02*
G37*
G36*
X546666D02*
X546695D01*
X546728Y-291740D01*
X546764Y-291747D01*
X546808Y-291758D01*
X546851Y-291769D01*
X546902Y-291783D01*
X546953Y-291801D01*
X547004Y-291823D01*
X547059Y-291852D01*
X547110Y-291885D01*
X547161Y-291921D01*
X547212Y-291965D01*
X547259Y-292016D01*
X547263Y-292020D01*
X547270Y-292031D01*
X547281Y-292045D01*
X547296Y-292071D01*
X547317Y-292104D01*
X547336Y-292140D01*
X547357Y-292187D01*
X547379Y-292238D01*
X547405Y-292300D01*
X547427Y-292369D01*
X547445Y-292446D01*
X547463Y-292529D01*
X547481Y-292624D01*
X547492Y-292726D01*
X547499Y-292835D01*
X547503Y-292952D01*
Y-292955D01*
Y-292959D01*
Y-292970D01*
Y-292984D01*
X547499Y-293021D01*
Y-293072D01*
X547496Y-293130D01*
X547488Y-293199D01*
X547481Y-293276D01*
X547470Y-293359D01*
X547456Y-293443D01*
X547437Y-293534D01*
X547416Y-293621D01*
X547390Y-293709D01*
X547357Y-293793D01*
X547321Y-293873D01*
X547281Y-293949D01*
X547234Y-294015D01*
X547230Y-294018D01*
X547223Y-294025D01*
X547208Y-294040D01*
X547190Y-294062D01*
X547168Y-294084D01*
X547139Y-294106D01*
X547103Y-294135D01*
X547066Y-294160D01*
X547022Y-294186D01*
X546975Y-294215D01*
X546921Y-294237D01*
X546866Y-294262D01*
X546804Y-294280D01*
X546739Y-294295D01*
X546669Y-294302D01*
X546597Y-294306D01*
X546567D01*
X546546Y-294302D01*
X546520D01*
X546491Y-294299D01*
X546422Y-294284D01*
X546346Y-294266D01*
X546265Y-294237D01*
X546185Y-294193D01*
X546145Y-294167D01*
X546109Y-294138D01*
X546105Y-294135D01*
X546102Y-294131D01*
X546091Y-294120D01*
X546080Y-294109D01*
X546062Y-294091D01*
X546047Y-294069D01*
X546007Y-294018D01*
X545967Y-293953D01*
X545930Y-293873D01*
X545898Y-293782D01*
X545876Y-293680D01*
X546185Y-293654D01*
Y-293658D01*
X546189Y-293661D01*
X546193Y-293683D01*
X546204Y-293716D01*
X546218Y-293756D01*
X546233Y-293800D01*
X546254Y-293843D01*
X546280Y-293883D01*
X546306Y-293916D01*
X546313Y-293923D01*
X546327Y-293938D01*
X546353Y-293960D01*
X546389Y-293985D01*
X546437Y-294007D01*
X546487Y-294029D01*
X546549Y-294044D01*
X546615Y-294051D01*
X546640D01*
X546669Y-294047D01*
X546702Y-294040D01*
X546746Y-294029D01*
X546790Y-294015D01*
X546833Y-293996D01*
X546877Y-293967D01*
X546884Y-293964D01*
X546902Y-293949D01*
X546928Y-293923D01*
X546961Y-293887D01*
X546997Y-293843D01*
X547037Y-293793D01*
X547074Y-293727D01*
X547110Y-293654D01*
Y-293651D01*
X547114Y-293643D01*
X547117Y-293632D01*
X547124Y-293618D01*
X547128Y-293596D01*
X547135Y-293570D01*
X547143Y-293541D01*
X547150Y-293505D01*
X547161Y-293465D01*
X547168Y-293421D01*
X547175Y-293374D01*
X547179Y-293323D01*
X547186Y-293265D01*
X547190Y-293206D01*
X547194Y-293141D01*
Y-293075D01*
X547190Y-293079D01*
X547175Y-293101D01*
X547150Y-293130D01*
X547117Y-293166D01*
X547081Y-293210D01*
X547033Y-293250D01*
X546982Y-293290D01*
X546924Y-293327D01*
X546921D01*
X546917Y-293330D01*
X546895Y-293341D01*
X546862Y-293352D01*
X546819Y-293370D01*
X546768Y-293385D01*
X546709Y-293396D01*
X546648Y-293407D01*
X546582Y-293410D01*
X546553D01*
X546531Y-293407D01*
X546502Y-293403D01*
X546473Y-293399D01*
X546437Y-293392D01*
X546400Y-293381D01*
X546316Y-293356D01*
X546273Y-293337D01*
X546229Y-293312D01*
X546185Y-293286D01*
X546138Y-293257D01*
X546094Y-293221D01*
X546054Y-293181D01*
X546051Y-293177D01*
X546043Y-293170D01*
X546032Y-293159D01*
X546022Y-293141D01*
X546003Y-293115D01*
X545985Y-293090D01*
X545967Y-293057D01*
X545945Y-293021D01*
X545923Y-292981D01*
X545905Y-292937D01*
X545887Y-292886D01*
X545869Y-292835D01*
X545858Y-292781D01*
X545847Y-292719D01*
X545840Y-292657D01*
X545836Y-292591D01*
Y-292588D01*
Y-292580D01*
Y-292569D01*
Y-292551D01*
X545840Y-292529D01*
Y-292508D01*
X545851Y-292449D01*
X545861Y-292380D01*
X545880Y-292307D01*
X545905Y-292227D01*
X545941Y-292151D01*
Y-292147D01*
X545945Y-292144D01*
X545952Y-292133D01*
X545960Y-292118D01*
X545982Y-292082D01*
X546014Y-292034D01*
X546054Y-291983D01*
X546102Y-291933D01*
X546160Y-291881D01*
X546222Y-291838D01*
X546225D01*
X546229Y-291834D01*
X546240Y-291827D01*
X546254Y-291823D01*
X546291Y-291805D01*
X546338Y-291787D01*
X546400Y-291765D01*
X546469Y-291751D01*
X546546Y-291736D01*
X546629Y-291732D01*
X546648D01*
X546666Y-291736D01*
D02*
G37*
G36*
X548886D02*
X548919D01*
X548959Y-291740D01*
X549003Y-291747D01*
X549054Y-291754D01*
X549159Y-291772D01*
X549268Y-291801D01*
X549378Y-291841D01*
X549429Y-291867D01*
X549479Y-291896D01*
X549483Y-291900D01*
X549490Y-291903D01*
X549505Y-291914D01*
X549520Y-291929D01*
X549541Y-291943D01*
X549567Y-291965D01*
X549596Y-291991D01*
X549625Y-292020D01*
X549654Y-292053D01*
X549687Y-292085D01*
X549753Y-292169D01*
X549814Y-292267D01*
X549869Y-292376D01*
Y-292380D01*
X549876Y-292391D01*
X549880Y-292409D01*
X549891Y-292431D01*
X549898Y-292460D01*
X549909Y-292497D01*
X549924Y-292537D01*
X549934Y-292580D01*
X549945Y-292628D01*
X549960Y-292682D01*
X549978Y-292795D01*
X549993Y-292922D01*
X550000Y-293054D01*
Y-293057D01*
Y-293072D01*
Y-293094D01*
X549996Y-293119D01*
Y-293156D01*
X549993Y-293192D01*
X549989Y-293239D01*
X549982Y-293286D01*
X549964Y-293392D01*
X549938Y-293509D01*
X549902Y-293625D01*
X549851Y-293738D01*
X549847Y-293741D01*
X549844Y-293752D01*
X549836Y-293767D01*
X549822Y-293785D01*
X549807Y-293811D01*
X549789Y-293840D01*
X549742Y-293905D01*
X549680Y-293978D01*
X549607Y-294051D01*
X549523Y-294124D01*
X549425Y-294186D01*
X549421Y-294189D01*
X549410Y-294193D01*
X549396Y-294200D01*
X549378Y-294211D01*
X549348Y-294222D01*
X549319Y-294233D01*
X549283Y-294248D01*
X549243Y-294262D01*
X549199Y-294277D01*
X549152Y-294291D01*
X549050Y-294313D01*
X548934Y-294331D01*
X548813Y-294338D01*
X548777D01*
X548751Y-294335D01*
X548719Y-294331D01*
X548679Y-294328D01*
X548639Y-294324D01*
X548591Y-294313D01*
X548493Y-294291D01*
X548384Y-294258D01*
X548329Y-294237D01*
X548278Y-294211D01*
X548227Y-294178D01*
X548176Y-294146D01*
X548173Y-294142D01*
X548166Y-294138D01*
X548151Y-294127D01*
X548133Y-294109D01*
X548114Y-294091D01*
X548089Y-294065D01*
X548064Y-294036D01*
X548034Y-294007D01*
X548005Y-293971D01*
X547976Y-293927D01*
X547943Y-293883D01*
X547914Y-293836D01*
X547889Y-293782D01*
X547860Y-293727D01*
X547838Y-293669D01*
X547816Y-293603D01*
X548144Y-293527D01*
Y-293530D01*
X548147Y-293538D01*
X548155Y-293552D01*
X548162Y-293570D01*
X548169Y-293592D01*
X548180Y-293621D01*
X548209Y-293680D01*
X548246Y-293745D01*
X548289Y-293811D01*
X548344Y-293873D01*
X548402Y-293927D01*
X548409Y-293934D01*
X548431Y-293949D01*
X548468Y-293967D01*
X548515Y-293993D01*
X548577Y-294015D01*
X548646Y-294036D01*
X548730Y-294051D01*
X548821Y-294055D01*
X548850D01*
X548868Y-294051D01*
X548893D01*
X548923Y-294047D01*
X548992Y-294036D01*
X549068Y-294022D01*
X549148Y-293996D01*
X549232Y-293960D01*
X549308Y-293913D01*
X549312D01*
X549316Y-293905D01*
X549341Y-293887D01*
X549374Y-293858D01*
X549414Y-293814D01*
X549461Y-293760D01*
X549505Y-293698D01*
X549545Y-293621D01*
X549581Y-293538D01*
Y-293534D01*
X549585Y-293527D01*
X549589Y-293516D01*
X549592Y-293498D01*
X549600Y-293476D01*
X549607Y-293450D01*
X549618Y-293389D01*
X549632Y-293316D01*
X549647Y-293236D01*
X549654Y-293148D01*
X549658Y-293054D01*
Y-293050D01*
Y-293039D01*
Y-293021D01*
Y-292999D01*
X549654Y-292973D01*
Y-292941D01*
X549651Y-292904D01*
X549647Y-292864D01*
X549636Y-292777D01*
X549618Y-292682D01*
X549596Y-292588D01*
X549567Y-292493D01*
Y-292489D01*
X549563Y-292482D01*
X549556Y-292471D01*
X549549Y-292453D01*
X549527Y-292409D01*
X549494Y-292358D01*
X549454Y-292300D01*
X549403Y-292238D01*
X549345Y-292184D01*
X549276Y-292133D01*
X549272D01*
X549265Y-292129D01*
X549254Y-292122D01*
X549239Y-292114D01*
X549221Y-292107D01*
X549199Y-292096D01*
X549148Y-292074D01*
X549083Y-292053D01*
X549010Y-292034D01*
X548930Y-292020D01*
X548846Y-292016D01*
X548821D01*
X548799Y-292020D01*
X548773D01*
X548748Y-292023D01*
X548682Y-292038D01*
X548606Y-292056D01*
X548529Y-292085D01*
X548449Y-292125D01*
X548409Y-292147D01*
X548373Y-292176D01*
X548369Y-292180D01*
X548366Y-292184D01*
X548355Y-292195D01*
X548340Y-292206D01*
X548326Y-292224D01*
X548307Y-292246D01*
X548286Y-292267D01*
X548267Y-292297D01*
X548246Y-292329D01*
X548220Y-292366D01*
X548198Y-292402D01*
X548176Y-292446D01*
X548158Y-292493D01*
X548140Y-292544D01*
X548122Y-292599D01*
X548107Y-292657D01*
X547772Y-292573D01*
Y-292569D01*
X547776Y-292555D01*
X547783Y-292533D01*
X547794Y-292504D01*
X547805Y-292471D01*
X547820Y-292431D01*
X547838Y-292387D01*
X547860Y-292340D01*
X547911Y-292238D01*
X547976Y-292136D01*
X548016Y-292085D01*
X548056Y-292034D01*
X548100Y-291991D01*
X548151Y-291947D01*
X548155Y-291943D01*
X548162Y-291936D01*
X548180Y-291929D01*
X548198Y-291914D01*
X548227Y-291896D01*
X548256Y-291878D01*
X548296Y-291860D01*
X548337Y-291841D01*
X548384Y-291820D01*
X548435Y-291801D01*
X548490Y-291783D01*
X548548Y-291765D01*
X548610Y-291751D01*
X548675Y-291743D01*
X548744Y-291736D01*
X548817Y-291732D01*
X548857D01*
X548886Y-291736D01*
D02*
G37*
G36*
X592378Y-291342D02*
X592414D01*
X592451Y-291346D01*
X592498Y-291350D01*
X592545Y-291357D01*
X592651Y-291375D01*
X592767Y-291401D01*
X592884Y-291437D01*
X592997Y-291488D01*
X593001Y-291492D01*
X593011Y-291495D01*
X593026Y-291502D01*
X593044Y-291517D01*
X593070Y-291531D01*
X593099Y-291550D01*
X593164Y-291597D01*
X593237Y-291659D01*
X593310Y-291732D01*
X593383Y-291815D01*
X593444Y-291914D01*
X593448Y-291917D01*
X593452Y-291928D01*
X593459Y-291943D01*
X593470Y-291961D01*
X593481Y-291990D01*
X593492Y-292019D01*
X593506Y-292056D01*
X593521Y-292096D01*
X593536Y-292139D01*
X593550Y-292187D01*
X593572Y-292289D01*
X593590Y-292405D01*
X593597Y-292525D01*
Y-292562D01*
X593594Y-292587D01*
X593590Y-292620D01*
X593586Y-292660D01*
X593583Y-292700D01*
X593572Y-292747D01*
X593550Y-292846D01*
X593517Y-292955D01*
X593496Y-293009D01*
X593470Y-293060D01*
X593437Y-293111D01*
X593404Y-293162D01*
X593401Y-293166D01*
X593397Y-293173D01*
X593386Y-293188D01*
X593368Y-293206D01*
X593350Y-293224D01*
X593324Y-293250D01*
X593295Y-293275D01*
X593266Y-293304D01*
X593230Y-293333D01*
X593186Y-293362D01*
X593142Y-293395D01*
X593095Y-293424D01*
X593041Y-293450D01*
X592986Y-293479D01*
X592928Y-293501D01*
X592862Y-293523D01*
X592786Y-293195D01*
X592789D01*
X592797Y-293191D01*
X592811Y-293184D01*
X592829Y-293177D01*
X592851Y-293169D01*
X592880Y-293159D01*
X592939Y-293129D01*
X593004Y-293093D01*
X593070Y-293049D01*
X593131Y-292995D01*
X593186Y-292936D01*
X593193Y-292929D01*
X593208Y-292907D01*
X593226Y-292871D01*
X593252Y-292824D01*
X593273Y-292762D01*
X593295Y-292693D01*
X593310Y-292609D01*
X593314Y-292518D01*
Y-292489D01*
X593310Y-292471D01*
Y-292445D01*
X593306Y-292416D01*
X593295Y-292347D01*
X593281Y-292270D01*
X593255Y-292190D01*
X593219Y-292107D01*
X593172Y-292030D01*
Y-292026D01*
X593164Y-292023D01*
X593146Y-291997D01*
X593117Y-291965D01*
X593073Y-291925D01*
X593019Y-291877D01*
X592957Y-291834D01*
X592880Y-291794D01*
X592797Y-291757D01*
X592793D01*
X592786Y-291754D01*
X592775Y-291750D01*
X592757Y-291746D01*
X592735Y-291739D01*
X592709Y-291732D01*
X592647Y-291721D01*
X592575Y-291706D01*
X592494Y-291692D01*
X592407Y-291684D01*
X592312Y-291681D01*
X592309D01*
X592298D01*
X592280D01*
X592258D01*
X592232Y-291684D01*
X592200D01*
X592163Y-291688D01*
X592123Y-291692D01*
X592036Y-291703D01*
X591941Y-291721D01*
X591847Y-291743D01*
X591752Y-291772D01*
X591748D01*
X591741Y-291775D01*
X591730Y-291783D01*
X591712Y-291790D01*
X591668Y-291812D01*
X591617Y-291845D01*
X591559Y-291885D01*
X591497Y-291936D01*
X591442Y-291994D01*
X591392Y-292063D01*
Y-292067D01*
X591388Y-292074D01*
X591381Y-292085D01*
X591373Y-292099D01*
X591366Y-292118D01*
X591355Y-292139D01*
X591333Y-292190D01*
X591312Y-292256D01*
X591293Y-292329D01*
X591279Y-292409D01*
X591275Y-292493D01*
Y-292518D01*
X591279Y-292540D01*
Y-292565D01*
X591282Y-292591D01*
X591297Y-292656D01*
X591315Y-292733D01*
X591344Y-292809D01*
X591384Y-292889D01*
X591406Y-292929D01*
X591435Y-292966D01*
X591439Y-292969D01*
X591442Y-292973D01*
X591453Y-292984D01*
X591464Y-292998D01*
X591483Y-293013D01*
X591504Y-293031D01*
X591526Y-293053D01*
X591555Y-293071D01*
X591588Y-293093D01*
X591624Y-293119D01*
X591661Y-293140D01*
X591705Y-293162D01*
X591752Y-293180D01*
X591803Y-293199D01*
X591857Y-293217D01*
X591916Y-293231D01*
X591832Y-293566D01*
X591828D01*
X591814Y-293563D01*
X591792Y-293555D01*
X591763Y-293544D01*
X591730Y-293533D01*
X591690Y-293519D01*
X591646Y-293501D01*
X591599Y-293479D01*
X591497Y-293428D01*
X591395Y-293362D01*
X591344Y-293322D01*
X591293Y-293282D01*
X591250Y-293239D01*
X591206Y-293188D01*
X591202Y-293184D01*
X591195Y-293177D01*
X591188Y-293159D01*
X591173Y-293140D01*
X591155Y-293111D01*
X591137Y-293082D01*
X591119Y-293042D01*
X591100Y-293002D01*
X591079Y-292955D01*
X591060Y-292904D01*
X591042Y-292849D01*
X591024Y-292791D01*
X591009Y-292729D01*
X591002Y-292664D01*
X590995Y-292594D01*
X590991Y-292522D01*
Y-292482D01*
X590995Y-292452D01*
Y-292420D01*
X590998Y-292380D01*
X591006Y-292336D01*
X591013Y-292285D01*
X591031Y-292179D01*
X591060Y-292070D01*
X591100Y-291961D01*
X591126Y-291910D01*
X591155Y-291859D01*
X591159Y-291856D01*
X591162Y-291848D01*
X591173Y-291834D01*
X591188Y-291819D01*
X591202Y-291797D01*
X591224Y-291772D01*
X591250Y-291743D01*
X591279Y-291714D01*
X591312Y-291684D01*
X591344Y-291652D01*
X591428Y-291586D01*
X591526Y-291524D01*
X591636Y-291470D01*
X591639D01*
X591650Y-291462D01*
X591668Y-291459D01*
X591690Y-291448D01*
X591719Y-291441D01*
X591756Y-291430D01*
X591796Y-291415D01*
X591839Y-291404D01*
X591887Y-291393D01*
X591941Y-291379D01*
X592054Y-291360D01*
X592181Y-291346D01*
X592312Y-291339D01*
X592316D01*
X592331D01*
X592352D01*
X592378Y-291342D01*
D02*
G37*
G36*
X593521Y-295503D02*
X593277D01*
X593273Y-295499D01*
X593266Y-295492D01*
X593252Y-295477D01*
X593230Y-295463D01*
X593204Y-295441D01*
X593175Y-295412D01*
X593139Y-295383D01*
X593095Y-295350D01*
X593051Y-295317D01*
X593001Y-295277D01*
X592942Y-295237D01*
X592884Y-295197D01*
X592818Y-295153D01*
X592749Y-295110D01*
X592673Y-295066D01*
X592596Y-295022D01*
X592593Y-295019D01*
X592578Y-295011D01*
X592556Y-295000D01*
X592524Y-294982D01*
X592484Y-294964D01*
X592440Y-294942D01*
X592389Y-294917D01*
X592331Y-294891D01*
X592265Y-294862D01*
X592200Y-294829D01*
X592127Y-294800D01*
X592050Y-294771D01*
X591894Y-294713D01*
X591726Y-294658D01*
X591723D01*
X591712Y-294655D01*
X591694Y-294651D01*
X591672Y-294644D01*
X591643Y-294636D01*
X591606Y-294629D01*
X591566Y-294618D01*
X591523Y-294611D01*
X591472Y-294600D01*
X591417Y-294589D01*
X591301Y-294571D01*
X591173Y-294553D01*
X591035Y-294542D01*
Y-294225D01*
X591039D01*
X591049D01*
X591064D01*
X591086Y-294229D01*
X591115D01*
X591151Y-294232D01*
X591191Y-294236D01*
X591235Y-294240D01*
X591286Y-294247D01*
X591337Y-294254D01*
X591399Y-294265D01*
X591461Y-294276D01*
X591526Y-294287D01*
X591599Y-294302D01*
X591748Y-294338D01*
X591752D01*
X591767Y-294342D01*
X591788Y-294349D01*
X591821Y-294360D01*
X591857Y-294371D01*
X591901Y-294385D01*
X591952Y-294400D01*
X592007Y-294422D01*
X592069Y-294443D01*
X592131Y-294465D01*
X592269Y-294520D01*
X592414Y-294585D01*
X592560Y-294658D01*
X592564Y-294662D01*
X592578Y-294669D01*
X592596Y-294680D01*
X592626Y-294695D01*
X592658Y-294713D01*
X592698Y-294738D01*
X592742Y-294764D01*
X592789Y-294793D01*
X592895Y-294862D01*
X593004Y-294935D01*
X593117Y-295019D01*
X593223Y-295106D01*
Y-293872D01*
X593521D01*
Y-295503D01*
D02*
G37*
G36*
X591104Y-295768D02*
X591137Y-295772D01*
X591173Y-295779D01*
X591210Y-295787D01*
X591250Y-295801D01*
X591253D01*
X591257Y-295805D01*
X591279Y-295812D01*
X591312Y-295827D01*
X591355Y-295848D01*
X591406Y-295878D01*
X591464Y-295914D01*
X591523Y-295954D01*
X591584Y-296005D01*
X591588D01*
X591592Y-296012D01*
X591614Y-296030D01*
X591646Y-296063D01*
X591694Y-296111D01*
X591748Y-296165D01*
X591814Y-296234D01*
X591887Y-296318D01*
X591963Y-296409D01*
X591967Y-296413D01*
X591978Y-296427D01*
X591996Y-296449D01*
X592018Y-296475D01*
X592047Y-296507D01*
X592079Y-296547D01*
X592116Y-296587D01*
X592156Y-296635D01*
X592243Y-296726D01*
X592331Y-296817D01*
X592374Y-296861D01*
X592418Y-296901D01*
X592458Y-296937D01*
X592498Y-296966D01*
X592502D01*
X592505Y-296973D01*
X592516Y-296981D01*
X592531Y-296988D01*
X592571Y-297013D01*
X592618Y-297042D01*
X592676Y-297068D01*
X592738Y-297093D01*
X592807Y-297108D01*
X592873Y-297115D01*
X592877D01*
X592880D01*
X592902Y-297112D01*
X592939Y-297108D01*
X592979Y-297097D01*
X593030Y-297082D01*
X593081Y-297057D01*
X593131Y-297024D01*
X593182Y-296981D01*
X593190Y-296973D01*
X593204Y-296955D01*
X593223Y-296930D01*
X593248Y-296890D01*
X593270Y-296839D01*
X593292Y-296780D01*
X593306Y-296711D01*
X593310Y-296635D01*
Y-296613D01*
X593306Y-296598D01*
X593303Y-296555D01*
X593292Y-296504D01*
X593277Y-296449D01*
X593252Y-296387D01*
X593219Y-296329D01*
X593175Y-296274D01*
X593168Y-296267D01*
X593150Y-296253D01*
X593121Y-296231D01*
X593077Y-296209D01*
X593026Y-296183D01*
X592960Y-296162D01*
X592888Y-296147D01*
X592804Y-296140D01*
X592837Y-295823D01*
X592840D01*
X592851Y-295827D01*
X592869D01*
X592895Y-295830D01*
X592924Y-295838D01*
X592957Y-295845D01*
X592997Y-295856D01*
X593037Y-295867D01*
X593124Y-295896D01*
X593212Y-295940D01*
X593255Y-295965D01*
X593299Y-295998D01*
X593339Y-296030D01*
X593375Y-296067D01*
X593379Y-296071D01*
X593383Y-296078D01*
X593394Y-296089D01*
X593404Y-296107D01*
X593419Y-296129D01*
X593434Y-296154D01*
X593452Y-296183D01*
X593470Y-296220D01*
X593488Y-296260D01*
X593506Y-296304D01*
X593521Y-296351D01*
X593536Y-296402D01*
X593546Y-296456D01*
X593557Y-296515D01*
X593561Y-296576D01*
X593565Y-296642D01*
Y-296678D01*
X593561Y-296704D01*
X593557Y-296733D01*
X593554Y-296769D01*
X593546Y-296810D01*
X593539Y-296849D01*
X593514Y-296944D01*
X593477Y-297039D01*
X593456Y-297086D01*
X593430Y-297133D01*
X593397Y-297177D01*
X593361Y-297217D01*
X593357Y-297221D01*
X593354Y-297228D01*
X593339Y-297235D01*
X593324Y-297250D01*
X593306Y-297268D01*
X593281Y-297286D01*
X593255Y-297305D01*
X593223Y-297326D01*
X593153Y-297363D01*
X593066Y-297399D01*
X593022Y-297414D01*
X592971Y-297421D01*
X592920Y-297428D01*
X592866Y-297432D01*
X592859D01*
X592840D01*
X592811Y-297428D01*
X592771Y-297425D01*
X592728Y-297417D01*
X592676Y-297403D01*
X592622Y-297388D01*
X592567Y-297366D01*
X592560Y-297363D01*
X592542Y-297356D01*
X592513Y-297341D01*
X592473Y-297319D01*
X592429Y-297290D01*
X592374Y-297254D01*
X592320Y-297210D01*
X592258Y-297159D01*
X592251Y-297152D01*
X592229Y-297133D01*
X592211Y-297115D01*
X592192Y-297097D01*
X592170Y-297075D01*
X592141Y-297046D01*
X592112Y-297017D01*
X592079Y-296981D01*
X592043Y-296944D01*
X592003Y-296901D01*
X591963Y-296853D01*
X591916Y-296802D01*
X591868Y-296744D01*
X591818Y-296686D01*
X591814Y-296682D01*
X591807Y-296675D01*
X591796Y-296660D01*
X591781Y-296642D01*
X591759Y-296620D01*
X591737Y-296595D01*
X591690Y-296536D01*
X591636Y-296475D01*
X591581Y-296416D01*
X591534Y-296365D01*
X591515Y-296344D01*
X591497Y-296325D01*
X591494Y-296322D01*
X591483Y-296311D01*
X591468Y-296296D01*
X591446Y-296278D01*
X591421Y-296260D01*
X591395Y-296238D01*
X591333Y-296194D01*
Y-297436D01*
X591035D01*
Y-295765D01*
X591039D01*
X591053D01*
X591075D01*
X591104Y-295768D01*
D02*
G37*
G36*
X549222Y-259649D02*
X549258D01*
X549294Y-259653D01*
X549342Y-259657D01*
X549389Y-259664D01*
X549494Y-259682D01*
X549611Y-259707D01*
X549727Y-259744D01*
X549840Y-259795D01*
X549844Y-259799D01*
X549855Y-259802D01*
X549869Y-259809D01*
X549888Y-259824D01*
X549913Y-259839D01*
X549942Y-259857D01*
X550008Y-259904D01*
X550080Y-259966D01*
X550153Y-260039D01*
X550226Y-260122D01*
X550288Y-260221D01*
X550292Y-260224D01*
X550295Y-260235D01*
X550303Y-260250D01*
X550314Y-260268D01*
X550324Y-260297D01*
X550335Y-260326D01*
X550350Y-260363D01*
X550364Y-260403D01*
X550379Y-260446D01*
X550393Y-260494D01*
X550415Y-260596D01*
X550434Y-260712D01*
X550441Y-260832D01*
Y-260869D01*
X550437Y-260894D01*
X550434Y-260927D01*
X550430Y-260967D01*
X550426Y-261007D01*
X550415Y-261054D01*
X550393Y-261153D01*
X550361Y-261262D01*
X550339Y-261316D01*
X550314Y-261367D01*
X550281Y-261418D01*
X550248Y-261469D01*
X550244Y-261473D01*
X550241Y-261480D01*
X550230Y-261495D01*
X550211Y-261513D01*
X550193Y-261531D01*
X550168Y-261557D01*
X550139Y-261582D01*
X550110Y-261611D01*
X550073Y-261640D01*
X550030Y-261669D01*
X549986Y-261702D01*
X549938Y-261731D01*
X549884Y-261757D01*
X549829Y-261786D01*
X549771Y-261808D01*
X549706Y-261830D01*
X549629Y-261502D01*
X549633D01*
X549640Y-261498D01*
X549655Y-261491D01*
X549673Y-261484D01*
X549695Y-261476D01*
X549724Y-261466D01*
X549782Y-261437D01*
X549848Y-261400D01*
X549913Y-261356D01*
X549975Y-261302D01*
X550030Y-261244D01*
X550037Y-261236D01*
X550051Y-261214D01*
X550070Y-261178D01*
X550095Y-261131D01*
X550117Y-261069D01*
X550139Y-261000D01*
X550153Y-260916D01*
X550157Y-260825D01*
Y-260796D01*
X550153Y-260778D01*
Y-260752D01*
X550150Y-260723D01*
X550139Y-260654D01*
X550124Y-260578D01*
X550099Y-260497D01*
X550062Y-260414D01*
X550015Y-260337D01*
Y-260334D01*
X550008Y-260330D01*
X549990Y-260304D01*
X549960Y-260272D01*
X549917Y-260232D01*
X549862Y-260184D01*
X549800Y-260141D01*
X549724Y-260101D01*
X549640Y-260064D01*
X549636D01*
X549629Y-260061D01*
X549618Y-260057D01*
X549600Y-260053D01*
X549578Y-260046D01*
X549553Y-260039D01*
X549491Y-260028D01*
X549418Y-260013D01*
X549338Y-259999D01*
X549251Y-259991D01*
X549156Y-259988D01*
X549152D01*
X549141D01*
X549123D01*
X549101D01*
X549076Y-259991D01*
X549043D01*
X549007Y-259995D01*
X548967Y-259999D01*
X548879Y-260010D01*
X548785Y-260028D01*
X548690Y-260050D01*
X548595Y-260079D01*
X548592D01*
X548585Y-260082D01*
X548573Y-260090D01*
X548555Y-260097D01*
X548512Y-260119D01*
X548461Y-260152D01*
X548403Y-260192D01*
X548341Y-260243D01*
X548286Y-260301D01*
X548235Y-260370D01*
Y-260374D01*
X548231Y-260381D01*
X548224Y-260392D01*
X548217Y-260406D01*
X548209Y-260425D01*
X548199Y-260446D01*
X548177Y-260497D01*
X548155Y-260563D01*
X548137Y-260636D01*
X548122Y-260716D01*
X548118Y-260800D01*
Y-260825D01*
X548122Y-260847D01*
Y-260872D01*
X548126Y-260898D01*
X548140Y-260963D01*
X548159Y-261040D01*
X548188Y-261116D01*
X548228Y-261196D01*
X548250Y-261236D01*
X548279Y-261273D01*
X548282Y-261276D01*
X548286Y-261280D01*
X548297Y-261291D01*
X548308Y-261305D01*
X548326Y-261320D01*
X548348Y-261338D01*
X548370Y-261360D01*
X548399Y-261378D01*
X548432Y-261400D01*
X548468Y-261426D01*
X548504Y-261447D01*
X548548Y-261469D01*
X548595Y-261488D01*
X548646Y-261506D01*
X548701Y-261524D01*
X548759Y-261538D01*
X548675Y-261873D01*
X548672D01*
X548657Y-261870D01*
X548635Y-261862D01*
X548606Y-261852D01*
X548573Y-261841D01*
X548533Y-261826D01*
X548490Y-261808D01*
X548443Y-261786D01*
X548341Y-261735D01*
X548239Y-261669D01*
X548188Y-261629D01*
X548137Y-261589D01*
X548093Y-261546D01*
X548049Y-261495D01*
X548046Y-261491D01*
X548038Y-261484D01*
X548031Y-261466D01*
X548017Y-261447D01*
X547998Y-261418D01*
X547980Y-261389D01*
X547962Y-261349D01*
X547944Y-261309D01*
X547922Y-261262D01*
X547904Y-261211D01*
X547886Y-261156D01*
X547867Y-261098D01*
X547853Y-261036D01*
X547846Y-260971D01*
X547838Y-260901D01*
X547835Y-260829D01*
Y-260789D01*
X547838Y-260759D01*
Y-260727D01*
X547842Y-260687D01*
X547849Y-260643D01*
X547857Y-260592D01*
X547875Y-260487D01*
X547904Y-260377D01*
X547944Y-260268D01*
X547969Y-260217D01*
X547998Y-260166D01*
X548002Y-260162D01*
X548006Y-260155D01*
X548017Y-260141D01*
X548031Y-260126D01*
X548046Y-260104D01*
X548068Y-260079D01*
X548093Y-260050D01*
X548122Y-260021D01*
X548155Y-259991D01*
X548188Y-259959D01*
X548271Y-259893D01*
X548370Y-259831D01*
X548479Y-259777D01*
X548483D01*
X548493Y-259769D01*
X548512Y-259766D01*
X548533Y-259755D01*
X548563Y-259748D01*
X548599Y-259737D01*
X548639Y-259722D01*
X548683Y-259711D01*
X548730Y-259700D01*
X548785Y-259686D01*
X548898Y-259667D01*
X549025Y-259653D01*
X549156Y-259646D01*
X549160D01*
X549174D01*
X549196D01*
X549222Y-259649D01*
D02*
G37*
G36*
X550364Y-263810D02*
X550120D01*
X550117Y-263806D01*
X550110Y-263799D01*
X550095Y-263784D01*
X550073Y-263770D01*
X550048Y-263748D01*
X550019Y-263719D01*
X549982Y-263690D01*
X549938Y-263657D01*
X549895Y-263624D01*
X549844Y-263584D01*
X549786Y-263544D01*
X549727Y-263504D01*
X549662Y-263460D01*
X549593Y-263417D01*
X549516Y-263373D01*
X549440Y-263329D01*
X549436Y-263326D01*
X549422Y-263318D01*
X549400Y-263307D01*
X549367Y-263289D01*
X549327Y-263271D01*
X549283Y-263249D01*
X549232Y-263224D01*
X549174Y-263198D01*
X549109Y-263169D01*
X549043Y-263136D01*
X548970Y-263107D01*
X548894Y-263078D01*
X548737Y-263020D01*
X548570Y-262965D01*
X548566D01*
X548555Y-262962D01*
X548537Y-262958D01*
X548515Y-262951D01*
X548486Y-262944D01*
X548450Y-262936D01*
X548410Y-262925D01*
X548366Y-262918D01*
X548315Y-262907D01*
X548260Y-262896D01*
X548144Y-262878D01*
X548017Y-262860D01*
X547878Y-262849D01*
Y-262532D01*
X547882D01*
X547893D01*
X547907D01*
X547929Y-262536D01*
X547958D01*
X547995Y-262539D01*
X548035Y-262543D01*
X548078Y-262547D01*
X548129Y-262554D01*
X548180Y-262561D01*
X548242Y-262572D01*
X548304Y-262583D01*
X548370Y-262594D01*
X548443Y-262609D01*
X548592Y-262645D01*
X548595D01*
X548610Y-262649D01*
X548632Y-262656D01*
X548665Y-262667D01*
X548701Y-262678D01*
X548745Y-262692D01*
X548796Y-262707D01*
X548850Y-262729D01*
X548912Y-262751D01*
X548974Y-262772D01*
X549112Y-262827D01*
X549258Y-262893D01*
X549403Y-262965D01*
X549407Y-262969D01*
X549422Y-262976D01*
X549440Y-262987D01*
X549469Y-263002D01*
X549502Y-263020D01*
X549542Y-263045D01*
X549585Y-263071D01*
X549633Y-263100D01*
X549738Y-263169D01*
X549848Y-263242D01*
X549960Y-263326D01*
X550066Y-263413D01*
Y-262179D01*
X550364D01*
Y-263810D01*
D02*
G37*
G36*
X548585Y-264429D02*
X548581D01*
X548573Y-264432D01*
X548559Y-264436D01*
X548541Y-264440D01*
X548519Y-264443D01*
X548493Y-264450D01*
X548439Y-264469D01*
X548373Y-264494D01*
X548311Y-264527D01*
X548253Y-264563D01*
X548202Y-264607D01*
X548199Y-264614D01*
X548184Y-264629D01*
X548166Y-264658D01*
X548148Y-264694D01*
X548126Y-264738D01*
X548108Y-264793D01*
X548093Y-264855D01*
X548089Y-264920D01*
Y-264942D01*
X548093Y-264956D01*
X548097Y-264996D01*
X548108Y-265047D01*
X548126Y-265106D01*
X548151Y-265167D01*
X548188Y-265229D01*
X548239Y-265288D01*
X548246Y-265295D01*
X548268Y-265313D01*
X548301Y-265335D01*
X548344Y-265364D01*
X548399Y-265393D01*
X548461Y-265415D01*
X548533Y-265433D01*
X548614Y-265441D01*
X548617D01*
X548625D01*
X548635D01*
X548650Y-265437D01*
X548690Y-265433D01*
X548737Y-265422D01*
X548796Y-265408D01*
X548854Y-265382D01*
X548912Y-265346D01*
X548967Y-265299D01*
X548974Y-265291D01*
X548988Y-265273D01*
X549010Y-265244D01*
X549036Y-265204D01*
X549061Y-265153D01*
X549083Y-265091D01*
X549098Y-265022D01*
X549105Y-264946D01*
Y-264913D01*
X549101Y-264887D01*
X549098Y-264855D01*
X549090Y-264818D01*
X549083Y-264774D01*
X549072Y-264727D01*
X549345Y-264763D01*
Y-264782D01*
X549342Y-264796D01*
Y-264844D01*
X549349Y-264884D01*
X549356Y-264931D01*
X549367Y-264985D01*
X549385Y-265047D01*
X549411Y-265106D01*
X549443Y-265167D01*
Y-265171D01*
X549447Y-265175D01*
X549462Y-265193D01*
X549487Y-265218D01*
X549520Y-265248D01*
X549567Y-265277D01*
X549622Y-265302D01*
X549684Y-265320D01*
X549720Y-265328D01*
X549760D01*
X549764D01*
X549767D01*
X549789D01*
X549818Y-265320D01*
X549858Y-265313D01*
X549902Y-265299D01*
X549949Y-265280D01*
X549997Y-265251D01*
X550040Y-265211D01*
X550044Y-265208D01*
X550059Y-265189D01*
X550077Y-265164D01*
X550099Y-265131D01*
X550117Y-265087D01*
X550135Y-265037D01*
X550150Y-264978D01*
X550153Y-264913D01*
Y-264884D01*
X550146Y-264851D01*
X550139Y-264807D01*
X550124Y-264760D01*
X550106Y-264713D01*
X550077Y-264662D01*
X550040Y-264614D01*
X550037Y-264611D01*
X550019Y-264596D01*
X549993Y-264574D01*
X549957Y-264549D01*
X549909Y-264523D01*
X549851Y-264498D01*
X549782Y-264476D01*
X549702Y-264461D01*
X549756Y-264152D01*
X549760D01*
X549771Y-264156D01*
X549786Y-264159D01*
X549808Y-264163D01*
X549833Y-264170D01*
X549862Y-264181D01*
X549931Y-264203D01*
X550011Y-264239D01*
X550091Y-264283D01*
X550168Y-264338D01*
X550237Y-264407D01*
X550241Y-264410D01*
X550244Y-264418D01*
X550252Y-264429D01*
X550262Y-264443D01*
X550277Y-264461D01*
X550292Y-264487D01*
X550306Y-264512D01*
X550324Y-264545D01*
X550353Y-264618D01*
X550383Y-264702D01*
X550401Y-264800D01*
X550408Y-264851D01*
Y-264942D01*
X550404Y-264982D01*
X550397Y-265029D01*
X550386Y-265087D01*
X550368Y-265153D01*
X550346Y-265218D01*
X550317Y-265284D01*
Y-265288D01*
X550314Y-265291D01*
X550303Y-265313D01*
X550281Y-265346D01*
X550255Y-265382D01*
X550219Y-265426D01*
X550179Y-265470D01*
X550132Y-265513D01*
X550077Y-265550D01*
X550070Y-265553D01*
X550051Y-265564D01*
X550019Y-265579D01*
X549979Y-265597D01*
X549931Y-265615D01*
X549877Y-265630D01*
X549815Y-265641D01*
X549753Y-265644D01*
X549746D01*
X549724D01*
X549695Y-265641D01*
X549655Y-265633D01*
X549607Y-265622D01*
X549556Y-265604D01*
X549505Y-265582D01*
X549454Y-265553D01*
X549447Y-265550D01*
X549433Y-265539D01*
X549407Y-265517D01*
X549378Y-265488D01*
X549345Y-265451D01*
X549309Y-265408D01*
X549276Y-265357D01*
X549243Y-265295D01*
Y-265299D01*
X549240Y-265306D01*
X549236Y-265317D01*
X549232Y-265331D01*
X549218Y-265371D01*
X549196Y-265422D01*
X549167Y-265480D01*
X549130Y-265539D01*
X549083Y-265593D01*
X549028Y-265644D01*
X549021Y-265648D01*
X548999Y-265663D01*
X548963Y-265684D01*
X548916Y-265706D01*
X548857Y-265728D01*
X548788Y-265750D01*
X548708Y-265764D01*
X548621Y-265768D01*
X548617D01*
X548606D01*
X548588D01*
X548566Y-265764D01*
X548537Y-265761D01*
X548504Y-265754D01*
X548468Y-265746D01*
X548428Y-265739D01*
X548341Y-265710D01*
X548293Y-265688D01*
X548250Y-265666D01*
X548202Y-265637D01*
X548155Y-265604D01*
X548108Y-265568D01*
X548064Y-265524D01*
X548060Y-265521D01*
X548053Y-265513D01*
X548042Y-265499D01*
X548028Y-265480D01*
X548009Y-265459D01*
X547991Y-265430D01*
X547969Y-265397D01*
X547951Y-265357D01*
X547929Y-265317D01*
X547907Y-265269D01*
X547889Y-265222D01*
X547871Y-265167D01*
X547857Y-265109D01*
X547846Y-265047D01*
X547838Y-264985D01*
X547835Y-264916D01*
Y-264884D01*
X547838Y-264862D01*
X547842Y-264833D01*
X547846Y-264800D01*
X547853Y-264763D01*
X547860Y-264723D01*
X547882Y-264636D01*
X547918Y-264545D01*
X547940Y-264498D01*
X547966Y-264454D01*
X547998Y-264410D01*
X548031Y-264367D01*
X548035Y-264363D01*
X548042Y-264356D01*
X548053Y-264345D01*
X548068Y-264334D01*
X548086Y-264316D01*
X548111Y-264298D01*
X548137Y-264276D01*
X548170Y-264254D01*
X548206Y-264232D01*
X548242Y-264210D01*
X548330Y-264170D01*
X548432Y-264137D01*
X548486Y-264126D01*
X548544Y-264119D01*
X548585Y-264429D01*
D02*
G37*
G36*
X571327Y-291736D02*
X571360D01*
X571400Y-291740D01*
X571444Y-291747D01*
X571495Y-291754D01*
X571600Y-291772D01*
X571709Y-291801D01*
X571818Y-291841D01*
X571870Y-291867D01*
X571920Y-291896D01*
X571924Y-291900D01*
X571931Y-291903D01*
X571946Y-291914D01*
X571960Y-291929D01*
X571982Y-291943D01*
X572008Y-291965D01*
X572037Y-291991D01*
X572066Y-292020D01*
X572095Y-292053D01*
X572128Y-292085D01*
X572193Y-292169D01*
X572255Y-292267D01*
X572310Y-292376D01*
Y-292380D01*
X572317Y-292391D01*
X572321Y-292409D01*
X572332Y-292431D01*
X572339Y-292460D01*
X572350Y-292497D01*
X572365Y-292537D01*
X572375Y-292580D01*
X572386Y-292628D01*
X572401Y-292682D01*
X572419Y-292795D01*
X572434Y-292922D01*
X572441Y-293054D01*
Y-293057D01*
Y-293072D01*
Y-293094D01*
X572437Y-293119D01*
Y-293156D01*
X572434Y-293192D01*
X572430Y-293239D01*
X572423Y-293286D01*
X572405Y-293392D01*
X572379Y-293509D01*
X572343Y-293625D01*
X572292Y-293738D01*
X572288Y-293741D01*
X572285Y-293752D01*
X572277Y-293767D01*
X572263Y-293785D01*
X572248Y-293811D01*
X572230Y-293840D01*
X572183Y-293905D01*
X572121Y-293978D01*
X572048Y-294051D01*
X571964Y-294124D01*
X571866Y-294186D01*
X571862Y-294189D01*
X571851Y-294193D01*
X571837Y-294200D01*
X571818Y-294211D01*
X571789Y-294222D01*
X571760Y-294233D01*
X571724Y-294248D01*
X571684Y-294262D01*
X571640Y-294277D01*
X571593Y-294291D01*
X571491Y-294313D01*
X571375Y-294331D01*
X571254Y-294338D01*
X571218D01*
X571193Y-294335D01*
X571160Y-294331D01*
X571120Y-294328D01*
X571080Y-294324D01*
X571032Y-294313D01*
X570934Y-294291D01*
X570825Y-294258D01*
X570770Y-294237D01*
X570719Y-294211D01*
X570668Y-294178D01*
X570617Y-294146D01*
X570614Y-294142D01*
X570606Y-294138D01*
X570592Y-294127D01*
X570574Y-294109D01*
X570555Y-294091D01*
X570530Y-294065D01*
X570505Y-294036D01*
X570475Y-294007D01*
X570446Y-293971D01*
X570417Y-293927D01*
X570384Y-293883D01*
X570355Y-293836D01*
X570330Y-293782D01*
X570301Y-293727D01*
X570279Y-293669D01*
X570257Y-293603D01*
X570585Y-293527D01*
Y-293530D01*
X570588Y-293538D01*
X570596Y-293552D01*
X570603Y-293570D01*
X570610Y-293592D01*
X570621Y-293621D01*
X570650Y-293680D01*
X570686Y-293745D01*
X570730Y-293811D01*
X570785Y-293873D01*
X570843Y-293927D01*
X570850Y-293934D01*
X570872Y-293949D01*
X570909Y-293967D01*
X570956Y-293993D01*
X571018Y-294015D01*
X571087Y-294036D01*
X571171Y-294051D01*
X571262Y-294055D01*
X571291D01*
X571309Y-294051D01*
X571334D01*
X571364Y-294047D01*
X571433Y-294036D01*
X571509Y-294022D01*
X571589Y-293996D01*
X571673Y-293960D01*
X571749Y-293913D01*
X571753D01*
X571757Y-293905D01*
X571782Y-293887D01*
X571815Y-293858D01*
X571855Y-293814D01*
X571902Y-293760D01*
X571946Y-293698D01*
X571986Y-293621D01*
X572022Y-293538D01*
Y-293534D01*
X572026Y-293527D01*
X572030Y-293516D01*
X572033Y-293498D01*
X572041Y-293476D01*
X572048Y-293450D01*
X572059Y-293389D01*
X572073Y-293316D01*
X572088Y-293236D01*
X572095Y-293148D01*
X572099Y-293054D01*
Y-293050D01*
Y-293039D01*
Y-293021D01*
Y-292999D01*
X572095Y-292973D01*
Y-292941D01*
X572092Y-292904D01*
X572088Y-292864D01*
X572077Y-292777D01*
X572059Y-292682D01*
X572037Y-292588D01*
X572008Y-292493D01*
Y-292489D01*
X572004Y-292482D01*
X571997Y-292471D01*
X571990Y-292453D01*
X571968Y-292409D01*
X571935Y-292358D01*
X571895Y-292300D01*
X571844Y-292238D01*
X571786Y-292184D01*
X571717Y-292133D01*
X571713D01*
X571706Y-292129D01*
X571695Y-292122D01*
X571680Y-292114D01*
X571662Y-292107D01*
X571640Y-292096D01*
X571589Y-292074D01*
X571524Y-292053D01*
X571451Y-292034D01*
X571371Y-292020D01*
X571287Y-292016D01*
X571262D01*
X571240Y-292020D01*
X571214D01*
X571189Y-292023D01*
X571123Y-292038D01*
X571047Y-292056D01*
X570970Y-292085D01*
X570890Y-292125D01*
X570850Y-292147D01*
X570814Y-292176D01*
X570810Y-292180D01*
X570807Y-292184D01*
X570796Y-292195D01*
X570781Y-292206D01*
X570767Y-292224D01*
X570748Y-292246D01*
X570727Y-292267D01*
X570708Y-292297D01*
X570686Y-292329D01*
X570661Y-292366D01*
X570639Y-292402D01*
X570617Y-292446D01*
X570599Y-292493D01*
X570581Y-292544D01*
X570563Y-292599D01*
X570548Y-292657D01*
X570213Y-292573D01*
Y-292569D01*
X570217Y-292555D01*
X570224Y-292533D01*
X570235Y-292504D01*
X570246Y-292471D01*
X570261Y-292431D01*
X570279Y-292387D01*
X570301Y-292340D01*
X570352Y-292238D01*
X570417Y-292136D01*
X570457Y-292085D01*
X570497Y-292034D01*
X570541Y-291991D01*
X570592Y-291947D01*
X570596Y-291943D01*
X570603Y-291936D01*
X570621Y-291929D01*
X570639Y-291914D01*
X570668Y-291896D01*
X570697Y-291878D01*
X570738Y-291860D01*
X570778Y-291841D01*
X570825Y-291820D01*
X570876Y-291801D01*
X570930Y-291783D01*
X570989Y-291765D01*
X571051Y-291751D01*
X571116Y-291743D01*
X571185Y-291736D01*
X571258Y-291732D01*
X571298D01*
X571327Y-291736D01*
D02*
G37*
G36*
X569555Y-291780D02*
Y-291791D01*
Y-291805D01*
X569551Y-291827D01*
Y-291856D01*
X569547Y-291892D01*
X569544Y-291933D01*
X569540Y-291976D01*
X569533Y-292027D01*
X569525Y-292078D01*
X569514Y-292140D01*
X569503Y-292202D01*
X569493Y-292267D01*
X569478Y-292340D01*
X569442Y-292489D01*
Y-292493D01*
X569438Y-292508D01*
X569431Y-292529D01*
X569420Y-292562D01*
X569409Y-292599D01*
X569394Y-292642D01*
X569380Y-292693D01*
X569358Y-292748D01*
X569336Y-292810D01*
X569314Y-292872D01*
X569260Y-293010D01*
X569194Y-293156D01*
X569121Y-293301D01*
X569118Y-293305D01*
X569110Y-293319D01*
X569100Y-293337D01*
X569085Y-293367D01*
X569067Y-293399D01*
X569041Y-293439D01*
X569016Y-293483D01*
X568987Y-293530D01*
X568918Y-293636D01*
X568845Y-293745D01*
X568761Y-293858D01*
X568674Y-293964D01*
X569908D01*
Y-294262D01*
X568277D01*
Y-294018D01*
X568281Y-294015D01*
X568288Y-294007D01*
X568302Y-293993D01*
X568317Y-293971D01*
X568339Y-293945D01*
X568368Y-293916D01*
X568397Y-293880D01*
X568430Y-293836D01*
X568463Y-293793D01*
X568503Y-293741D01*
X568543Y-293683D01*
X568583Y-293625D01*
X568626Y-293560D01*
X568670Y-293490D01*
X568714Y-293414D01*
X568757Y-293337D01*
X568761Y-293334D01*
X568768Y-293319D01*
X568779Y-293297D01*
X568797Y-293265D01*
X568816Y-293225D01*
X568837Y-293181D01*
X568863Y-293130D01*
X568888Y-293072D01*
X568918Y-293006D01*
X568950Y-292941D01*
X568979Y-292868D01*
X569008Y-292792D01*
X569067Y-292635D01*
X569121Y-292467D01*
Y-292464D01*
X569125Y-292453D01*
X569129Y-292435D01*
X569136Y-292413D01*
X569143Y-292384D01*
X569150Y-292347D01*
X569161Y-292307D01*
X569169Y-292264D01*
X569180Y-292213D01*
X569191Y-292158D01*
X569209Y-292042D01*
X569227Y-291914D01*
X569238Y-291776D01*
X569555D01*
Y-291780D01*
D02*
G37*
G36*
X566981Y-292380D02*
X568077D01*
Y-292664D01*
X566923Y-294295D01*
X566672D01*
Y-292664D01*
X566329D01*
Y-292380D01*
X566672D01*
Y-291776D01*
X566981D01*
Y-292380D01*
D02*
G37*
G36*
X592206Y-247425D02*
X592213Y-247432D01*
X592228Y-247446D01*
X592250Y-247461D01*
X592275Y-247483D01*
X592304Y-247512D01*
X592341Y-247541D01*
X592384Y-247574D01*
X592428Y-247606D01*
X592479Y-247647D01*
X592537Y-247687D01*
X592595Y-247727D01*
X592661Y-247770D01*
X592730Y-247814D01*
X592806Y-247858D01*
X592883Y-247901D01*
X592887Y-247905D01*
X592901Y-247912D01*
X592923Y-247923D01*
X592956Y-247941D01*
X592996Y-247960D01*
X593040Y-247981D01*
X593090Y-248007D01*
X593149Y-248032D01*
X593214Y-248061D01*
X593280Y-248094D01*
X593353Y-248123D01*
X593429Y-248152D01*
X593585Y-248211D01*
X593753Y-248265D01*
X593757D01*
X593767Y-248269D01*
X593786Y-248273D01*
X593808Y-248280D01*
X593837Y-248287D01*
X593873Y-248294D01*
X593913Y-248305D01*
X593957Y-248313D01*
X594008Y-248324D01*
X594062Y-248335D01*
X594179Y-248353D01*
X594306Y-248371D01*
X594445Y-248382D01*
Y-248698D01*
X594441D01*
X594430D01*
X594415D01*
X594394Y-248695D01*
X594365D01*
X594328Y-248691D01*
X594288Y-248688D01*
X594244Y-248684D01*
X594193Y-248677D01*
X594142Y-248669D01*
X594081Y-248658D01*
X594019Y-248648D01*
X593953Y-248637D01*
X593880Y-248622D01*
X593731Y-248586D01*
X593727D01*
X593713Y-248582D01*
X593691Y-248575D01*
X593658Y-248564D01*
X593622Y-248553D01*
X593578Y-248538D01*
X593527Y-248524D01*
X593473Y-248502D01*
X593411Y-248480D01*
X593349Y-248458D01*
X593211Y-248404D01*
X593065Y-248338D01*
X592919Y-248265D01*
X592916Y-248262D01*
X592901Y-248254D01*
X592883Y-248243D01*
X592854Y-248229D01*
X592821Y-248211D01*
X592781Y-248185D01*
X592737Y-248160D01*
X592690Y-248131D01*
X592585Y-248061D01*
X592475Y-247989D01*
X592362Y-247905D01*
X592257Y-247818D01*
Y-249052D01*
X591958D01*
Y-247421D01*
X592202D01*
X592206Y-247425D01*
D02*
G37*
G36*
Y-249383D02*
X592213Y-249390D01*
X592228Y-249405D01*
X592250Y-249419D01*
X592275Y-249441D01*
X592304Y-249470D01*
X592341Y-249499D01*
X592384Y-249532D01*
X592428Y-249565D01*
X592479Y-249605D01*
X592537Y-249645D01*
X592595Y-249685D01*
X592661Y-249729D01*
X592730Y-249772D01*
X592806Y-249816D01*
X592883Y-249860D01*
X592887Y-249863D01*
X592901Y-249871D01*
X592923Y-249882D01*
X592956Y-249900D01*
X592996Y-249918D01*
X593040Y-249940D01*
X593090Y-249965D01*
X593149Y-249991D01*
X593214Y-250020D01*
X593280Y-250053D01*
X593353Y-250082D01*
X593429Y-250111D01*
X593585Y-250169D01*
X593753Y-250224D01*
X593757D01*
X593767Y-250227D01*
X593786Y-250231D01*
X593808Y-250238D01*
X593837Y-250245D01*
X593873Y-250253D01*
X593913Y-250264D01*
X593957Y-250271D01*
X594008Y-250282D01*
X594062Y-250293D01*
X594179Y-250311D01*
X594306Y-250329D01*
X594445Y-250340D01*
Y-250657D01*
X594441D01*
X594430D01*
X594415D01*
X594394Y-250653D01*
X594365D01*
X594328Y-250650D01*
X594288Y-250646D01*
X594244Y-250642D01*
X594193Y-250635D01*
X594142Y-250628D01*
X594081Y-250617D01*
X594019Y-250606D01*
X593953Y-250595D01*
X593880Y-250580D01*
X593731Y-250544D01*
X593727D01*
X593713Y-250540D01*
X593691Y-250533D01*
X593658Y-250522D01*
X593622Y-250511D01*
X593578Y-250497D01*
X593527Y-250482D01*
X593473Y-250460D01*
X593411Y-250438D01*
X593349Y-250417D01*
X593211Y-250362D01*
X593065Y-250296D01*
X592919Y-250224D01*
X592916Y-250220D01*
X592901Y-250213D01*
X592883Y-250202D01*
X592854Y-250187D01*
X592821Y-250169D01*
X592781Y-250144D01*
X592737Y-250118D01*
X592690Y-250089D01*
X592585Y-250020D01*
X592475Y-249947D01*
X592362Y-249863D01*
X592257Y-249776D01*
Y-251010D01*
X591958D01*
Y-249379D01*
X592202D01*
X592206Y-249383D01*
D02*
G37*
G36*
X593666Y-251319D02*
X593687Y-251327D01*
X593717Y-251338D01*
X593749Y-251348D01*
X593789Y-251363D01*
X593833Y-251381D01*
X593880Y-251403D01*
X593982Y-251454D01*
X594084Y-251519D01*
X594135Y-251560D01*
X594186Y-251600D01*
X594230Y-251643D01*
X594274Y-251694D01*
X594277Y-251698D01*
X594284Y-251705D01*
X594292Y-251723D01*
X594306Y-251742D01*
X594324Y-251771D01*
X594343Y-251800D01*
X594361Y-251840D01*
X594379Y-251880D01*
X594401Y-251927D01*
X594419Y-251978D01*
X594437Y-252033D01*
X594455Y-252091D01*
X594470Y-252153D01*
X594477Y-252218D01*
X594485Y-252288D01*
X594488Y-252360D01*
Y-252400D01*
X594485Y-252430D01*
Y-252462D01*
X594481Y-252502D01*
X594474Y-252546D01*
X594466Y-252597D01*
X594448Y-252702D01*
X594419Y-252812D01*
X594379Y-252921D01*
X594353Y-252972D01*
X594324Y-253023D01*
X594321Y-253027D01*
X594317Y-253034D01*
X594306Y-253048D01*
X594292Y-253063D01*
X594277Y-253085D01*
X594255Y-253110D01*
X594230Y-253139D01*
X594201Y-253168D01*
X594168Y-253198D01*
X594135Y-253230D01*
X594051Y-253296D01*
X593953Y-253358D01*
X593844Y-253412D01*
X593840D01*
X593829Y-253420D01*
X593811Y-253423D01*
X593789Y-253434D01*
X593760Y-253441D01*
X593724Y-253452D01*
X593684Y-253467D01*
X593640Y-253478D01*
X593593Y-253489D01*
X593538Y-253503D01*
X593425Y-253521D01*
X593298Y-253536D01*
X593167Y-253543D01*
X593163D01*
X593149D01*
X593127D01*
X593101Y-253540D01*
X593065D01*
X593029Y-253536D01*
X592981Y-253533D01*
X592934Y-253525D01*
X592828Y-253507D01*
X592712Y-253482D01*
X592595Y-253445D01*
X592483Y-253394D01*
X592479Y-253391D01*
X592468Y-253387D01*
X592453Y-253380D01*
X592435Y-253365D01*
X592410Y-253350D01*
X592381Y-253332D01*
X592315Y-253285D01*
X592242Y-253223D01*
X592170Y-253150D01*
X592097Y-253066D01*
X592035Y-252968D01*
X592031Y-252965D01*
X592028Y-252954D01*
X592020Y-252939D01*
X592009Y-252921D01*
X591998Y-252892D01*
X591988Y-252863D01*
X591973Y-252826D01*
X591958Y-252786D01*
X591944Y-252743D01*
X591929Y-252695D01*
X591908Y-252593D01*
X591889Y-252477D01*
X591882Y-252357D01*
Y-252320D01*
X591886Y-252295D01*
X591889Y-252262D01*
X591893Y-252222D01*
X591897Y-252182D01*
X591908Y-252135D01*
X591929Y-252036D01*
X591962Y-251927D01*
X591984Y-251873D01*
X592009Y-251822D01*
X592042Y-251771D01*
X592075Y-251720D01*
X592078Y-251716D01*
X592082Y-251709D01*
X592093Y-251694D01*
X592111Y-251676D01*
X592130Y-251658D01*
X592155Y-251632D01*
X592184Y-251607D01*
X592213Y-251578D01*
X592250Y-251549D01*
X592293Y-251519D01*
X592337Y-251487D01*
X592384Y-251458D01*
X592439Y-251432D01*
X592493Y-251403D01*
X592552Y-251381D01*
X592617Y-251359D01*
X592694Y-251687D01*
X592690D01*
X592683Y-251691D01*
X592668Y-251698D01*
X592650Y-251705D01*
X592628Y-251712D01*
X592599Y-251723D01*
X592541Y-251752D01*
X592475Y-251789D01*
X592410Y-251833D01*
X592348Y-251887D01*
X592293Y-251945D01*
X592286Y-251953D01*
X592272Y-251975D01*
X592253Y-252011D01*
X592228Y-252058D01*
X592206Y-252120D01*
X592184Y-252189D01*
X592170Y-252273D01*
X592166Y-252364D01*
Y-252393D01*
X592170Y-252411D01*
Y-252437D01*
X592173Y-252466D01*
X592184Y-252535D01*
X592199Y-252611D01*
X592224Y-252692D01*
X592261Y-252775D01*
X592308Y-252852D01*
Y-252855D01*
X592315Y-252859D01*
X592333Y-252885D01*
X592362Y-252917D01*
X592406Y-252957D01*
X592461Y-253005D01*
X592523Y-253048D01*
X592599Y-253088D01*
X592683Y-253125D01*
X592686D01*
X592694Y-253128D01*
X592705Y-253132D01*
X592723Y-253136D01*
X592745Y-253143D01*
X592770Y-253150D01*
X592832Y-253161D01*
X592905Y-253176D01*
X592985Y-253190D01*
X593072Y-253198D01*
X593167Y-253201D01*
X593171D01*
X593182D01*
X593200D01*
X593222D01*
X593247Y-253198D01*
X593280D01*
X593316Y-253194D01*
X593356Y-253190D01*
X593443Y-253179D01*
X593538Y-253161D01*
X593633Y-253139D01*
X593727Y-253110D01*
X593731D01*
X593738Y-253107D01*
X593749Y-253099D01*
X593767Y-253092D01*
X593811Y-253070D01*
X593862Y-253037D01*
X593920Y-252997D01*
X593982Y-252946D01*
X594037Y-252888D01*
X594088Y-252819D01*
Y-252815D01*
X594092Y-252808D01*
X594099Y-252797D01*
X594106Y-252783D01*
X594113Y-252764D01*
X594124Y-252743D01*
X594146Y-252692D01*
X594168Y-252626D01*
X594186Y-252553D01*
X594201Y-252473D01*
X594204Y-252390D01*
Y-252364D01*
X594201Y-252342D01*
Y-252317D01*
X594197Y-252291D01*
X594182Y-252226D01*
X594164Y-252149D01*
X594135Y-252073D01*
X594095Y-251993D01*
X594073Y-251953D01*
X594044Y-251916D01*
X594040Y-251913D01*
X594037Y-251909D01*
X594026Y-251898D01*
X594015Y-251884D01*
X593997Y-251869D01*
X593975Y-251851D01*
X593953Y-251829D01*
X593924Y-251811D01*
X593891Y-251789D01*
X593855Y-251763D01*
X593819Y-251742D01*
X593775Y-251720D01*
X593727Y-251701D01*
X593677Y-251683D01*
X593622Y-251665D01*
X593564Y-251651D01*
X593647Y-251316D01*
X593651D01*
X593666Y-251319D01*
D02*
G37*
G36*
X604715Y-247818D02*
X604737D01*
X604795Y-247829D01*
X604864Y-247840D01*
X604937Y-247858D01*
X605017Y-247884D01*
X605093Y-247920D01*
X605097D01*
X605100Y-247924D01*
X605111Y-247931D01*
X605126Y-247938D01*
X605162Y-247960D01*
X605210Y-247993D01*
X605261Y-248033D01*
X605312Y-248080D01*
X605363Y-248138D01*
X605406Y-248200D01*
Y-248204D01*
X605410Y-248208D01*
X605417Y-248219D01*
X605421Y-248233D01*
X605439Y-248270D01*
X605457Y-248317D01*
X605479Y-248379D01*
X605494Y-248448D01*
X605508Y-248524D01*
X605512Y-248608D01*
Y-248626D01*
X605508Y-248644D01*
Y-248674D01*
X605505Y-248706D01*
X605497Y-248743D01*
X605486Y-248786D01*
X605476Y-248830D01*
X605461Y-248881D01*
X605443Y-248932D01*
X605421Y-248983D01*
X605392Y-249038D01*
X605359Y-249089D01*
X605323Y-249140D01*
X605279Y-249190D01*
X605228Y-249238D01*
X605224Y-249241D01*
X605213Y-249249D01*
X605199Y-249260D01*
X605173Y-249274D01*
X605141Y-249296D01*
X605104Y-249314D01*
X605057Y-249336D01*
X605006Y-249358D01*
X604944Y-249383D01*
X604875Y-249405D01*
X604798Y-249424D01*
X604715Y-249442D01*
X604620Y-249460D01*
X604518Y-249471D01*
X604409Y-249478D01*
X604292Y-249482D01*
X604289D01*
X604285D01*
X604274D01*
X604260D01*
X604223Y-249478D01*
X604172D01*
X604114Y-249474D01*
X604045Y-249467D01*
X603968Y-249460D01*
X603885Y-249449D01*
X603801Y-249434D01*
X603710Y-249416D01*
X603623Y-249394D01*
X603535Y-249369D01*
X603452Y-249336D01*
X603371Y-249300D01*
X603295Y-249260D01*
X603230Y-249212D01*
X603226Y-249209D01*
X603219Y-249201D01*
X603204Y-249187D01*
X603182Y-249169D01*
X603160Y-249147D01*
X603139Y-249118D01*
X603110Y-249081D01*
X603084Y-249045D01*
X603058Y-249001D01*
X603029Y-248954D01*
X603008Y-248899D01*
X602982Y-248845D01*
X602964Y-248783D01*
X602949Y-248717D01*
X602942Y-248648D01*
X602938Y-248575D01*
Y-248546D01*
X602942Y-248524D01*
Y-248499D01*
X602946Y-248470D01*
X602960Y-248401D01*
X602978Y-248324D01*
X603008Y-248244D01*
X603051Y-248164D01*
X603077Y-248124D01*
X603106Y-248088D01*
X603110Y-248084D01*
X603113Y-248080D01*
X603124Y-248069D01*
X603135Y-248059D01*
X603153Y-248040D01*
X603175Y-248026D01*
X603226Y-247986D01*
X603291Y-247946D01*
X603371Y-247909D01*
X603463Y-247877D01*
X603565Y-247855D01*
X603590Y-248164D01*
X603586D01*
X603583Y-248168D01*
X603561Y-248171D01*
X603528Y-248182D01*
X603488Y-248197D01*
X603444Y-248211D01*
X603401Y-248233D01*
X603361Y-248259D01*
X603328Y-248284D01*
X603321Y-248291D01*
X603306Y-248306D01*
X603284Y-248331D01*
X603259Y-248368D01*
X603237Y-248415D01*
X603215Y-248466D01*
X603200Y-248528D01*
X603193Y-248594D01*
Y-248619D01*
X603197Y-248648D01*
X603204Y-248681D01*
X603215Y-248725D01*
X603230Y-248768D01*
X603248Y-248812D01*
X603277Y-248856D01*
X603280Y-248863D01*
X603295Y-248881D01*
X603321Y-248907D01*
X603357Y-248939D01*
X603401Y-248976D01*
X603452Y-249016D01*
X603517Y-249052D01*
X603590Y-249089D01*
X603594D01*
X603601Y-249092D01*
X603612Y-249096D01*
X603626Y-249103D01*
X603648Y-249107D01*
X603674Y-249114D01*
X603703Y-249121D01*
X603739Y-249129D01*
X603779Y-249140D01*
X603823Y-249147D01*
X603870Y-249154D01*
X603921Y-249158D01*
X603979Y-249165D01*
X604038Y-249169D01*
X604103Y-249172D01*
X604169D01*
X604165Y-249169D01*
X604143Y-249154D01*
X604114Y-249129D01*
X604078Y-249096D01*
X604034Y-249060D01*
X603994Y-249012D01*
X603954Y-248961D01*
X603918Y-248903D01*
Y-248899D01*
X603914Y-248896D01*
X603903Y-248874D01*
X603892Y-248841D01*
X603874Y-248797D01*
X603859Y-248746D01*
X603848Y-248688D01*
X603837Y-248626D01*
X603834Y-248561D01*
Y-248532D01*
X603837Y-248510D01*
X603841Y-248481D01*
X603845Y-248452D01*
X603852Y-248415D01*
X603863Y-248379D01*
X603888Y-248295D01*
X603907Y-248251D01*
X603932Y-248208D01*
X603958Y-248164D01*
X603987Y-248117D01*
X604023Y-248073D01*
X604063Y-248033D01*
X604067Y-248029D01*
X604074Y-248022D01*
X604085Y-248011D01*
X604103Y-248000D01*
X604129Y-247982D01*
X604154Y-247964D01*
X604187Y-247946D01*
X604223Y-247924D01*
X604263Y-247902D01*
X604307Y-247884D01*
X604358Y-247866D01*
X604409Y-247847D01*
X604463Y-247836D01*
X604525Y-247826D01*
X604587Y-247818D01*
X604653Y-247815D01*
X604657D01*
X604664D01*
X604675D01*
X604693D01*
X604715Y-247818D01*
D02*
G37*
G36*
X603230Y-249777D02*
X603237Y-249784D01*
X603251Y-249798D01*
X603273Y-249813D01*
X603299Y-249835D01*
X603328Y-249864D01*
X603364Y-249893D01*
X603408Y-249926D01*
X603452Y-249959D01*
X603503Y-249999D01*
X603561Y-250039D01*
X603619Y-250079D01*
X603685Y-250122D01*
X603754Y-250166D01*
X603830Y-250210D01*
X603907Y-250253D01*
X603910Y-250257D01*
X603925Y-250264D01*
X603947Y-250275D01*
X603979Y-250293D01*
X604019Y-250312D01*
X604063Y-250333D01*
X604114Y-250359D01*
X604172Y-250384D01*
X604238Y-250413D01*
X604303Y-250446D01*
X604376Y-250475D01*
X604453Y-250505D01*
X604609Y-250563D01*
X604777Y-250617D01*
X604780D01*
X604791Y-250621D01*
X604809Y-250625D01*
X604831Y-250632D01*
X604860Y-250639D01*
X604897Y-250646D01*
X604937Y-250657D01*
X604980Y-250665D01*
X605031Y-250676D01*
X605086Y-250687D01*
X605202Y-250705D01*
X605330Y-250723D01*
X605468Y-250734D01*
Y-251051D01*
X605465D01*
X605454D01*
X605439D01*
X605417Y-251047D01*
X605388D01*
X605352Y-251043D01*
X605312Y-251040D01*
X605268Y-251036D01*
X605217Y-251029D01*
X605166Y-251021D01*
X605104Y-251010D01*
X605042Y-251000D01*
X604977Y-250989D01*
X604904Y-250974D01*
X604755Y-250938D01*
X604751D01*
X604737Y-250934D01*
X604715Y-250927D01*
X604682Y-250916D01*
X604645Y-250905D01*
X604602Y-250890D01*
X604551Y-250876D01*
X604496Y-250854D01*
X604434Y-250832D01*
X604373Y-250810D01*
X604234Y-250756D01*
X604089Y-250690D01*
X603943Y-250617D01*
X603939Y-250614D01*
X603925Y-250606D01*
X603907Y-250596D01*
X603877Y-250581D01*
X603845Y-250563D01*
X603805Y-250537D01*
X603761Y-250512D01*
X603714Y-250483D01*
X603608Y-250413D01*
X603499Y-250341D01*
X603386Y-250257D01*
X603280Y-250170D01*
Y-251404D01*
X602982D01*
Y-249773D01*
X603226D01*
X603230Y-249777D01*
D02*
G37*
G36*
X604689Y-251713D02*
X604711Y-251720D01*
X604740Y-251731D01*
X604773Y-251742D01*
X604813Y-251757D01*
X604857Y-251775D01*
X604904Y-251797D01*
X605006Y-251848D01*
X605108Y-251913D01*
X605159Y-251953D01*
X605210Y-251993D01*
X605253Y-252037D01*
X605297Y-252088D01*
X605301Y-252092D01*
X605308Y-252099D01*
X605315Y-252117D01*
X605330Y-252135D01*
X605348Y-252164D01*
X605366Y-252193D01*
X605384Y-252234D01*
X605403Y-252274D01*
X605424Y-252321D01*
X605443Y-252372D01*
X605461Y-252427D01*
X605479Y-252485D01*
X605494Y-252547D01*
X605501Y-252612D01*
X605508Y-252681D01*
X605512Y-252754D01*
Y-252794D01*
X605508Y-252823D01*
Y-252856D01*
X605505Y-252896D01*
X605497Y-252940D01*
X605490Y-252991D01*
X605472Y-253096D01*
X605443Y-253205D01*
X605403Y-253315D01*
X605377Y-253366D01*
X605348Y-253417D01*
X605344Y-253420D01*
X605341Y-253428D01*
X605330Y-253442D01*
X605315Y-253457D01*
X605301Y-253478D01*
X605279Y-253504D01*
X605253Y-253533D01*
X605224Y-253562D01*
X605192Y-253591D01*
X605159Y-253624D01*
X605075Y-253690D01*
X604977Y-253751D01*
X604868Y-253806D01*
X604864D01*
X604853Y-253813D01*
X604835Y-253817D01*
X604813Y-253828D01*
X604784Y-253835D01*
X604747Y-253846D01*
X604707Y-253861D01*
X604664Y-253871D01*
X604616Y-253883D01*
X604562Y-253897D01*
X604449Y-253915D01*
X604322Y-253930D01*
X604190Y-253937D01*
X604187D01*
X604172D01*
X604150D01*
X604125Y-253933D01*
X604089D01*
X604052Y-253930D01*
X604005Y-253926D01*
X603958Y-253919D01*
X603852Y-253901D01*
X603735Y-253875D01*
X603619Y-253839D01*
X603506Y-253788D01*
X603503Y-253784D01*
X603492Y-253781D01*
X603477Y-253773D01*
X603459Y-253759D01*
X603433Y-253744D01*
X603404Y-253726D01*
X603339Y-253679D01*
X603266Y-253617D01*
X603193Y-253544D01*
X603120Y-253460D01*
X603058Y-253362D01*
X603055Y-253358D01*
X603051Y-253347D01*
X603044Y-253333D01*
X603033Y-253315D01*
X603022Y-253286D01*
X603011Y-253256D01*
X602997Y-253220D01*
X602982Y-253180D01*
X602968Y-253136D01*
X602953Y-253089D01*
X602931Y-252987D01*
X602913Y-252871D01*
X602906Y-252750D01*
Y-252714D01*
X602909Y-252689D01*
X602913Y-252656D01*
X602916Y-252616D01*
X602920Y-252576D01*
X602931Y-252528D01*
X602953Y-252430D01*
X602986Y-252321D01*
X603008Y-252266D01*
X603033Y-252215D01*
X603066Y-252164D01*
X603098Y-252113D01*
X603102Y-252110D01*
X603106Y-252102D01*
X603117Y-252088D01*
X603135Y-252070D01*
X603153Y-252051D01*
X603179Y-252026D01*
X603208Y-252001D01*
X603237Y-251972D01*
X603273Y-251942D01*
X603317Y-251913D01*
X603361Y-251881D01*
X603408Y-251851D01*
X603463Y-251826D01*
X603517Y-251797D01*
X603575Y-251775D01*
X603641Y-251753D01*
X603717Y-252081D01*
X603714D01*
X603706Y-252084D01*
X603692Y-252092D01*
X603674Y-252099D01*
X603652Y-252106D01*
X603623Y-252117D01*
X603565Y-252146D01*
X603499Y-252183D01*
X603433Y-252226D01*
X603371Y-252281D01*
X603317Y-252339D01*
X603310Y-252346D01*
X603295Y-252368D01*
X603277Y-252405D01*
X603251Y-252452D01*
X603230Y-252514D01*
X603208Y-252583D01*
X603193Y-252667D01*
X603190Y-252758D01*
Y-252787D01*
X603193Y-252805D01*
Y-252831D01*
X603197Y-252860D01*
X603208Y-252929D01*
X603222Y-253005D01*
X603248Y-253085D01*
X603284Y-253169D01*
X603332Y-253245D01*
Y-253249D01*
X603339Y-253253D01*
X603357Y-253278D01*
X603386Y-253311D01*
X603430Y-253351D01*
X603484Y-253398D01*
X603546Y-253442D01*
X603623Y-253482D01*
X603706Y-253519D01*
X603710D01*
X603717Y-253522D01*
X603728Y-253526D01*
X603747Y-253529D01*
X603768Y-253537D01*
X603794Y-253544D01*
X603856Y-253555D01*
X603928Y-253569D01*
X604008Y-253584D01*
X604096Y-253591D01*
X604190Y-253595D01*
X604194D01*
X604205D01*
X604223D01*
X604245D01*
X604271Y-253591D01*
X604303D01*
X604340Y-253588D01*
X604380Y-253584D01*
X604467Y-253573D01*
X604562Y-253555D01*
X604657Y-253533D01*
X604751Y-253504D01*
X604755D01*
X604762Y-253500D01*
X604773Y-253493D01*
X604791Y-253486D01*
X604835Y-253464D01*
X604886Y-253431D01*
X604944Y-253391D01*
X605006Y-253340D01*
X605060Y-253282D01*
X605111Y-253213D01*
Y-253209D01*
X605115Y-253202D01*
X605122Y-253191D01*
X605130Y-253176D01*
X605137Y-253158D01*
X605148Y-253136D01*
X605170Y-253085D01*
X605192Y-253020D01*
X605210Y-252947D01*
X605224Y-252867D01*
X605228Y-252783D01*
Y-252758D01*
X605224Y-252736D01*
Y-252710D01*
X605221Y-252685D01*
X605206Y-252619D01*
X605188Y-252543D01*
X605159Y-252467D01*
X605119Y-252386D01*
X605097Y-252346D01*
X605068Y-252310D01*
X605064Y-252306D01*
X605060Y-252303D01*
X605050Y-252292D01*
X605039Y-252277D01*
X605020Y-252263D01*
X604999Y-252244D01*
X604977Y-252223D01*
X604948Y-252204D01*
X604915Y-252183D01*
X604879Y-252157D01*
X604842Y-252135D01*
X604798Y-252113D01*
X604751Y-252095D01*
X604700Y-252077D01*
X604645Y-252059D01*
X604587Y-252044D01*
X604671Y-251709D01*
X604675D01*
X604689Y-251713D01*
D02*
G37*
G36*
X665422Y-265901D02*
X665454Y-265905D01*
X665494Y-265909D01*
X665534Y-265912D01*
X665582Y-265923D01*
X665680Y-265945D01*
X665789Y-265978D01*
X665844Y-266000D01*
X665895Y-266025D01*
X665946Y-266058D01*
X665997Y-266091D01*
X666001Y-266094D01*
X666008Y-266098D01*
X666022Y-266109D01*
X666041Y-266127D01*
X666059Y-266145D01*
X666084Y-266171D01*
X666110Y-266200D01*
X666139Y-266229D01*
X666168Y-266265D01*
X666197Y-266309D01*
X666230Y-266353D01*
X666259Y-266400D01*
X666284Y-266455D01*
X666314Y-266509D01*
X666335Y-266567D01*
X666357Y-266633D01*
X666030Y-266709D01*
Y-266706D01*
X666026Y-266699D01*
X666019Y-266684D01*
X666011Y-266666D01*
X666004Y-266644D01*
X665993Y-266615D01*
X665964Y-266557D01*
X665928Y-266491D01*
X665884Y-266426D01*
X665829Y-266364D01*
X665771Y-266309D01*
X665764Y-266302D01*
X665742Y-266287D01*
X665706Y-266269D01*
X665658Y-266244D01*
X665596Y-266222D01*
X665527Y-266200D01*
X665444Y-266185D01*
X665352Y-266182D01*
X665323D01*
X665305Y-266185D01*
X665280D01*
X665251Y-266189D01*
X665181Y-266200D01*
X665105Y-266214D01*
X665025Y-266240D01*
X664941Y-266276D01*
X664865Y-266324D01*
X664861D01*
X664857Y-266331D01*
X664832Y-266349D01*
X664799Y-266378D01*
X664759Y-266422D01*
X664712Y-266476D01*
X664668Y-266538D01*
X664628Y-266615D01*
X664592Y-266699D01*
Y-266702D01*
X664588Y-266709D01*
X664584Y-266720D01*
X664581Y-266739D01*
X664574Y-266760D01*
X664566Y-266786D01*
X664555Y-266848D01*
X664541Y-266921D01*
X664526Y-267001D01*
X664519Y-267088D01*
X664515Y-267183D01*
Y-267186D01*
Y-267197D01*
Y-267215D01*
Y-267237D01*
X664519Y-267263D01*
Y-267296D01*
X664523Y-267332D01*
X664526Y-267372D01*
X664537Y-267459D01*
X664555Y-267554D01*
X664577Y-267649D01*
X664606Y-267743D01*
Y-267747D01*
X664610Y-267754D01*
X664617Y-267765D01*
X664625Y-267783D01*
X664646Y-267827D01*
X664679Y-267878D01*
X664719Y-267936D01*
X664770Y-267998D01*
X664828Y-268053D01*
X664897Y-268104D01*
X664901D01*
X664909Y-268107D01*
X664919Y-268114D01*
X664934Y-268122D01*
X664952Y-268129D01*
X664974Y-268140D01*
X665025Y-268162D01*
X665091Y-268184D01*
X665163Y-268202D01*
X665243Y-268216D01*
X665327Y-268220D01*
X665352D01*
X665374Y-268216D01*
X665400D01*
X665425Y-268213D01*
X665491Y-268198D01*
X665567Y-268180D01*
X665644Y-268151D01*
X665724Y-268111D01*
X665764Y-268089D01*
X665800Y-268060D01*
X665804Y-268056D01*
X665807Y-268053D01*
X665819Y-268042D01*
X665833Y-268031D01*
X665848Y-268013D01*
X665866Y-267991D01*
X665888Y-267969D01*
X665906Y-267940D01*
X665928Y-267907D01*
X665953Y-267871D01*
X665975Y-267834D01*
X665997Y-267791D01*
X666015Y-267743D01*
X666033Y-267692D01*
X666051Y-267638D01*
X666066Y-267579D01*
X666401Y-267663D01*
Y-267667D01*
X666397Y-267681D01*
X666390Y-267703D01*
X666379Y-267732D01*
X666368Y-267765D01*
X666354Y-267805D01*
X666335Y-267849D01*
X666314Y-267896D01*
X666262Y-267998D01*
X666197Y-268100D01*
X666157Y-268151D01*
X666117Y-268202D01*
X666073Y-268246D01*
X666022Y-268289D01*
X666019Y-268293D01*
X666011Y-268300D01*
X665993Y-268307D01*
X665975Y-268322D01*
X665946Y-268340D01*
X665917Y-268358D01*
X665877Y-268377D01*
X665837Y-268395D01*
X665789Y-268417D01*
X665738Y-268435D01*
X665684Y-268453D01*
X665625Y-268471D01*
X665564Y-268486D01*
X665498Y-268493D01*
X665429Y-268500D01*
X665356Y-268504D01*
X665316D01*
X665287Y-268500D01*
X665254D01*
X665214Y-268497D01*
X665170Y-268489D01*
X665120Y-268482D01*
X665014Y-268464D01*
X664905Y-268435D01*
X664796Y-268395D01*
X664745Y-268369D01*
X664694Y-268340D01*
X664690Y-268337D01*
X664683Y-268333D01*
X664668Y-268322D01*
X664654Y-268307D01*
X664632Y-268293D01*
X664606Y-268271D01*
X664577Y-268246D01*
X664548Y-268216D01*
X664519Y-268184D01*
X664486Y-268151D01*
X664421Y-268067D01*
X664359Y-267969D01*
X664304Y-267860D01*
Y-267856D01*
X664297Y-267845D01*
X664293Y-267827D01*
X664282Y-267805D01*
X664275Y-267776D01*
X664264Y-267740D01*
X664250Y-267700D01*
X664239Y-267656D01*
X664228Y-267609D01*
X664213Y-267554D01*
X664195Y-267441D01*
X664181Y-267314D01*
X664173Y-267183D01*
Y-267179D01*
Y-267164D01*
Y-267143D01*
X664177Y-267117D01*
Y-267081D01*
X664181Y-267044D01*
X664184Y-266997D01*
X664191Y-266950D01*
X664210Y-266844D01*
X664235Y-266728D01*
X664271Y-266611D01*
X664322Y-266498D01*
X664326Y-266495D01*
X664330Y-266484D01*
X664337Y-266469D01*
X664352Y-266451D01*
X664366Y-266426D01*
X664384Y-266396D01*
X664432Y-266331D01*
X664494Y-266258D01*
X664566Y-266185D01*
X664650Y-266112D01*
X664748Y-266051D01*
X664752Y-266047D01*
X664763Y-266043D01*
X664777Y-266036D01*
X664796Y-266025D01*
X664825Y-266014D01*
X664854Y-266003D01*
X664890Y-265989D01*
X664930Y-265974D01*
X664974Y-265960D01*
X665021Y-265945D01*
X665123Y-265923D01*
X665240Y-265905D01*
X665360Y-265898D01*
X665396D01*
X665422Y-265901D01*
D02*
G37*
G36*
X668337Y-266218D02*
X668334Y-266222D01*
X668326Y-266229D01*
X668312Y-266244D01*
X668297Y-266265D01*
X668275Y-266291D01*
X668246Y-266320D01*
X668217Y-266356D01*
X668185Y-266400D01*
X668152Y-266444D01*
X668112Y-266495D01*
X668072Y-266553D01*
X668032Y-266611D01*
X667988Y-266677D01*
X667944Y-266746D01*
X667901Y-266822D01*
X667857Y-266899D01*
X667853Y-266902D01*
X667846Y-266917D01*
X667835Y-266939D01*
X667817Y-266971D01*
X667799Y-267012D01*
X667777Y-267055D01*
X667751Y-267106D01*
X667726Y-267164D01*
X667697Y-267230D01*
X667664Y-267296D01*
X667635Y-267368D01*
X667606Y-267445D01*
X667548Y-267601D01*
X667493Y-267769D01*
Y-267772D01*
X667489Y-267783D01*
X667486Y-267801D01*
X667478Y-267823D01*
X667471Y-267852D01*
X667464Y-267889D01*
X667453Y-267929D01*
X667446Y-267973D01*
X667435Y-268023D01*
X667424Y-268078D01*
X667406Y-268195D01*
X667387Y-268322D01*
X667376Y-268460D01*
X667060D01*
Y-268457D01*
Y-268446D01*
Y-268431D01*
X667063Y-268409D01*
Y-268380D01*
X667067Y-268344D01*
X667071Y-268304D01*
X667074Y-268260D01*
X667081Y-268209D01*
X667089Y-268158D01*
X667100Y-268096D01*
X667111Y-268034D01*
X667122Y-267969D01*
X667136Y-267896D01*
X667172Y-267747D01*
Y-267743D01*
X667176Y-267729D01*
X667183Y-267707D01*
X667194Y-267674D01*
X667205Y-267638D01*
X667220Y-267594D01*
X667234Y-267543D01*
X667256Y-267488D01*
X667278Y-267426D01*
X667300Y-267365D01*
X667354Y-267226D01*
X667420Y-267081D01*
X667493Y-266935D01*
X667496Y-266932D01*
X667504Y-266917D01*
X667515Y-266899D01*
X667529Y-266870D01*
X667548Y-266837D01*
X667573Y-266797D01*
X667598Y-266753D01*
X667627Y-266706D01*
X667697Y-266600D01*
X667769Y-266491D01*
X667853Y-266378D01*
X667941Y-266273D01*
X666707D01*
Y-265974D01*
X668337D01*
Y-266218D01*
D02*
G37*
G36*
X669517Y-265934D02*
X669546Y-265938D01*
X669579Y-265941D01*
X669615Y-265945D01*
X669651Y-265956D01*
X669739Y-265978D01*
X669826Y-266011D01*
X669870Y-266032D01*
X669913Y-266058D01*
X669953Y-266091D01*
X669993Y-266123D01*
X669997Y-266127D01*
X670001Y-266131D01*
X670012Y-266142D01*
X670026Y-266156D01*
X670041Y-266178D01*
X670059Y-266200D01*
X670095Y-266254D01*
X670132Y-266324D01*
X670165Y-266404D01*
X670190Y-266495D01*
X670194Y-266542D01*
X670197Y-266593D01*
Y-266597D01*
Y-266600D01*
Y-266622D01*
X670194Y-266655D01*
X670187Y-266695D01*
X670176Y-266746D01*
X670157Y-266797D01*
X670135Y-266848D01*
X670103Y-266899D01*
X670099Y-266906D01*
X670084Y-266921D01*
X670063Y-266942D01*
X670034Y-266971D01*
X669993Y-267004D01*
X669946Y-267037D01*
X669892Y-267070D01*
X669826Y-267099D01*
X669830D01*
X669837Y-267103D01*
X669848Y-267106D01*
X669863Y-267113D01*
X669906Y-267132D01*
X669957Y-267157D01*
X670012Y-267194D01*
X670070Y-267234D01*
X670125Y-267285D01*
X670176Y-267343D01*
Y-267347D01*
X670179Y-267350D01*
X670194Y-267372D01*
X670216Y-267408D01*
X670237Y-267456D01*
X670259Y-267514D01*
X670281Y-267583D01*
X670296Y-267659D01*
X670299Y-267743D01*
Y-267747D01*
Y-267758D01*
Y-267776D01*
X670296Y-267798D01*
X670292Y-267823D01*
X670288Y-267856D01*
X670281Y-267893D01*
X670270Y-267933D01*
X670245Y-268016D01*
X670226Y-268063D01*
X670201Y-268107D01*
X670176Y-268155D01*
X670146Y-268198D01*
X670110Y-268242D01*
X670070Y-268286D01*
X670066Y-268289D01*
X670059Y-268297D01*
X670048Y-268307D01*
X670030Y-268318D01*
X670005Y-268337D01*
X669979Y-268355D01*
X669946Y-268373D01*
X669910Y-268395D01*
X669870Y-268417D01*
X669823Y-268435D01*
X669771Y-268453D01*
X669721Y-268471D01*
X669662Y-268482D01*
X669600Y-268493D01*
X669538Y-268500D01*
X669469Y-268504D01*
X669433D01*
X669408Y-268500D01*
X669375Y-268497D01*
X669338Y-268493D01*
X669298Y-268486D01*
X669255Y-268475D01*
X669156Y-268449D01*
X669105Y-268431D01*
X669058Y-268413D01*
X669007Y-268388D01*
X668956Y-268358D01*
X668909Y-268326D01*
X668865Y-268286D01*
X668861Y-268282D01*
X668854Y-268275D01*
X668843Y-268264D01*
X668829Y-268246D01*
X668814Y-268224D01*
X668792Y-268198D01*
X668774Y-268169D01*
X668752Y-268133D01*
X668730Y-268096D01*
X668712Y-268053D01*
X668676Y-267962D01*
X668661Y-267907D01*
X668650Y-267852D01*
X668643Y-267794D01*
X668640Y-267736D01*
Y-267732D01*
Y-267725D01*
Y-267710D01*
X668643Y-267696D01*
Y-267674D01*
X668647Y-267649D01*
X668654Y-267590D01*
X668669Y-267525D01*
X668690Y-267459D01*
X668723Y-267390D01*
X668763Y-267325D01*
Y-267321D01*
X668771Y-267317D01*
X668785Y-267299D01*
X668814Y-267270D01*
X668854Y-267234D01*
X668905Y-267197D01*
X668967Y-267157D01*
X669036Y-267124D01*
X669120Y-267099D01*
X669116D01*
X669113Y-267095D01*
X669102Y-267092D01*
X669087Y-267084D01*
X669054Y-267070D01*
X669011Y-267048D01*
X668963Y-267019D01*
X668916Y-266983D01*
X668872Y-266942D01*
X668832Y-266899D01*
X668829Y-266892D01*
X668818Y-266877D01*
X668803Y-266848D01*
X668789Y-266811D01*
X668771Y-266764D01*
X668756Y-266709D01*
X668745Y-266648D01*
X668741Y-266582D01*
Y-266578D01*
Y-266571D01*
Y-266557D01*
X668745Y-266535D01*
X668749Y-266513D01*
X668752Y-266484D01*
X668767Y-266422D01*
X668789Y-266349D01*
X668825Y-266273D01*
X668847Y-266233D01*
X668872Y-266193D01*
X668905Y-266156D01*
X668938Y-266120D01*
X668942Y-266116D01*
X668949Y-266112D01*
X668960Y-266102D01*
X668974Y-266091D01*
X668993Y-266076D01*
X669018Y-266061D01*
X669047Y-266043D01*
X669076Y-266025D01*
X669113Y-266007D01*
X669153Y-265989D01*
X669196Y-265974D01*
X669244Y-265960D01*
X669346Y-265938D01*
X669404Y-265934D01*
X669462Y-265931D01*
X669495D01*
X669517Y-265934D01*
D02*
G37*
G36*
X636516Y-277956D02*
X636545Y-277960D01*
X636578Y-277964D01*
X636615Y-277971D01*
X636655Y-277978D01*
X636742Y-278000D01*
X636833Y-278036D01*
X636880Y-278058D01*
X636924Y-278084D01*
X636968Y-278116D01*
X637011Y-278149D01*
X637015Y-278153D01*
X637022Y-278160D01*
X637033Y-278171D01*
X637044Y-278186D01*
X637062Y-278204D01*
X637080Y-278229D01*
X637102Y-278255D01*
X637124Y-278288D01*
X637146Y-278324D01*
X637168Y-278360D01*
X637208Y-278448D01*
X637241Y-278550D01*
X637252Y-278604D01*
X637259Y-278662D01*
X636949Y-278703D01*
Y-278699D01*
X636946Y-278692D01*
X636942Y-278677D01*
X636938Y-278659D01*
X636935Y-278637D01*
X636928Y-278612D01*
X636909Y-278557D01*
X636884Y-278491D01*
X636851Y-278430D01*
X636815Y-278371D01*
X636771Y-278320D01*
X636764Y-278317D01*
X636749Y-278302D01*
X636720Y-278284D01*
X636684Y-278266D01*
X636640Y-278244D01*
X636585Y-278226D01*
X636523Y-278211D01*
X636458Y-278207D01*
X636436D01*
X636422Y-278211D01*
X636381Y-278215D01*
X636331Y-278226D01*
X636272Y-278244D01*
X636210Y-278269D01*
X636149Y-278306D01*
X636090Y-278357D01*
X636083Y-278364D01*
X636065Y-278386D01*
X636043Y-278419D01*
X636014Y-278462D01*
X635985Y-278517D01*
X635963Y-278579D01*
X635945Y-278652D01*
X635937Y-278732D01*
Y-278735D01*
Y-278743D01*
Y-278753D01*
X635941Y-278768D01*
X635945Y-278808D01*
X635956Y-278855D01*
X635970Y-278914D01*
X635996Y-278972D01*
X636032Y-279030D01*
X636079Y-279085D01*
X636087Y-279092D01*
X636105Y-279107D01*
X636134Y-279129D01*
X636174Y-279154D01*
X636225Y-279179D01*
X636287Y-279201D01*
X636356Y-279216D01*
X636433Y-279223D01*
X636465D01*
X636491Y-279220D01*
X636523Y-279216D01*
X636560Y-279208D01*
X636604Y-279201D01*
X636651Y-279190D01*
X636615Y-279463D01*
X636596D01*
X636582Y-279460D01*
X636534D01*
X636494Y-279467D01*
X636447Y-279474D01*
X636392Y-279485D01*
X636331Y-279503D01*
X636272Y-279529D01*
X636210Y-279562D01*
X636207D01*
X636203Y-279565D01*
X636185Y-279580D01*
X636160Y-279605D01*
X636130Y-279638D01*
X636101Y-279685D01*
X636076Y-279740D01*
X636058Y-279802D01*
X636050Y-279838D01*
Y-279878D01*
Y-279882D01*
Y-279886D01*
Y-279907D01*
X636058Y-279937D01*
X636065Y-279977D01*
X636079Y-280020D01*
X636098Y-280068D01*
X636127Y-280115D01*
X636167Y-280159D01*
X636170Y-280162D01*
X636189Y-280177D01*
X636214Y-280195D01*
X636247Y-280217D01*
X636291Y-280235D01*
X636341Y-280253D01*
X636400Y-280268D01*
X636465Y-280271D01*
X636494D01*
X636527Y-280264D01*
X636571Y-280257D01*
X636618Y-280242D01*
X636665Y-280224D01*
X636716Y-280195D01*
X636764Y-280159D01*
X636767Y-280155D01*
X636782Y-280137D01*
X636804Y-280111D01*
X636829Y-280075D01*
X636855Y-280028D01*
X636880Y-279969D01*
X636902Y-279900D01*
X636917Y-279820D01*
X637226Y-279875D01*
Y-279878D01*
X637222Y-279889D01*
X637219Y-279904D01*
X637215Y-279926D01*
X637208Y-279951D01*
X637197Y-279980D01*
X637175Y-280049D01*
X637139Y-280129D01*
X637095Y-280209D01*
X637040Y-280286D01*
X636971Y-280355D01*
X636968Y-280359D01*
X636960Y-280362D01*
X636949Y-280370D01*
X636935Y-280381D01*
X636917Y-280395D01*
X636891Y-280410D01*
X636866Y-280424D01*
X636833Y-280443D01*
X636760Y-280472D01*
X636676Y-280501D01*
X636578Y-280519D01*
X636527Y-280526D01*
X636436D01*
X636396Y-280523D01*
X636349Y-280515D01*
X636291Y-280504D01*
X636225Y-280486D01*
X636160Y-280464D01*
X636094Y-280435D01*
X636090D01*
X636087Y-280432D01*
X636065Y-280421D01*
X636032Y-280399D01*
X635996Y-280373D01*
X635952Y-280337D01*
X635908Y-280297D01*
X635865Y-280250D01*
X635828Y-280195D01*
X635825Y-280188D01*
X635814Y-280170D01*
X635799Y-280137D01*
X635781Y-280097D01*
X635763Y-280049D01*
X635748Y-279995D01*
X635737Y-279933D01*
X635734Y-279871D01*
Y-279864D01*
Y-279842D01*
X635737Y-279813D01*
X635744Y-279773D01*
X635755Y-279725D01*
X635774Y-279674D01*
X635795Y-279624D01*
X635825Y-279573D01*
X635828Y-279565D01*
X635839Y-279551D01*
X635861Y-279525D01*
X635890Y-279496D01*
X635926Y-279463D01*
X635970Y-279427D01*
X636021Y-279394D01*
X636083Y-279361D01*
X636079D01*
X636072Y-279358D01*
X636061Y-279354D01*
X636047Y-279350D01*
X636007Y-279336D01*
X635956Y-279314D01*
X635897Y-279285D01*
X635839Y-279249D01*
X635785Y-279201D01*
X635734Y-279147D01*
X635730Y-279139D01*
X635715Y-279117D01*
X635694Y-279081D01*
X635672Y-279034D01*
X635650Y-278976D01*
X635628Y-278906D01*
X635613Y-278826D01*
X635610Y-278739D01*
Y-278735D01*
Y-278724D01*
Y-278706D01*
X635613Y-278684D01*
X635617Y-278655D01*
X635624Y-278623D01*
X635632Y-278586D01*
X635639Y-278546D01*
X635668Y-278459D01*
X635690Y-278411D01*
X635712Y-278368D01*
X635741Y-278320D01*
X635774Y-278273D01*
X635810Y-278226D01*
X635854Y-278182D01*
X635857Y-278178D01*
X635865Y-278171D01*
X635879Y-278160D01*
X635897Y-278146D01*
X635919Y-278127D01*
X635948Y-278109D01*
X635981Y-278087D01*
X636021Y-278069D01*
X636061Y-278047D01*
X636108Y-278026D01*
X636156Y-278007D01*
X636210Y-277989D01*
X636269Y-277975D01*
X636331Y-277964D01*
X636392Y-277956D01*
X636462Y-277953D01*
X636494D01*
X636516Y-277956D01*
D02*
G37*
G36*
X640619D02*
X640651D01*
X640691Y-277960D01*
X640735Y-277967D01*
X640786Y-277975D01*
X640892Y-277993D01*
X641001Y-278022D01*
X641110Y-278062D01*
X641161Y-278087D01*
X641212Y-278116D01*
X641215Y-278120D01*
X641223Y-278124D01*
X641237Y-278135D01*
X641252Y-278149D01*
X641274Y-278164D01*
X641299Y-278186D01*
X641328Y-278211D01*
X641357Y-278240D01*
X641387Y-278273D01*
X641419Y-278306D01*
X641485Y-278390D01*
X641547Y-278488D01*
X641601Y-278597D01*
Y-278601D01*
X641609Y-278612D01*
X641612Y-278630D01*
X641623Y-278652D01*
X641630Y-278681D01*
X641641Y-278717D01*
X641656Y-278757D01*
X641667Y-278801D01*
X641678Y-278848D01*
X641692Y-278903D01*
X641711Y-279016D01*
X641725Y-279143D01*
X641732Y-279274D01*
Y-279278D01*
Y-279292D01*
Y-279314D01*
X641729Y-279340D01*
Y-279376D01*
X641725Y-279412D01*
X641721Y-279460D01*
X641714Y-279507D01*
X641696Y-279613D01*
X641670Y-279729D01*
X641634Y-279845D01*
X641583Y-279958D01*
X641579Y-279962D01*
X641576Y-279973D01*
X641569Y-279988D01*
X641554Y-280006D01*
X641539Y-280031D01*
X641521Y-280060D01*
X641474Y-280126D01*
X641412Y-280199D01*
X641339Y-280271D01*
X641256Y-280344D01*
X641157Y-280406D01*
X641154Y-280410D01*
X641143Y-280413D01*
X641128Y-280421D01*
X641110Y-280432D01*
X641081Y-280443D01*
X641052Y-280453D01*
X641015Y-280468D01*
X640975Y-280483D01*
X640932Y-280497D01*
X640884Y-280512D01*
X640782Y-280534D01*
X640666Y-280552D01*
X640546Y-280559D01*
X640509D01*
X640484Y-280555D01*
X640451Y-280552D01*
X640411Y-280548D01*
X640371Y-280544D01*
X640324Y-280534D01*
X640225Y-280512D01*
X640116Y-280479D01*
X640062Y-280457D01*
X640011Y-280432D01*
X639960Y-280399D01*
X639909Y-280366D01*
X639905Y-280362D01*
X639898Y-280359D01*
X639883Y-280348D01*
X639865Y-280330D01*
X639847Y-280311D01*
X639821Y-280286D01*
X639796Y-280257D01*
X639767Y-280228D01*
X639738Y-280191D01*
X639709Y-280148D01*
X639676Y-280104D01*
X639647Y-280057D01*
X639621Y-280002D01*
X639592Y-279947D01*
X639570Y-279889D01*
X639548Y-279824D01*
X639876Y-279747D01*
Y-279751D01*
X639880Y-279758D01*
X639887Y-279773D01*
X639894Y-279791D01*
X639901Y-279813D01*
X639912Y-279842D01*
X639941Y-279900D01*
X639978Y-279966D01*
X640022Y-280031D01*
X640076Y-280093D01*
X640134Y-280148D01*
X640142Y-280155D01*
X640164Y-280170D01*
X640200Y-280188D01*
X640247Y-280213D01*
X640309Y-280235D01*
X640378Y-280257D01*
X640462Y-280271D01*
X640553Y-280275D01*
X640582D01*
X640600Y-280271D01*
X640626D01*
X640655Y-280268D01*
X640724Y-280257D01*
X640801Y-280242D01*
X640881Y-280217D01*
X640964Y-280180D01*
X641041Y-280133D01*
X641044D01*
X641048Y-280126D01*
X641074Y-280108D01*
X641106Y-280079D01*
X641146Y-280035D01*
X641194Y-279980D01*
X641237Y-279918D01*
X641277Y-279842D01*
X641314Y-279758D01*
Y-279754D01*
X641317Y-279747D01*
X641321Y-279736D01*
X641325Y-279718D01*
X641332Y-279696D01*
X641339Y-279671D01*
X641350Y-279609D01*
X641365Y-279536D01*
X641379Y-279456D01*
X641387Y-279369D01*
X641390Y-279274D01*
Y-279270D01*
Y-279259D01*
Y-279241D01*
Y-279220D01*
X641387Y-279194D01*
Y-279161D01*
X641383Y-279125D01*
X641379Y-279085D01*
X641368Y-278997D01*
X641350Y-278903D01*
X641328Y-278808D01*
X641299Y-278713D01*
Y-278710D01*
X641295Y-278703D01*
X641288Y-278692D01*
X641281Y-278674D01*
X641259Y-278630D01*
X641226Y-278579D01*
X641186Y-278521D01*
X641135Y-278459D01*
X641077Y-278404D01*
X641008Y-278353D01*
X641004D01*
X640997Y-278349D01*
X640986Y-278342D01*
X640972Y-278335D01*
X640953Y-278328D01*
X640932Y-278317D01*
X640881Y-278295D01*
X640815Y-278273D01*
X640742Y-278255D01*
X640662Y-278240D01*
X640578Y-278237D01*
X640553D01*
X640531Y-278240D01*
X640506D01*
X640480Y-278244D01*
X640415Y-278258D01*
X640338Y-278277D01*
X640262Y-278306D01*
X640182Y-278346D01*
X640142Y-278368D01*
X640105Y-278397D01*
X640102Y-278400D01*
X640098Y-278404D01*
X640087Y-278415D01*
X640072Y-278426D01*
X640058Y-278444D01*
X640040Y-278466D01*
X640018Y-278488D01*
X640000Y-278517D01*
X639978Y-278550D01*
X639952Y-278586D01*
X639930Y-278623D01*
X639909Y-278666D01*
X639890Y-278713D01*
X639872Y-278764D01*
X639854Y-278819D01*
X639840Y-278877D01*
X639505Y-278794D01*
Y-278790D01*
X639508Y-278775D01*
X639516Y-278753D01*
X639527Y-278724D01*
X639537Y-278692D01*
X639552Y-278652D01*
X639570Y-278608D01*
X639592Y-278561D01*
X639643Y-278459D01*
X639709Y-278357D01*
X639748Y-278306D01*
X639789Y-278255D01*
X639832Y-278211D01*
X639883Y-278168D01*
X639887Y-278164D01*
X639894Y-278157D01*
X639912Y-278149D01*
X639930Y-278135D01*
X639960Y-278116D01*
X639989Y-278098D01*
X640029Y-278080D01*
X640069Y-278062D01*
X640116Y-278040D01*
X640167Y-278022D01*
X640222Y-278004D01*
X640280Y-277986D01*
X640342Y-277971D01*
X640407Y-277964D01*
X640477Y-277956D01*
X640549Y-277953D01*
X640589D01*
X640619Y-277956D01*
D02*
G37*
G36*
X638456D02*
X638489Y-277960D01*
X638525Y-277964D01*
X638565Y-277971D01*
X638609Y-277982D01*
X638707Y-278007D01*
X638758Y-278026D01*
X638806Y-278044D01*
X638857Y-278069D01*
X638908Y-278098D01*
X638955Y-278131D01*
X638999Y-278171D01*
X639002Y-278175D01*
X639010Y-278182D01*
X639020Y-278193D01*
X639035Y-278211D01*
X639050Y-278233D01*
X639072Y-278258D01*
X639090Y-278288D01*
X639112Y-278324D01*
X639133Y-278360D01*
X639152Y-278404D01*
X639188Y-278495D01*
X639202Y-278550D01*
X639214Y-278604D01*
X639221Y-278662D01*
X639224Y-278721D01*
Y-278724D01*
Y-278732D01*
Y-278746D01*
X639221Y-278761D01*
Y-278783D01*
X639217Y-278808D01*
X639210Y-278866D01*
X639195Y-278932D01*
X639173Y-278997D01*
X639141Y-279067D01*
X639101Y-279132D01*
Y-279136D01*
X639093Y-279139D01*
X639079Y-279158D01*
X639050Y-279187D01*
X639010Y-279223D01*
X638959Y-279259D01*
X638897Y-279299D01*
X638828Y-279332D01*
X638744Y-279358D01*
X638748D01*
X638751Y-279361D01*
X638762Y-279365D01*
X638777Y-279372D01*
X638809Y-279387D01*
X638853Y-279409D01*
X638900Y-279438D01*
X638948Y-279474D01*
X638991Y-279514D01*
X639032Y-279558D01*
X639035Y-279565D01*
X639046Y-279580D01*
X639061Y-279609D01*
X639075Y-279645D01*
X639093Y-279693D01*
X639108Y-279747D01*
X639119Y-279809D01*
X639122Y-279875D01*
Y-279878D01*
Y-279886D01*
Y-279900D01*
X639119Y-279922D01*
X639115Y-279944D01*
X639112Y-279973D01*
X639097Y-280035D01*
X639075Y-280108D01*
X639039Y-280184D01*
X639017Y-280224D01*
X638991Y-280264D01*
X638959Y-280300D01*
X638926Y-280337D01*
X638922Y-280341D01*
X638915Y-280344D01*
X638904Y-280355D01*
X638890Y-280366D01*
X638871Y-280381D01*
X638846Y-280395D01*
X638817Y-280413D01*
X638788Y-280432D01*
X638751Y-280450D01*
X638711Y-280468D01*
X638667Y-280483D01*
X638620Y-280497D01*
X638518Y-280519D01*
X638460Y-280523D01*
X638402Y-280526D01*
X638369D01*
X638347Y-280523D01*
X638318Y-280519D01*
X638285Y-280515D01*
X638249Y-280512D01*
X638212Y-280501D01*
X638125Y-280479D01*
X638038Y-280446D01*
X637994Y-280424D01*
X637950Y-280399D01*
X637910Y-280366D01*
X637870Y-280333D01*
X637867Y-280330D01*
X637863Y-280326D01*
X637852Y-280315D01*
X637838Y-280300D01*
X637823Y-280279D01*
X637805Y-280257D01*
X637768Y-280202D01*
X637732Y-280133D01*
X637699Y-280053D01*
X637674Y-279962D01*
X637670Y-279915D01*
X637666Y-279864D01*
Y-279860D01*
Y-279856D01*
Y-279835D01*
X637670Y-279802D01*
X637677Y-279762D01*
X637688Y-279711D01*
X637707Y-279660D01*
X637728Y-279609D01*
X637761Y-279558D01*
X637765Y-279551D01*
X637779Y-279536D01*
X637801Y-279514D01*
X637830Y-279485D01*
X637870Y-279452D01*
X637918Y-279420D01*
X637972Y-279387D01*
X638038Y-279358D01*
X638034D01*
X638027Y-279354D01*
X638016Y-279350D01*
X638001Y-279343D01*
X637958Y-279325D01*
X637907Y-279299D01*
X637852Y-279263D01*
X637794Y-279223D01*
X637739Y-279172D01*
X637688Y-279114D01*
Y-279110D01*
X637685Y-279107D01*
X637670Y-279085D01*
X637648Y-279048D01*
X637626Y-279001D01*
X637605Y-278943D01*
X637583Y-278874D01*
X637568Y-278797D01*
X637565Y-278713D01*
Y-278710D01*
Y-278699D01*
Y-278681D01*
X637568Y-278659D01*
X637572Y-278633D01*
X637575Y-278601D01*
X637583Y-278564D01*
X637594Y-278524D01*
X637619Y-278440D01*
X637637Y-278393D01*
X637663Y-278349D01*
X637688Y-278302D01*
X637717Y-278258D01*
X637754Y-278215D01*
X637794Y-278171D01*
X637797Y-278168D01*
X637805Y-278160D01*
X637816Y-278149D01*
X637834Y-278138D01*
X637859Y-278120D01*
X637885Y-278102D01*
X637918Y-278084D01*
X637954Y-278062D01*
X637994Y-278040D01*
X638041Y-278022D01*
X638092Y-278004D01*
X638143Y-277986D01*
X638202Y-277975D01*
X638263Y-277964D01*
X638325Y-277956D01*
X638394Y-277953D01*
X638431D01*
X638456Y-277956D01*
D02*
G37*
G36*
X665815Y-273775D02*
X665848Y-273779D01*
X665888Y-273783D01*
X665928Y-273786D01*
X665976Y-273797D01*
X666074Y-273819D01*
X666183Y-273852D01*
X666238Y-273874D01*
X666289Y-273899D01*
X666340Y-273932D01*
X666391Y-273965D01*
X666394Y-273968D01*
X666401Y-273972D01*
X666416Y-273983D01*
X666434Y-274001D01*
X666452Y-274019D01*
X666478Y-274045D01*
X666503Y-274074D01*
X666533Y-274103D01*
X666562Y-274139D01*
X666591Y-274183D01*
X666623Y-274227D01*
X666653Y-274274D01*
X666678Y-274329D01*
X666707Y-274383D01*
X666729Y-274442D01*
X666751Y-274507D01*
X666423Y-274584D01*
Y-274580D01*
X666420Y-274573D01*
X666412Y-274558D01*
X666405Y-274540D01*
X666398Y-274518D01*
X666387Y-274489D01*
X666358Y-274431D01*
X666321Y-274365D01*
X666278Y-274300D01*
X666223Y-274238D01*
X666165Y-274183D01*
X666158Y-274176D01*
X666136Y-274161D01*
X666099Y-274143D01*
X666052Y-274118D01*
X665990Y-274096D01*
X665921Y-274074D01*
X665837Y-274059D01*
X665746Y-274056D01*
X665717D01*
X665699Y-274059D01*
X665673D01*
X665644Y-274063D01*
X665575Y-274074D01*
X665499Y-274088D01*
X665419Y-274114D01*
X665335Y-274150D01*
X665259Y-274198D01*
X665255D01*
X665251Y-274205D01*
X665226Y-274223D01*
X665193Y-274252D01*
X665153Y-274296D01*
X665106Y-274351D01*
X665062Y-274412D01*
X665022Y-274489D01*
X664986Y-274573D01*
Y-274576D01*
X664982Y-274584D01*
X664978Y-274594D01*
X664975Y-274613D01*
X664967Y-274634D01*
X664960Y-274660D01*
X664949Y-274722D01*
X664934Y-274795D01*
X664920Y-274875D01*
X664913Y-274962D01*
X664909Y-275057D01*
Y-275060D01*
Y-275071D01*
Y-275089D01*
Y-275111D01*
X664913Y-275137D01*
Y-275169D01*
X664916Y-275206D01*
X664920Y-275246D01*
X664931Y-275333D01*
X664949Y-275428D01*
X664971Y-275523D01*
X665000Y-275617D01*
Y-275621D01*
X665004Y-275628D01*
X665011Y-275639D01*
X665018Y-275657D01*
X665040Y-275701D01*
X665073Y-275752D01*
X665113Y-275810D01*
X665164Y-275872D01*
X665222Y-275927D01*
X665291Y-275978D01*
X665295D01*
X665302Y-275981D01*
X665313Y-275989D01*
X665328Y-275996D01*
X665346Y-276003D01*
X665368Y-276014D01*
X665419Y-276036D01*
X665484Y-276058D01*
X665557Y-276076D01*
X665637Y-276090D01*
X665721Y-276094D01*
X665746D01*
X665768Y-276090D01*
X665794D01*
X665819Y-276087D01*
X665885Y-276072D01*
X665961Y-276054D01*
X666037Y-276025D01*
X666117Y-275985D01*
X666158Y-275963D01*
X666194Y-275934D01*
X666198Y-275930D01*
X666201Y-275927D01*
X666212Y-275916D01*
X666227Y-275905D01*
X666241Y-275887D01*
X666259Y-275865D01*
X666281Y-275843D01*
X666299Y-275814D01*
X666321Y-275781D01*
X666347Y-275745D01*
X666369Y-275708D01*
X666391Y-275665D01*
X666409Y-275617D01*
X666427Y-275566D01*
X666445Y-275512D01*
X666460Y-275453D01*
X666795Y-275537D01*
Y-275541D01*
X666791Y-275555D01*
X666784Y-275577D01*
X666773Y-275606D01*
X666762Y-275639D01*
X666747Y-275679D01*
X666729Y-275723D01*
X666707Y-275770D01*
X666656Y-275872D01*
X666591Y-275974D01*
X666551Y-276025D01*
X666511Y-276076D01*
X666467Y-276120D01*
X666416Y-276163D01*
X666412Y-276167D01*
X666405Y-276174D01*
X666387Y-276181D01*
X666369Y-276196D01*
X666340Y-276214D01*
X666310Y-276232D01*
X666270Y-276251D01*
X666230Y-276269D01*
X666183Y-276291D01*
X666132Y-276309D01*
X666078Y-276327D01*
X666019Y-276345D01*
X665957Y-276360D01*
X665892Y-276367D01*
X665823Y-276374D01*
X665750Y-276378D01*
X665710D01*
X665681Y-276374D01*
X665648D01*
X665608Y-276371D01*
X665564Y-276363D01*
X665513Y-276356D01*
X665408Y-276338D01*
X665299Y-276309D01*
X665189Y-276269D01*
X665138Y-276243D01*
X665087Y-276214D01*
X665084Y-276211D01*
X665076Y-276207D01*
X665062Y-276196D01*
X665047Y-276181D01*
X665026Y-276167D01*
X665000Y-276145D01*
X664971Y-276120D01*
X664942Y-276090D01*
X664913Y-276058D01*
X664880Y-276025D01*
X664814Y-275941D01*
X664752Y-275843D01*
X664698Y-275734D01*
Y-275730D01*
X664691Y-275719D01*
X664687Y-275701D01*
X664676Y-275679D01*
X664669Y-275650D01*
X664658Y-275614D01*
X664643Y-275574D01*
X664632Y-275530D01*
X664621Y-275483D01*
X664607Y-275428D01*
X664589Y-275315D01*
X664574Y-275188D01*
X664567Y-275057D01*
Y-275053D01*
Y-275039D01*
Y-275017D01*
X664571Y-274991D01*
Y-274955D01*
X664574Y-274918D01*
X664578Y-274871D01*
X664585Y-274824D01*
X664603Y-274718D01*
X664629Y-274602D01*
X664665Y-274485D01*
X664716Y-274372D01*
X664720Y-274369D01*
X664723Y-274358D01*
X664731Y-274343D01*
X664745Y-274325D01*
X664760Y-274300D01*
X664778Y-274270D01*
X664825Y-274205D01*
X664887Y-274132D01*
X664960Y-274059D01*
X665044Y-273987D01*
X665142Y-273925D01*
X665146Y-273921D01*
X665157Y-273917D01*
X665171Y-273910D01*
X665189Y-273899D01*
X665218Y-273888D01*
X665248Y-273877D01*
X665284Y-273863D01*
X665324Y-273848D01*
X665368Y-273834D01*
X665415Y-273819D01*
X665517Y-273797D01*
X665633Y-273779D01*
X665754Y-273772D01*
X665790D01*
X665815Y-273775D01*
D02*
G37*
G36*
X669932Y-273808D02*
X669961Y-273812D01*
X669998Y-273815D01*
X670038Y-273823D01*
X670078Y-273830D01*
X670173Y-273855D01*
X670267Y-273892D01*
X670314Y-273914D01*
X670362Y-273939D01*
X670405Y-273972D01*
X670445Y-274008D01*
X670449Y-274012D01*
X670456Y-274016D01*
X670464Y-274030D01*
X670478Y-274045D01*
X670496Y-274063D01*
X670515Y-274088D01*
X670533Y-274114D01*
X670555Y-274147D01*
X670591Y-274216D01*
X670627Y-274303D01*
X670642Y-274347D01*
X670649Y-274398D01*
X670657Y-274449D01*
X670660Y-274503D01*
Y-274511D01*
Y-274529D01*
X670657Y-274558D01*
X670653Y-274598D01*
X670646Y-274642D01*
X670631Y-274693D01*
X670617Y-274747D01*
X670595Y-274802D01*
X670591Y-274809D01*
X670584Y-274827D01*
X670569Y-274856D01*
X670547Y-274897D01*
X670518Y-274940D01*
X670482Y-274995D01*
X670438Y-275049D01*
X670387Y-275111D01*
X670380Y-275119D01*
X670362Y-275140D01*
X670344Y-275159D01*
X670325Y-275177D01*
X670303Y-275199D01*
X670274Y-275228D01*
X670245Y-275257D01*
X670209Y-275290D01*
X670173Y-275326D01*
X670129Y-275366D01*
X670082Y-275406D01*
X670030Y-275453D01*
X669972Y-275501D01*
X669914Y-275552D01*
X669910Y-275555D01*
X669903Y-275563D01*
X669889Y-275574D01*
X669870Y-275588D01*
X669848Y-275610D01*
X669823Y-275632D01*
X669765Y-275679D01*
X669703Y-275734D01*
X669645Y-275788D01*
X669594Y-275836D01*
X669572Y-275854D01*
X669554Y-275872D01*
X669550Y-275876D01*
X669539Y-275887D01*
X669525Y-275901D01*
X669506Y-275923D01*
X669488Y-275949D01*
X669466Y-275974D01*
X669423Y-276036D01*
X670664D01*
Y-276334D01*
X668993D01*
Y-276331D01*
Y-276316D01*
Y-276294D01*
X668997Y-276265D01*
X669000Y-276232D01*
X669008Y-276196D01*
X669015Y-276160D01*
X669030Y-276120D01*
Y-276116D01*
X669033Y-276112D01*
X669040Y-276090D01*
X669055Y-276058D01*
X669077Y-276014D01*
X669106Y-275963D01*
X669142Y-275905D01*
X669182Y-275847D01*
X669233Y-275785D01*
Y-275781D01*
X669241Y-275777D01*
X669259Y-275756D01*
X669292Y-275723D01*
X669339Y-275676D01*
X669393Y-275621D01*
X669463Y-275555D01*
X669546Y-275483D01*
X669637Y-275406D01*
X669641Y-275402D01*
X669656Y-275392D01*
X669677Y-275373D01*
X669703Y-275352D01*
X669736Y-275322D01*
X669776Y-275290D01*
X669816Y-275253D01*
X669863Y-275213D01*
X669954Y-275126D01*
X670045Y-275039D01*
X670089Y-274995D01*
X670129Y-274951D01*
X670165Y-274911D01*
X670194Y-274871D01*
Y-274867D01*
X670202Y-274864D01*
X670209Y-274853D01*
X670216Y-274838D01*
X670242Y-274798D01*
X670271Y-274751D01*
X670296Y-274693D01*
X670322Y-274631D01*
X670336Y-274562D01*
X670344Y-274496D01*
Y-274493D01*
Y-274489D01*
X670340Y-274467D01*
X670336Y-274431D01*
X670325Y-274391D01*
X670311Y-274340D01*
X670285Y-274289D01*
X670253Y-274238D01*
X670209Y-274187D01*
X670202Y-274179D01*
X670183Y-274165D01*
X670158Y-274147D01*
X670118Y-274121D01*
X670067Y-274099D01*
X670009Y-274078D01*
X669940Y-274063D01*
X669863Y-274059D01*
X669841D01*
X669827Y-274063D01*
X669783Y-274067D01*
X669732Y-274078D01*
X669677Y-274092D01*
X669616Y-274118D01*
X669557Y-274150D01*
X669503Y-274194D01*
X669495Y-274201D01*
X669481Y-274219D01*
X669459Y-274249D01*
X669437Y-274292D01*
X669412Y-274343D01*
X669390Y-274409D01*
X669375Y-274482D01*
X669368Y-274565D01*
X669051Y-274533D01*
Y-274529D01*
X669055Y-274518D01*
Y-274500D01*
X669059Y-274474D01*
X669066Y-274445D01*
X669073Y-274412D01*
X669084Y-274372D01*
X669095Y-274332D01*
X669124Y-274245D01*
X669168Y-274158D01*
X669193Y-274114D01*
X669226Y-274070D01*
X669259Y-274030D01*
X669295Y-273994D01*
X669299Y-273990D01*
X669306Y-273987D01*
X669317Y-273976D01*
X669335Y-273965D01*
X669357Y-273950D01*
X669383Y-273936D01*
X669412Y-273917D01*
X669448Y-273899D01*
X669488Y-273881D01*
X669532Y-273863D01*
X669579Y-273848D01*
X669630Y-273834D01*
X669685Y-273823D01*
X669743Y-273812D01*
X669805Y-273808D01*
X669870Y-273804D01*
X669907D01*
X669932Y-273808D01*
D02*
G37*
G36*
X667952D02*
X667981Y-273812D01*
X668014Y-273815D01*
X668050Y-273819D01*
X668087Y-273830D01*
X668174Y-273852D01*
X668261Y-273885D01*
X668305Y-273906D01*
X668349Y-273932D01*
X668389Y-273965D01*
X668429Y-273997D01*
X668433Y-274001D01*
X668436Y-274005D01*
X668447Y-274016D01*
X668462Y-274030D01*
X668476Y-274052D01*
X668494Y-274074D01*
X668531Y-274129D01*
X668567Y-274198D01*
X668600Y-274278D01*
X668625Y-274369D01*
X668629Y-274416D01*
X668633Y-274467D01*
Y-274471D01*
Y-274474D01*
Y-274496D01*
X668629Y-274529D01*
X668622Y-274569D01*
X668611Y-274620D01*
X668593Y-274671D01*
X668571Y-274722D01*
X668538Y-274773D01*
X668535Y-274780D01*
X668520Y-274795D01*
X668498Y-274816D01*
X668469Y-274846D01*
X668429Y-274878D01*
X668382Y-274911D01*
X668327Y-274944D01*
X668261Y-274973D01*
X668265D01*
X668272Y-274977D01*
X668283Y-274980D01*
X668298Y-274988D01*
X668342Y-275006D01*
X668393Y-275031D01*
X668447Y-275068D01*
X668505Y-275108D01*
X668560Y-275159D01*
X668611Y-275217D01*
Y-275220D01*
X668615Y-275224D01*
X668629Y-275246D01*
X668651Y-275282D01*
X668673Y-275330D01*
X668695Y-275388D01*
X668716Y-275457D01*
X668731Y-275534D01*
X668735Y-275617D01*
Y-275621D01*
Y-275632D01*
Y-275650D01*
X668731Y-275672D01*
X668727Y-275697D01*
X668724Y-275730D01*
X668716Y-275766D01*
X668706Y-275806D01*
X668680Y-275890D01*
X668662Y-275938D01*
X668636Y-275981D01*
X668611Y-276029D01*
X668582Y-276072D01*
X668545Y-276116D01*
X668505Y-276160D01*
X668502Y-276163D01*
X668494Y-276170D01*
X668483Y-276181D01*
X668465Y-276192D01*
X668440Y-276211D01*
X668414Y-276229D01*
X668382Y-276247D01*
X668345Y-276269D01*
X668305Y-276291D01*
X668258Y-276309D01*
X668207Y-276327D01*
X668156Y-276345D01*
X668098Y-276356D01*
X668036Y-276367D01*
X667974Y-276374D01*
X667905Y-276378D01*
X667868D01*
X667843Y-276374D01*
X667810Y-276371D01*
X667774Y-276367D01*
X667734Y-276360D01*
X667690Y-276349D01*
X667592Y-276323D01*
X667541Y-276305D01*
X667493Y-276287D01*
X667443Y-276261D01*
X667391Y-276232D01*
X667344Y-276200D01*
X667301Y-276160D01*
X667297Y-276156D01*
X667290Y-276149D01*
X667279Y-276138D01*
X667264Y-276120D01*
X667250Y-276098D01*
X667228Y-276072D01*
X667209Y-276043D01*
X667188Y-276007D01*
X667166Y-275970D01*
X667148Y-275927D01*
X667111Y-275836D01*
X667097Y-275781D01*
X667086Y-275726D01*
X667078Y-275668D01*
X667075Y-275610D01*
Y-275606D01*
Y-275599D01*
Y-275585D01*
X667078Y-275570D01*
Y-275548D01*
X667082Y-275523D01*
X667089Y-275464D01*
X667104Y-275399D01*
X667126Y-275333D01*
X667159Y-275264D01*
X667199Y-275199D01*
Y-275195D01*
X667206Y-275191D01*
X667220Y-275173D01*
X667250Y-275144D01*
X667290Y-275108D01*
X667341Y-275071D01*
X667402Y-275031D01*
X667472Y-274998D01*
X667555Y-274973D01*
X667552D01*
X667548Y-274969D01*
X667537Y-274966D01*
X667523Y-274958D01*
X667490Y-274944D01*
X667446Y-274922D01*
X667399Y-274893D01*
X667351Y-274856D01*
X667308Y-274816D01*
X667268Y-274773D01*
X667264Y-274765D01*
X667253Y-274751D01*
X667239Y-274722D01*
X667224Y-274685D01*
X667206Y-274638D01*
X667191Y-274584D01*
X667180Y-274522D01*
X667177Y-274456D01*
Y-274452D01*
Y-274445D01*
Y-274431D01*
X667180Y-274409D01*
X667184Y-274387D01*
X667188Y-274358D01*
X667202Y-274296D01*
X667224Y-274223D01*
X667261Y-274147D01*
X667282Y-274107D01*
X667308Y-274067D01*
X667341Y-274030D01*
X667373Y-273994D01*
X667377Y-273990D01*
X667384Y-273987D01*
X667395Y-273976D01*
X667410Y-273965D01*
X667428Y-273950D01*
X667453Y-273936D01*
X667483Y-273917D01*
X667512Y-273899D01*
X667548Y-273881D01*
X667588Y-273863D01*
X667632Y-273848D01*
X667679Y-273834D01*
X667781Y-273812D01*
X667839Y-273808D01*
X667898Y-273804D01*
X667930D01*
X667952Y-273808D01*
D02*
G37*
G36*
X666629Y-249700D02*
X666661Y-249704D01*
X666701Y-249708D01*
X666741Y-249711D01*
X666789Y-249722D01*
X666887Y-249744D01*
X666996Y-249777D01*
X667051Y-249798D01*
X667102Y-249824D01*
X667153Y-249857D01*
X667204Y-249889D01*
X667207Y-249893D01*
X667214Y-249897D01*
X667229Y-249908D01*
X667247Y-249926D01*
X667266Y-249944D01*
X667291Y-249970D01*
X667316Y-249999D01*
X667346Y-250028D01*
X667375Y-250064D01*
X667404Y-250108D01*
X667437Y-250152D01*
X667466Y-250199D01*
X667491Y-250254D01*
X667520Y-250308D01*
X667542Y-250366D01*
X667564Y-250432D01*
X667236Y-250508D01*
Y-250505D01*
X667233Y-250497D01*
X667225Y-250483D01*
X667218Y-250465D01*
X667211Y-250443D01*
X667200Y-250414D01*
X667171Y-250355D01*
X667134Y-250290D01*
X667091Y-250224D01*
X667036Y-250163D01*
X666978Y-250108D01*
X666971Y-250101D01*
X666949Y-250086D01*
X666912Y-250068D01*
X666865Y-250042D01*
X666803Y-250021D01*
X666734Y-249999D01*
X666650Y-249984D01*
X666559Y-249980D01*
X666530D01*
X666512Y-249984D01*
X666487D01*
X666457Y-249988D01*
X666388Y-249999D01*
X666312Y-250013D01*
X666232Y-250039D01*
X666148Y-250075D01*
X666072Y-250122D01*
X666068D01*
X666064Y-250130D01*
X666039Y-250148D01*
X666006Y-250177D01*
X665966Y-250221D01*
X665919Y-250275D01*
X665875Y-250337D01*
X665835Y-250414D01*
X665799Y-250497D01*
Y-250501D01*
X665795Y-250508D01*
X665791Y-250519D01*
X665788Y-250537D01*
X665780Y-250559D01*
X665773Y-250585D01*
X665762Y-250647D01*
X665748Y-250719D01*
X665733Y-250799D01*
X665726Y-250887D01*
X665722Y-250981D01*
Y-250985D01*
Y-250996D01*
Y-251014D01*
Y-251036D01*
X665726Y-251062D01*
Y-251094D01*
X665729Y-251131D01*
X665733Y-251171D01*
X665744Y-251258D01*
X665762Y-251353D01*
X665784Y-251447D01*
X665813Y-251542D01*
Y-251546D01*
X665817Y-251553D01*
X665824Y-251564D01*
X665831Y-251582D01*
X665853Y-251626D01*
X665886Y-251677D01*
X665926Y-251735D01*
X665977Y-251797D01*
X666035Y-251852D01*
X666104Y-251902D01*
X666108D01*
X666115Y-251906D01*
X666126Y-251913D01*
X666141Y-251921D01*
X666159Y-251928D01*
X666181Y-251939D01*
X666232Y-251961D01*
X666297Y-251982D01*
X666370Y-252001D01*
X666450Y-252015D01*
X666534Y-252019D01*
X666559D01*
X666581Y-252015D01*
X666607D01*
X666632Y-252012D01*
X666698Y-251997D01*
X666774Y-251979D01*
X666851Y-251950D01*
X666931Y-251910D01*
X666971Y-251888D01*
X667007Y-251859D01*
X667011Y-251855D01*
X667014Y-251852D01*
X667025Y-251840D01*
X667040Y-251830D01*
X667054Y-251811D01*
X667072Y-251790D01*
X667094Y-251768D01*
X667113Y-251739D01*
X667134Y-251706D01*
X667160Y-251670D01*
X667182Y-251633D01*
X667204Y-251589D01*
X667222Y-251542D01*
X667240Y-251491D01*
X667258Y-251436D01*
X667273Y-251378D01*
X667608Y-251462D01*
Y-251466D01*
X667604Y-251480D01*
X667597Y-251502D01*
X667586Y-251531D01*
X667575Y-251564D01*
X667560Y-251604D01*
X667542Y-251648D01*
X667520Y-251695D01*
X667469Y-251797D01*
X667404Y-251899D01*
X667364Y-251950D01*
X667324Y-252001D01*
X667280Y-252044D01*
X667229Y-252088D01*
X667225Y-252092D01*
X667218Y-252099D01*
X667200Y-252106D01*
X667182Y-252121D01*
X667153Y-252139D01*
X667124Y-252157D01*
X667084Y-252175D01*
X667043Y-252194D01*
X666996Y-252216D01*
X666945Y-252234D01*
X666890Y-252252D01*
X666832Y-252270D01*
X666770Y-252285D01*
X666705Y-252292D01*
X666636Y-252299D01*
X666563Y-252303D01*
X666523D01*
X666494Y-252299D01*
X666461D01*
X666421Y-252295D01*
X666377Y-252288D01*
X666326Y-252281D01*
X666221Y-252263D01*
X666112Y-252234D01*
X666002Y-252194D01*
X665951Y-252168D01*
X665901Y-252139D01*
X665897Y-252135D01*
X665890Y-252132D01*
X665875Y-252121D01*
X665860Y-252106D01*
X665839Y-252092D01*
X665813Y-252070D01*
X665784Y-252044D01*
X665755Y-252015D01*
X665726Y-251982D01*
X665693Y-251950D01*
X665627Y-251866D01*
X665566Y-251768D01*
X665511Y-251659D01*
Y-251655D01*
X665504Y-251644D01*
X665500Y-251626D01*
X665489Y-251604D01*
X665482Y-251575D01*
X665471Y-251538D01*
X665456Y-251498D01*
X665446Y-251455D01*
X665435Y-251407D01*
X665420Y-251353D01*
X665402Y-251240D01*
X665387Y-251113D01*
X665380Y-250981D01*
Y-250978D01*
Y-250963D01*
Y-250941D01*
X665384Y-250916D01*
Y-250880D01*
X665387Y-250843D01*
X665391Y-250796D01*
X665398Y-250748D01*
X665416Y-250643D01*
X665442Y-250526D01*
X665478Y-250410D01*
X665529Y-250297D01*
X665533Y-250293D01*
X665536Y-250283D01*
X665544Y-250268D01*
X665558Y-250250D01*
X665573Y-250224D01*
X665591Y-250195D01*
X665638Y-250130D01*
X665700Y-250057D01*
X665773Y-249984D01*
X665857Y-249911D01*
X665955Y-249849D01*
X665959Y-249846D01*
X665970Y-249842D01*
X665984Y-249835D01*
X666002Y-249824D01*
X666032Y-249813D01*
X666061Y-249802D01*
X666097Y-249788D01*
X666137Y-249773D01*
X666181Y-249758D01*
X666228Y-249744D01*
X666330Y-249722D01*
X666446Y-249704D01*
X666567Y-249697D01*
X666603D01*
X666629Y-249700D01*
D02*
G37*
G36*
X671015Y-252259D02*
X670705D01*
Y-250290D01*
X670702Y-250293D01*
X670683Y-250308D01*
X670662Y-250330D01*
X670625Y-250355D01*
X670585Y-250388D01*
X670534Y-250425D01*
X670476Y-250465D01*
X670410Y-250505D01*
X670407D01*
X670403Y-250508D01*
X670381Y-250523D01*
X670345Y-250541D01*
X670301Y-250563D01*
X670250Y-250588D01*
X670196Y-250614D01*
X670141Y-250639D01*
X670086Y-250661D01*
Y-250363D01*
X670090D01*
X670097Y-250355D01*
X670112Y-250352D01*
X670130Y-250341D01*
X670152Y-250330D01*
X670178Y-250315D01*
X670239Y-250279D01*
X670312Y-250239D01*
X670385Y-250188D01*
X670461Y-250130D01*
X670538Y-250068D01*
X670541Y-250064D01*
X670545Y-250061D01*
X670556Y-250050D01*
X670571Y-250039D01*
X670603Y-250002D01*
X670647Y-249959D01*
X670691Y-249908D01*
X670738Y-249849D01*
X670778Y-249791D01*
X670815Y-249729D01*
X671015D01*
Y-252259D01*
D02*
G37*
G36*
X668765Y-249733D02*
X668794Y-249737D01*
X668827Y-249740D01*
X668863Y-249744D01*
X668900Y-249755D01*
X668987Y-249777D01*
X669074Y-249809D01*
X669118Y-249831D01*
X669162Y-249857D01*
X669202Y-249889D01*
X669242Y-249922D01*
X669246Y-249926D01*
X669249Y-249929D01*
X669260Y-249940D01*
X669275Y-249955D01*
X669289Y-249977D01*
X669308Y-249999D01*
X669344Y-250053D01*
X669380Y-250122D01*
X669413Y-250202D01*
X669439Y-250293D01*
X669442Y-250341D01*
X669446Y-250392D01*
Y-250395D01*
Y-250399D01*
Y-250421D01*
X669442Y-250454D01*
X669435Y-250494D01*
X669424Y-250545D01*
X669406Y-250596D01*
X669384Y-250647D01*
X669351Y-250698D01*
X669347Y-250705D01*
X669333Y-250719D01*
X669311Y-250741D01*
X669282Y-250770D01*
X669242Y-250803D01*
X669195Y-250836D01*
X669140Y-250869D01*
X669074Y-250898D01*
X669078D01*
X669086Y-250901D01*
X669096Y-250905D01*
X669111Y-250912D01*
X669155Y-250931D01*
X669206Y-250956D01*
X669260Y-250992D01*
X669318Y-251032D01*
X669373Y-251083D01*
X669424Y-251142D01*
Y-251145D01*
X669428Y-251149D01*
X669442Y-251171D01*
X669464Y-251207D01*
X669486Y-251255D01*
X669508Y-251313D01*
X669529Y-251382D01*
X669544Y-251458D01*
X669548Y-251542D01*
Y-251546D01*
Y-251557D01*
Y-251575D01*
X669544Y-251597D01*
X669541Y-251622D01*
X669537Y-251655D01*
X669529Y-251691D01*
X669519Y-251731D01*
X669493Y-251815D01*
X669475Y-251862D01*
X669450Y-251906D01*
X669424Y-251953D01*
X669395Y-251997D01*
X669358Y-252041D01*
X669318Y-252084D01*
X669315Y-252088D01*
X669308Y-252095D01*
X669297Y-252106D01*
X669278Y-252117D01*
X669253Y-252135D01*
X669227Y-252154D01*
X669195Y-252172D01*
X669158Y-252194D01*
X669118Y-252216D01*
X669071Y-252234D01*
X669020Y-252252D01*
X668969Y-252270D01*
X668911Y-252281D01*
X668849Y-252292D01*
X668787Y-252299D01*
X668718Y-252303D01*
X668681D01*
X668656Y-252299D01*
X668623Y-252295D01*
X668587Y-252292D01*
X668547Y-252285D01*
X668503Y-252274D01*
X668405Y-252248D01*
X668354Y-252230D01*
X668306Y-252212D01*
X668256Y-252186D01*
X668205Y-252157D01*
X668157Y-252124D01*
X668114Y-252084D01*
X668110Y-252081D01*
X668103Y-252074D01*
X668092Y-252063D01*
X668077Y-252044D01*
X668063Y-252023D01*
X668041Y-251997D01*
X668023Y-251968D01*
X668001Y-251932D01*
X667979Y-251895D01*
X667961Y-251852D01*
X667924Y-251760D01*
X667910Y-251706D01*
X667899Y-251651D01*
X667892Y-251593D01*
X667888Y-251535D01*
Y-251531D01*
Y-251524D01*
Y-251509D01*
X667892Y-251495D01*
Y-251473D01*
X667895Y-251447D01*
X667903Y-251389D01*
X667917Y-251324D01*
X667939Y-251258D01*
X667972Y-251189D01*
X668012Y-251123D01*
Y-251120D01*
X668019Y-251116D01*
X668034Y-251098D01*
X668063Y-251069D01*
X668103Y-251032D01*
X668154Y-250996D01*
X668216Y-250956D01*
X668285Y-250923D01*
X668368Y-250898D01*
X668365D01*
X668361Y-250894D01*
X668350Y-250890D01*
X668336Y-250883D01*
X668303Y-250869D01*
X668259Y-250847D01*
X668212Y-250818D01*
X668164Y-250781D01*
X668121Y-250741D01*
X668081Y-250698D01*
X668077Y-250690D01*
X668066Y-250676D01*
X668052Y-250647D01*
X668037Y-250610D01*
X668019Y-250563D01*
X668004Y-250508D01*
X667993Y-250446D01*
X667990Y-250381D01*
Y-250377D01*
Y-250370D01*
Y-250355D01*
X667993Y-250334D01*
X667997Y-250312D01*
X668001Y-250283D01*
X668015Y-250221D01*
X668037Y-250148D01*
X668074Y-250072D01*
X668095Y-250031D01*
X668121Y-249991D01*
X668154Y-249955D01*
X668186Y-249919D01*
X668190Y-249915D01*
X668197Y-249911D01*
X668208Y-249900D01*
X668223Y-249889D01*
X668241Y-249875D01*
X668266Y-249860D01*
X668296Y-249842D01*
X668325Y-249824D01*
X668361Y-249806D01*
X668401Y-249788D01*
X668445Y-249773D01*
X668492Y-249758D01*
X668594Y-249737D01*
X668652Y-249733D01*
X668711Y-249729D01*
X668743D01*
X668765Y-249733D01*
D02*
G37*
G36*
X666603Y-257634D02*
X666636Y-257637D01*
X666676Y-257641D01*
X666716Y-257645D01*
X666763Y-257656D01*
X666861Y-257677D01*
X666970Y-257710D01*
X667025Y-257732D01*
X667076Y-257757D01*
X667127Y-257790D01*
X667178Y-257823D01*
X667182Y-257827D01*
X667189Y-257830D01*
X667203Y-257841D01*
X667222Y-257859D01*
X667240Y-257878D01*
X667265Y-257903D01*
X667291Y-257932D01*
X667320Y-257961D01*
X667349Y-257998D01*
X667378Y-258041D01*
X667411Y-258085D01*
X667440Y-258132D01*
X667465Y-258187D01*
X667495Y-258242D01*
X667516Y-258300D01*
X667538Y-258365D01*
X667211Y-258442D01*
Y-258438D01*
X667207Y-258431D01*
X667200Y-258416D01*
X667193Y-258398D01*
X667185Y-258376D01*
X667174Y-258347D01*
X667145Y-258289D01*
X667109Y-258223D01*
X667065Y-258158D01*
X667010Y-258096D01*
X666952Y-258041D01*
X666945Y-258034D01*
X666923Y-258019D01*
X666887Y-258001D01*
X666839Y-257976D01*
X666778Y-257954D01*
X666708Y-257932D01*
X666625Y-257918D01*
X666534Y-257914D01*
X666504D01*
X666486Y-257918D01*
X666461D01*
X666432Y-257921D01*
X666363Y-257932D01*
X666286Y-257947D01*
X666206Y-257972D01*
X666122Y-258009D01*
X666046Y-258056D01*
X666042D01*
X666039Y-258063D01*
X666013Y-258081D01*
X665980Y-258110D01*
X665940Y-258154D01*
X665893Y-258209D01*
X665849Y-258271D01*
X665809Y-258347D01*
X665773Y-258431D01*
Y-258435D01*
X665769Y-258442D01*
X665766Y-258453D01*
X665762Y-258471D01*
X665755Y-258493D01*
X665747Y-258518D01*
X665736Y-258580D01*
X665722Y-258653D01*
X665707Y-258733D01*
X665700Y-258820D01*
X665696Y-258915D01*
Y-258919D01*
Y-258929D01*
Y-258948D01*
Y-258969D01*
X665700Y-258995D01*
Y-259028D01*
X665704Y-259064D01*
X665707Y-259104D01*
X665718Y-259192D01*
X665736Y-259286D01*
X665758Y-259381D01*
X665787Y-259475D01*
Y-259479D01*
X665791Y-259486D01*
X665798Y-259497D01*
X665806Y-259516D01*
X665828Y-259559D01*
X665860Y-259610D01*
X665900Y-259668D01*
X665951Y-259730D01*
X666010Y-259785D01*
X666079Y-259836D01*
X666082D01*
X666090Y-259840D01*
X666101Y-259847D01*
X666115Y-259854D01*
X666133Y-259861D01*
X666155Y-259872D01*
X666206Y-259894D01*
X666272Y-259916D01*
X666344Y-259934D01*
X666424Y-259949D01*
X666508Y-259952D01*
X666534D01*
X666556Y-259949D01*
X666581D01*
X666606Y-259945D01*
X666672Y-259930D01*
X666748Y-259912D01*
X666825Y-259883D01*
X666905Y-259843D01*
X666945Y-259821D01*
X666981Y-259792D01*
X666985Y-259788D01*
X666989Y-259785D01*
X667000Y-259774D01*
X667014Y-259763D01*
X667029Y-259745D01*
X667047Y-259723D01*
X667069Y-259701D01*
X667087Y-259672D01*
X667109Y-259639D01*
X667134Y-259603D01*
X667156Y-259566D01*
X667178Y-259523D01*
X667196Y-259475D01*
X667214Y-259424D01*
X667233Y-259370D01*
X667247Y-259312D01*
X667582Y-259395D01*
Y-259399D01*
X667578Y-259414D01*
X667571Y-259436D01*
X667560Y-259465D01*
X667549Y-259497D01*
X667535Y-259537D01*
X667516Y-259581D01*
X667495Y-259628D01*
X667444Y-259730D01*
X667378Y-259832D01*
X667338Y-259883D01*
X667298Y-259934D01*
X667254Y-259978D01*
X667203Y-260021D01*
X667200Y-260025D01*
X667193Y-260032D01*
X667174Y-260040D01*
X667156Y-260054D01*
X667127Y-260072D01*
X667098Y-260091D01*
X667058Y-260109D01*
X667018Y-260127D01*
X666970Y-260149D01*
X666920Y-260167D01*
X666865Y-260185D01*
X666807Y-260204D01*
X666745Y-260218D01*
X666679Y-260225D01*
X666610Y-260233D01*
X666537Y-260236D01*
X666497D01*
X666468Y-260233D01*
X666435D01*
X666395Y-260229D01*
X666352Y-260222D01*
X666301Y-260214D01*
X666195Y-260196D01*
X666086Y-260167D01*
X665977Y-260127D01*
X665926Y-260102D01*
X665875Y-260072D01*
X665871Y-260069D01*
X665864Y-260065D01*
X665849Y-260054D01*
X665835Y-260040D01*
X665813Y-260025D01*
X665787Y-260003D01*
X665758Y-259978D01*
X665729Y-259949D01*
X665700Y-259916D01*
X665667Y-259883D01*
X665602Y-259800D01*
X665540Y-259701D01*
X665485Y-259592D01*
Y-259588D01*
X665478Y-259577D01*
X665474Y-259559D01*
X665463Y-259537D01*
X665456Y-259508D01*
X665445Y-259472D01*
X665431Y-259432D01*
X665420Y-259388D01*
X665409Y-259341D01*
X665394Y-259286D01*
X665376Y-259173D01*
X665362Y-259046D01*
X665354Y-258915D01*
Y-258911D01*
Y-258897D01*
Y-258875D01*
X665358Y-258849D01*
Y-258813D01*
X665362Y-258777D01*
X665365Y-258729D01*
X665373Y-258682D01*
X665391Y-258576D01*
X665416Y-258460D01*
X665453Y-258344D01*
X665504Y-258231D01*
X665507Y-258227D01*
X665511Y-258216D01*
X665518Y-258202D01*
X665533Y-258183D01*
X665547Y-258158D01*
X665565Y-258129D01*
X665613Y-258063D01*
X665675Y-257990D01*
X665747Y-257918D01*
X665831Y-257845D01*
X665929Y-257783D01*
X665933Y-257779D01*
X665944Y-257776D01*
X665958Y-257768D01*
X665977Y-257757D01*
X666006Y-257747D01*
X666035Y-257736D01*
X666071Y-257721D01*
X666111Y-257706D01*
X666155Y-257692D01*
X666202Y-257677D01*
X666304Y-257656D01*
X666421Y-257637D01*
X666541Y-257630D01*
X666577D01*
X666603Y-257634D01*
D02*
G37*
G36*
X670720Y-257666D02*
X670767Y-257674D01*
X670822Y-257685D01*
X670880Y-257699D01*
X670942Y-257717D01*
X671000Y-257747D01*
X671004D01*
X671007Y-257750D01*
X671025Y-257761D01*
X671055Y-257779D01*
X671091Y-257805D01*
X671131Y-257841D01*
X671175Y-257881D01*
X671215Y-257928D01*
X671255Y-257983D01*
X671258Y-257990D01*
X671273Y-258009D01*
X671287Y-258041D01*
X671313Y-258089D01*
X671335Y-258143D01*
X671364Y-258205D01*
X671389Y-258278D01*
X671411Y-258358D01*
Y-258362D01*
X671415Y-258369D01*
X671419Y-258380D01*
X671422Y-258398D01*
X671426Y-258420D01*
X671429Y-258445D01*
X671437Y-258478D01*
X671440Y-258515D01*
X671448Y-258555D01*
X671451Y-258598D01*
X671455Y-258649D01*
X671462Y-258700D01*
X671466Y-258758D01*
Y-258817D01*
X671469Y-258882D01*
Y-258951D01*
Y-258955D01*
Y-258969D01*
Y-258995D01*
Y-259024D01*
X671466Y-259064D01*
Y-259108D01*
X671462Y-259155D01*
X671459Y-259206D01*
X671448Y-259323D01*
X671429Y-259443D01*
X671408Y-259559D01*
X671393Y-259614D01*
X671375Y-259668D01*
Y-259672D01*
X671371Y-259679D01*
X671364Y-259694D01*
X671357Y-259712D01*
X671349Y-259738D01*
X671335Y-259763D01*
X671306Y-259825D01*
X671269Y-259891D01*
X671222Y-259963D01*
X671167Y-260029D01*
X671102Y-260091D01*
X671098D01*
X671095Y-260098D01*
X671084Y-260105D01*
X671069Y-260113D01*
X671051Y-260123D01*
X671033Y-260138D01*
X670978Y-260163D01*
X670913Y-260189D01*
X670836Y-260214D01*
X670745Y-260229D01*
X670647Y-260236D01*
X670610D01*
X670585Y-260233D01*
X670556Y-260229D01*
X670519Y-260222D01*
X670479Y-260214D01*
X670436Y-260204D01*
X670392Y-260189D01*
X670345Y-260174D01*
X670297Y-260153D01*
X670250Y-260127D01*
X670203Y-260098D01*
X670155Y-260062D01*
X670112Y-260021D01*
X670072Y-259978D01*
X670068Y-259974D01*
X670061Y-259963D01*
X670050Y-259945D01*
X670032Y-259916D01*
X670014Y-259883D01*
X669995Y-259840D01*
X669970Y-259788D01*
X669948Y-259730D01*
X669926Y-259665D01*
X669904Y-259588D01*
X669882Y-259505D01*
X669864Y-259410D01*
X669846Y-259308D01*
X669835Y-259199D01*
X669828Y-259079D01*
X669824Y-258951D01*
Y-258948D01*
Y-258933D01*
Y-258908D01*
Y-258878D01*
X669828Y-258839D01*
Y-258795D01*
X669832Y-258748D01*
X669835Y-258693D01*
X669846Y-258580D01*
X669864Y-258460D01*
X669886Y-258340D01*
X669901Y-258285D01*
X669915Y-258231D01*
Y-258227D01*
X669919Y-258220D01*
X669926Y-258205D01*
X669933Y-258187D01*
X669941Y-258161D01*
X669955Y-258136D01*
X669984Y-258074D01*
X670021Y-258009D01*
X670068Y-257939D01*
X670123Y-257870D01*
X670188Y-257812D01*
X670192D01*
X670195Y-257805D01*
X670206Y-257798D01*
X670221Y-257790D01*
X670239Y-257776D01*
X670261Y-257765D01*
X670316Y-257736D01*
X670381Y-257710D01*
X670458Y-257685D01*
X670549Y-257670D01*
X670647Y-257663D01*
X670680D01*
X670720Y-257666D01*
D02*
G37*
G36*
X668740D02*
X668769Y-257670D01*
X668801Y-257674D01*
X668838Y-257677D01*
X668874Y-257688D01*
X668961Y-257710D01*
X669049Y-257743D01*
X669093Y-257765D01*
X669136Y-257790D01*
X669176Y-257823D01*
X669216Y-257856D01*
X669220Y-257859D01*
X669224Y-257863D01*
X669235Y-257874D01*
X669249Y-257889D01*
X669264Y-257910D01*
X669282Y-257932D01*
X669318Y-257987D01*
X669355Y-258056D01*
X669387Y-258136D01*
X669413Y-258227D01*
X669417Y-258274D01*
X669420Y-258325D01*
Y-258329D01*
Y-258332D01*
Y-258354D01*
X669417Y-258387D01*
X669409Y-258427D01*
X669398Y-258478D01*
X669380Y-258529D01*
X669358Y-258580D01*
X669325Y-258631D01*
X669322Y-258638D01*
X669307Y-258653D01*
X669285Y-258675D01*
X669256Y-258704D01*
X669216Y-258737D01*
X669169Y-258769D01*
X669114Y-258802D01*
X669049Y-258831D01*
X669053D01*
X669060Y-258835D01*
X669071Y-258839D01*
X669085Y-258846D01*
X669129Y-258864D01*
X669180Y-258890D01*
X669235Y-258926D01*
X669293Y-258966D01*
X669347Y-259017D01*
X669398Y-259075D01*
Y-259079D01*
X669402Y-259082D01*
X669417Y-259104D01*
X669438Y-259141D01*
X669460Y-259188D01*
X669482Y-259246D01*
X669504Y-259315D01*
X669518Y-259392D01*
X669522Y-259475D01*
Y-259479D01*
Y-259490D01*
Y-259508D01*
X669518Y-259530D01*
X669515Y-259556D01*
X669511Y-259588D01*
X669504Y-259625D01*
X669493Y-259665D01*
X669467Y-259749D01*
X669449Y-259796D01*
X669424Y-259840D01*
X669398Y-259887D01*
X669369Y-259930D01*
X669333Y-259974D01*
X669293Y-260018D01*
X669289Y-260021D01*
X669282Y-260029D01*
X669271Y-260040D01*
X669253Y-260051D01*
X669227Y-260069D01*
X669202Y-260087D01*
X669169Y-260105D01*
X669133Y-260127D01*
X669093Y-260149D01*
X669045Y-260167D01*
X668994Y-260185D01*
X668943Y-260204D01*
X668885Y-260214D01*
X668823Y-260225D01*
X668761Y-260233D01*
X668692Y-260236D01*
X668656D01*
X668630Y-260233D01*
X668598Y-260229D01*
X668561Y-260225D01*
X668521Y-260218D01*
X668477Y-260207D01*
X668379Y-260182D01*
X668328Y-260163D01*
X668281Y-260145D01*
X668230Y-260120D01*
X668179Y-260091D01*
X668132Y-260058D01*
X668088Y-260018D01*
X668084Y-260014D01*
X668077Y-260007D01*
X668066Y-259996D01*
X668051Y-259978D01*
X668037Y-259956D01*
X668015Y-259930D01*
X667997Y-259901D01*
X667975Y-259865D01*
X667953Y-259829D01*
X667935Y-259785D01*
X667899Y-259694D01*
X667884Y-259639D01*
X667873Y-259585D01*
X667866Y-259526D01*
X667862Y-259468D01*
Y-259465D01*
Y-259457D01*
Y-259443D01*
X667866Y-259428D01*
Y-259406D01*
X667870Y-259381D01*
X667877Y-259323D01*
X667891Y-259257D01*
X667913Y-259192D01*
X667946Y-259122D01*
X667986Y-259057D01*
Y-259053D01*
X667993Y-259050D01*
X668008Y-259031D01*
X668037Y-259002D01*
X668077Y-258966D01*
X668128Y-258929D01*
X668190Y-258890D01*
X668259Y-258857D01*
X668343Y-258831D01*
X668339D01*
X668335Y-258828D01*
X668325Y-258824D01*
X668310Y-258817D01*
X668277Y-258802D01*
X668233Y-258780D01*
X668186Y-258751D01*
X668139Y-258715D01*
X668095Y-258675D01*
X668055Y-258631D01*
X668051Y-258624D01*
X668041Y-258609D01*
X668026Y-258580D01*
X668012Y-258544D01*
X667993Y-258496D01*
X667979Y-258442D01*
X667968Y-258380D01*
X667964Y-258314D01*
Y-258311D01*
Y-258303D01*
Y-258289D01*
X667968Y-258267D01*
X667971Y-258245D01*
X667975Y-258216D01*
X667990Y-258154D01*
X668012Y-258081D01*
X668048Y-258005D01*
X668070Y-257965D01*
X668095Y-257925D01*
X668128Y-257889D01*
X668161Y-257852D01*
X668164Y-257848D01*
X668172Y-257845D01*
X668183Y-257834D01*
X668197Y-257823D01*
X668215Y-257808D01*
X668241Y-257794D01*
X668270Y-257776D01*
X668299Y-257757D01*
X668335Y-257739D01*
X668375Y-257721D01*
X668419Y-257706D01*
X668467Y-257692D01*
X668568Y-257670D01*
X668627Y-257666D01*
X668685Y-257663D01*
X668718D01*
X668740Y-257666D01*
D02*
G37*
G36*
X644556Y-252469D02*
X644588Y-252473D01*
X644628Y-252477D01*
X644668Y-252480D01*
X644716Y-252491D01*
X644814Y-252513D01*
X644923Y-252546D01*
X644978Y-252568D01*
X645029Y-252593D01*
X645080Y-252626D01*
X645131Y-252659D01*
X645134Y-252662D01*
X645142Y-252666D01*
X645156Y-252677D01*
X645174Y-252695D01*
X645193Y-252713D01*
X645218Y-252739D01*
X645244Y-252768D01*
X645273Y-252797D01*
X645302Y-252833D01*
X645331Y-252877D01*
X645364Y-252921D01*
X645393Y-252968D01*
X645418Y-253023D01*
X645447Y-253077D01*
X645469Y-253135D01*
X645491Y-253201D01*
X645163Y-253277D01*
Y-253274D01*
X645160Y-253266D01*
X645153Y-253252D01*
X645145Y-253234D01*
X645138Y-253212D01*
X645127Y-253183D01*
X645098Y-253124D01*
X645062Y-253059D01*
X645018Y-252993D01*
X644963Y-252931D01*
X644905Y-252877D01*
X644898Y-252870D01*
X644876Y-252855D01*
X644839Y-252837D01*
X644792Y-252811D01*
X644730Y-252790D01*
X644661Y-252768D01*
X644578Y-252753D01*
X644486Y-252749D01*
X644457D01*
X644439Y-252753D01*
X644414D01*
X644384Y-252757D01*
X644315Y-252768D01*
X644239Y-252782D01*
X644159Y-252808D01*
X644075Y-252844D01*
X643999Y-252891D01*
X643995D01*
X643991Y-252899D01*
X643966Y-252917D01*
X643933Y-252946D01*
X643893Y-252990D01*
X643846Y-253044D01*
X643802Y-253106D01*
X643762Y-253183D01*
X643726Y-253266D01*
Y-253270D01*
X643722Y-253277D01*
X643718Y-253288D01*
X643715Y-253306D01*
X643708Y-253328D01*
X643700Y-253354D01*
X643689Y-253416D01*
X643675Y-253488D01*
X643660Y-253569D01*
X643653Y-253656D01*
X643649Y-253750D01*
Y-253754D01*
Y-253765D01*
Y-253783D01*
Y-253805D01*
X643653Y-253831D01*
Y-253863D01*
X643656Y-253900D01*
X643660Y-253940D01*
X643671Y-254027D01*
X643689Y-254122D01*
X643711Y-254216D01*
X643740Y-254311D01*
Y-254315D01*
X643744Y-254322D01*
X643751Y-254333D01*
X643758Y-254351D01*
X643780Y-254395D01*
X643813Y-254446D01*
X643853Y-254504D01*
X643904Y-254566D01*
X643962Y-254621D01*
X644031Y-254671D01*
X644035D01*
X644042Y-254675D01*
X644053Y-254682D01*
X644068Y-254690D01*
X644086Y-254697D01*
X644108Y-254708D01*
X644159Y-254730D01*
X644224Y-254751D01*
X644297Y-254770D01*
X644377Y-254784D01*
X644461Y-254788D01*
X644486D01*
X644508Y-254784D01*
X644534D01*
X644559Y-254781D01*
X644625Y-254766D01*
X644701Y-254748D01*
X644778Y-254719D01*
X644858Y-254679D01*
X644898Y-254657D01*
X644934Y-254628D01*
X644938Y-254624D01*
X644941Y-254621D01*
X644952Y-254609D01*
X644967Y-254599D01*
X644981Y-254580D01*
X645000Y-254559D01*
X645021Y-254537D01*
X645040Y-254508D01*
X645062Y-254475D01*
X645087Y-254438D01*
X645109Y-254402D01*
X645131Y-254358D01*
X645149Y-254311D01*
X645167Y-254260D01*
X645185Y-254205D01*
X645200Y-254147D01*
X645535Y-254231D01*
Y-254235D01*
X645531Y-254249D01*
X645524Y-254271D01*
X645513Y-254300D01*
X645502Y-254333D01*
X645487Y-254373D01*
X645469Y-254417D01*
X645447Y-254464D01*
X645397Y-254566D01*
X645331Y-254668D01*
X645291Y-254719D01*
X645251Y-254770D01*
X645207Y-254813D01*
X645156Y-254857D01*
X645153Y-254861D01*
X645145Y-254868D01*
X645127Y-254875D01*
X645109Y-254890D01*
X645080Y-254908D01*
X645051Y-254926D01*
X645011Y-254944D01*
X644971Y-254963D01*
X644923Y-254984D01*
X644872Y-255003D01*
X644818Y-255021D01*
X644760Y-255039D01*
X644698Y-255054D01*
X644632Y-255061D01*
X644563Y-255068D01*
X644490Y-255072D01*
X644450D01*
X644421Y-255068D01*
X644388D01*
X644348Y-255065D01*
X644304Y-255057D01*
X644253Y-255050D01*
X644148Y-255032D01*
X644039Y-255003D01*
X643929Y-254963D01*
X643879Y-254937D01*
X643828Y-254908D01*
X643824Y-254904D01*
X643817Y-254901D01*
X643802Y-254890D01*
X643788Y-254875D01*
X643766Y-254861D01*
X643740Y-254839D01*
X643711Y-254813D01*
X643682Y-254784D01*
X643653Y-254751D01*
X643620Y-254719D01*
X643555Y-254635D01*
X643493Y-254537D01*
X643438Y-254428D01*
Y-254424D01*
X643431Y-254413D01*
X643427Y-254395D01*
X643416Y-254373D01*
X643409Y-254344D01*
X643398Y-254307D01*
X643384Y-254267D01*
X643373Y-254224D01*
X643362Y-254176D01*
X643347Y-254122D01*
X643329Y-254009D01*
X643314Y-253882D01*
X643307Y-253750D01*
Y-253747D01*
Y-253732D01*
Y-253711D01*
X643311Y-253685D01*
Y-253649D01*
X643314Y-253612D01*
X643318Y-253565D01*
X643325Y-253518D01*
X643343Y-253412D01*
X643369Y-253295D01*
X643405Y-253179D01*
X643456Y-253066D01*
X643460Y-253063D01*
X643464Y-253052D01*
X643471Y-253037D01*
X643485Y-253019D01*
X643500Y-252993D01*
X643518Y-252964D01*
X643566Y-252899D01*
X643627Y-252826D01*
X643700Y-252753D01*
X643784Y-252680D01*
X643882Y-252619D01*
X643886Y-252615D01*
X643897Y-252611D01*
X643911Y-252604D01*
X643929Y-252593D01*
X643959Y-252582D01*
X643988Y-252571D01*
X644024Y-252557D01*
X644064Y-252542D01*
X644108Y-252527D01*
X644155Y-252513D01*
X644257Y-252491D01*
X644374Y-252473D01*
X644494Y-252466D01*
X644530D01*
X644556Y-252469D01*
D02*
G37*
G36*
X648611Y-252502D02*
X648629D01*
X648654Y-252506D01*
X648716Y-252517D01*
X648785Y-252531D01*
X648862Y-252557D01*
X648938Y-252589D01*
X649015Y-252633D01*
X649018D01*
X649022Y-252640D01*
X649033Y-252648D01*
X649047Y-252659D01*
X649084Y-252688D01*
X649131Y-252728D01*
X649178Y-252782D01*
X649233Y-252848D01*
X649280Y-252924D01*
X649324Y-253012D01*
Y-253015D01*
X649328Y-253023D01*
X649335Y-253037D01*
X649342Y-253055D01*
X649349Y-253081D01*
X649360Y-253114D01*
X649368Y-253150D01*
X649379Y-253190D01*
X649390Y-253237D01*
X649401Y-253292D01*
X649408Y-253350D01*
X649415Y-253412D01*
X649422Y-253481D01*
X649430Y-253554D01*
X649433Y-253634D01*
Y-253718D01*
Y-253721D01*
Y-253740D01*
Y-253765D01*
Y-253798D01*
X649430Y-253838D01*
Y-253885D01*
X649426Y-253940D01*
X649419Y-253994D01*
X649408Y-254118D01*
X649390Y-254249D01*
X649364Y-254373D01*
X649346Y-254435D01*
X649328Y-254489D01*
Y-254493D01*
X649324Y-254500D01*
X649317Y-254515D01*
X649309Y-254537D01*
X649298Y-254559D01*
X649284Y-254588D01*
X649248Y-254650D01*
X649204Y-254719D01*
X649153Y-254792D01*
X649087Y-254861D01*
X649015Y-254923D01*
X649011D01*
X649004Y-254930D01*
X648993Y-254937D01*
X648978Y-254944D01*
X648956Y-254955D01*
X648935Y-254970D01*
X648905Y-254984D01*
X648876Y-254995D01*
X648807Y-255025D01*
X648723Y-255050D01*
X648632Y-255065D01*
X648530Y-255072D01*
X648501D01*
X648483Y-255068D01*
X648458D01*
X648429Y-255065D01*
X648359Y-255050D01*
X648283Y-255032D01*
X648203Y-255003D01*
X648123Y-254963D01*
X648083Y-254937D01*
X648046Y-254908D01*
X648043Y-254904D01*
X648039Y-254901D01*
X648028Y-254890D01*
X648017Y-254879D01*
X648003Y-254861D01*
X647985Y-254839D01*
X647948Y-254788D01*
X647912Y-254722D01*
X647875Y-254642D01*
X647846Y-254551D01*
X647824Y-254446D01*
X648123Y-254420D01*
Y-254424D01*
X648127Y-254431D01*
Y-254438D01*
X648130Y-254453D01*
X648141Y-254493D01*
X648156Y-254537D01*
X648174Y-254588D01*
X648199Y-254639D01*
X648228Y-254686D01*
X648265Y-254726D01*
X648268Y-254730D01*
X648283Y-254741D01*
X648308Y-254755D01*
X648338Y-254770D01*
X648378Y-254788D01*
X648425Y-254802D01*
X648480Y-254813D01*
X648538Y-254817D01*
X648563D01*
X648589Y-254813D01*
X648622Y-254810D01*
X648662Y-254802D01*
X648702Y-254792D01*
X648745Y-254777D01*
X648785Y-254755D01*
X648789Y-254751D01*
X648804Y-254744D01*
X648825Y-254730D01*
X648847Y-254708D01*
X648876Y-254682D01*
X648905Y-254653D01*
X648935Y-254621D01*
X648964Y-254580D01*
X648967Y-254577D01*
X648975Y-254559D01*
X648989Y-254533D01*
X649004Y-254500D01*
X649022Y-254457D01*
X649040Y-254406D01*
X649058Y-254347D01*
X649077Y-254282D01*
Y-254278D01*
X649080Y-254275D01*
Y-254264D01*
X649084Y-254249D01*
X649091Y-254213D01*
X649102Y-254166D01*
X649109Y-254107D01*
X649117Y-254045D01*
X649120Y-253976D01*
X649124Y-253903D01*
Y-253900D01*
Y-253889D01*
Y-253871D01*
Y-253841D01*
X649120Y-253849D01*
X649106Y-253867D01*
X649084Y-253892D01*
X649058Y-253929D01*
X649022Y-253965D01*
X648978Y-254005D01*
X648927Y-254045D01*
X648869Y-254082D01*
X648862Y-254085D01*
X648840Y-254096D01*
X648807Y-254111D01*
X648767Y-254125D01*
X648712Y-254144D01*
X648654Y-254158D01*
X648589Y-254169D01*
X648520Y-254173D01*
X648490D01*
X648469Y-254169D01*
X648440Y-254166D01*
X648410Y-254162D01*
X648374Y-254155D01*
X648338Y-254144D01*
X648254Y-254118D01*
X648210Y-254100D01*
X648167Y-254078D01*
X648119Y-254053D01*
X648075Y-254020D01*
X648032Y-253987D01*
X647992Y-253947D01*
X647988Y-253943D01*
X647981Y-253936D01*
X647974Y-253925D01*
X647959Y-253907D01*
X647941Y-253882D01*
X647923Y-253856D01*
X647904Y-253823D01*
X647886Y-253787D01*
X647864Y-253747D01*
X647846Y-253703D01*
X647828Y-253652D01*
X647810Y-253601D01*
X647795Y-253543D01*
X647788Y-253481D01*
X647781Y-253419D01*
X647777Y-253350D01*
Y-253346D01*
Y-253332D01*
Y-253314D01*
X647781Y-253288D01*
X647784Y-253256D01*
X647788Y-253215D01*
X647795Y-253175D01*
X647806Y-253128D01*
X647832Y-253033D01*
X647850Y-252982D01*
X647872Y-252928D01*
X647897Y-252877D01*
X647930Y-252830D01*
X647963Y-252779D01*
X648003Y-252735D01*
X648006Y-252731D01*
X648014Y-252724D01*
X648025Y-252713D01*
X648043Y-252698D01*
X648065Y-252680D01*
X648094Y-252659D01*
X648123Y-252640D01*
X648159Y-252615D01*
X648196Y-252593D01*
X648239Y-252575D01*
X648338Y-252535D01*
X648388Y-252520D01*
X648447Y-252509D01*
X648505Y-252502D01*
X648567Y-252498D01*
X648592D01*
X648611Y-252502D01*
D02*
G37*
G36*
X647471Y-252786D02*
X647468Y-252790D01*
X647460Y-252797D01*
X647446Y-252811D01*
X647431Y-252833D01*
X647409Y-252859D01*
X647380Y-252888D01*
X647351Y-252924D01*
X647318Y-252968D01*
X647286Y-253012D01*
X647246Y-253063D01*
X647205Y-253121D01*
X647165Y-253179D01*
X647122Y-253244D01*
X647078Y-253314D01*
X647035Y-253390D01*
X646991Y-253467D01*
X646987Y-253470D01*
X646980Y-253485D01*
X646969Y-253507D01*
X646951Y-253539D01*
X646933Y-253579D01*
X646911Y-253623D01*
X646885Y-253674D01*
X646860Y-253732D01*
X646831Y-253798D01*
X646798Y-253863D01*
X646769Y-253936D01*
X646740Y-254013D01*
X646681Y-254169D01*
X646627Y-254337D01*
Y-254340D01*
X646623Y-254351D01*
X646620Y-254369D01*
X646612Y-254391D01*
X646605Y-254420D01*
X646598Y-254457D01*
X646587Y-254497D01*
X646579Y-254540D01*
X646568Y-254591D01*
X646558Y-254646D01*
X646539Y-254762D01*
X646521Y-254890D01*
X646510Y-255028D01*
X646194D01*
Y-255025D01*
Y-255014D01*
Y-254999D01*
X646197Y-254977D01*
Y-254948D01*
X646201Y-254912D01*
X646205Y-254872D01*
X646208Y-254828D01*
X646215Y-254777D01*
X646223Y-254726D01*
X646234Y-254664D01*
X646245Y-254602D01*
X646255Y-254537D01*
X646270Y-254464D01*
X646307Y-254315D01*
Y-254311D01*
X646310Y-254296D01*
X646317Y-254275D01*
X646328Y-254242D01*
X646339Y-254205D01*
X646354Y-254162D01*
X646368Y-254111D01*
X646390Y-254056D01*
X646412Y-253994D01*
X646434Y-253932D01*
X646489Y-253794D01*
X646554Y-253649D01*
X646627Y-253503D01*
X646630Y-253499D01*
X646638Y-253485D01*
X646649Y-253467D01*
X646663Y-253437D01*
X646681Y-253405D01*
X646707Y-253365D01*
X646732Y-253321D01*
X646761Y-253274D01*
X646831Y-253168D01*
X646903Y-253059D01*
X646987Y-252946D01*
X647075Y-252840D01*
X645841D01*
Y-252542D01*
X647471D01*
Y-252786D01*
D02*
G37*
G36*
X656343Y-300004D02*
X656369D01*
X656398Y-300007D01*
X656467Y-300022D01*
X656543Y-300040D01*
X656624Y-300069D01*
X656704Y-300109D01*
X656744Y-300135D01*
X656780Y-300164D01*
X656784Y-300167D01*
X656787Y-300171D01*
X656798Y-300182D01*
X656809Y-300193D01*
X656824Y-300211D01*
X656842Y-300233D01*
X656878Y-300284D01*
X656915Y-300349D01*
X656951Y-300430D01*
X656980Y-300520D01*
X657002Y-300626D01*
X656704Y-300652D01*
Y-300648D01*
X656700Y-300641D01*
Y-300633D01*
X656696Y-300619D01*
X656685Y-300579D01*
X656671Y-300535D01*
X656653Y-300484D01*
X656627Y-300433D01*
X656598Y-300386D01*
X656562Y-300346D01*
X656558Y-300342D01*
X656543Y-300331D01*
X656518Y-300317D01*
X656489Y-300302D01*
X656449Y-300284D01*
X656401Y-300269D01*
X656347Y-300258D01*
X656289Y-300255D01*
X656263D01*
X656238Y-300258D01*
X656205Y-300262D01*
X656165Y-300269D01*
X656125Y-300280D01*
X656081Y-300295D01*
X656041Y-300317D01*
X656037Y-300320D01*
X656023Y-300328D01*
X656001Y-300342D01*
X655979Y-300364D01*
X655950Y-300389D01*
X655921Y-300419D01*
X655892Y-300451D01*
X655863Y-300491D01*
X655859Y-300495D01*
X655852Y-300513D01*
X655837Y-300539D01*
X655823Y-300571D01*
X655804Y-300615D01*
X655786Y-300666D01*
X655768Y-300724D01*
X655750Y-300790D01*
Y-300794D01*
X655746Y-300797D01*
Y-300808D01*
X655743Y-300823D01*
X655735Y-300859D01*
X655724Y-300906D01*
X655717Y-300965D01*
X655710Y-301027D01*
X655706Y-301096D01*
X655702Y-301168D01*
Y-301172D01*
Y-301183D01*
Y-301201D01*
Y-301230D01*
X655706Y-301223D01*
X655721Y-301205D01*
X655743Y-301179D01*
X655768Y-301143D01*
X655804Y-301107D01*
X655848Y-301066D01*
X655899Y-301027D01*
X655957Y-300990D01*
X655965Y-300986D01*
X655986Y-300975D01*
X656019Y-300961D01*
X656059Y-300946D01*
X656114Y-300928D01*
X656172Y-300914D01*
X656238Y-300903D01*
X656307Y-300899D01*
X656336D01*
X656358Y-300903D01*
X656387Y-300906D01*
X656416Y-300910D01*
X656452Y-300917D01*
X656489Y-300928D01*
X656572Y-300954D01*
X656616Y-300972D01*
X656660Y-300994D01*
X656707Y-301019D01*
X656751Y-301052D01*
X656795Y-301085D01*
X656835Y-301125D01*
X656838Y-301128D01*
X656846Y-301136D01*
X656853Y-301147D01*
X656867Y-301165D01*
X656885Y-301190D01*
X656904Y-301216D01*
X656922Y-301249D01*
X656940Y-301285D01*
X656962Y-301325D01*
X656980Y-301369D01*
X656998Y-301420D01*
X657017Y-301470D01*
X657031Y-301529D01*
X657038Y-301591D01*
X657046Y-301653D01*
X657049Y-301722D01*
Y-301725D01*
Y-301740D01*
Y-301758D01*
X657046Y-301784D01*
X657042Y-301816D01*
X657038Y-301856D01*
X657031Y-301896D01*
X657020Y-301944D01*
X656995Y-302038D01*
X656977Y-302089D01*
X656955Y-302144D01*
X656929Y-302195D01*
X656896Y-302242D01*
X656864Y-302293D01*
X656824Y-302337D01*
X656820Y-302341D01*
X656813Y-302348D01*
X656802Y-302359D01*
X656784Y-302373D01*
X656762Y-302391D01*
X656733Y-302413D01*
X656704Y-302432D01*
X656667Y-302457D01*
X656631Y-302479D01*
X656587Y-302497D01*
X656489Y-302537D01*
X656438Y-302552D01*
X656380Y-302562D01*
X656321Y-302570D01*
X656259Y-302573D01*
X656234D01*
X656216Y-302570D01*
X656198D01*
X656172Y-302566D01*
X656110Y-302555D01*
X656041Y-302541D01*
X655965Y-302515D01*
X655888Y-302483D01*
X655812Y-302439D01*
X655808D01*
X655804Y-302432D01*
X655794Y-302424D01*
X655779Y-302413D01*
X655743Y-302384D01*
X655695Y-302344D01*
X655648Y-302290D01*
X655593Y-302224D01*
X655546Y-302148D01*
X655502Y-302060D01*
Y-302057D01*
X655499Y-302049D01*
X655491Y-302035D01*
X655484Y-302016D01*
X655477Y-301991D01*
X655466Y-301958D01*
X655459Y-301922D01*
X655448Y-301882D01*
X655437Y-301835D01*
X655426Y-301780D01*
X655419Y-301722D01*
X655411Y-301660D01*
X655404Y-301591D01*
X655397Y-301518D01*
X655393Y-301438D01*
Y-301354D01*
Y-301350D01*
Y-301332D01*
Y-301307D01*
Y-301274D01*
X655397Y-301234D01*
Y-301187D01*
X655400Y-301132D01*
X655408Y-301077D01*
X655419Y-300954D01*
X655437Y-300823D01*
X655462Y-300699D01*
X655480Y-300637D01*
X655499Y-300582D01*
Y-300579D01*
X655502Y-300571D01*
X655510Y-300557D01*
X655517Y-300535D01*
X655528Y-300513D01*
X655542Y-300484D01*
X655579Y-300422D01*
X655622Y-300353D01*
X655673Y-300280D01*
X655739Y-300211D01*
X655812Y-300149D01*
X655815D01*
X655823Y-300142D01*
X655834Y-300135D01*
X655848Y-300127D01*
X655870Y-300116D01*
X655892Y-300102D01*
X655921Y-300087D01*
X655950Y-300076D01*
X656019Y-300047D01*
X656103Y-300022D01*
X656194Y-300007D01*
X656296Y-300000D01*
X656325D01*
X656343Y-300004D01*
D02*
G37*
G36*
X660482D02*
X660511D01*
X660547Y-300007D01*
X660587Y-300011D01*
X660628Y-300014D01*
X660718Y-300029D01*
X660817Y-300051D01*
X660911Y-300080D01*
X661002Y-300120D01*
X661006D01*
X661013Y-300127D01*
X661024Y-300135D01*
X661039Y-300142D01*
X661079Y-300171D01*
X661126Y-300211D01*
X661181Y-300262D01*
X661232Y-300320D01*
X661283Y-300393D01*
X661323Y-300473D01*
Y-300477D01*
X661326Y-300484D01*
X661330Y-300499D01*
X661337Y-300517D01*
X661344Y-300539D01*
X661352Y-300568D01*
X661363Y-300601D01*
X661370Y-300641D01*
X661377Y-300684D01*
X661388Y-300732D01*
X661396Y-300783D01*
X661403Y-300837D01*
X661410Y-300899D01*
X661414Y-300965D01*
X661417Y-301034D01*
Y-301107D01*
Y-302562D01*
X661083D01*
Y-301107D01*
Y-301103D01*
Y-301092D01*
Y-301074D01*
Y-301052D01*
X661079Y-301027D01*
Y-300994D01*
X661075Y-300924D01*
X661068Y-300845D01*
X661057Y-300764D01*
X661042Y-300688D01*
X661035Y-300655D01*
X661024Y-300622D01*
X661021Y-300615D01*
X661013Y-300597D01*
X660995Y-300571D01*
X660973Y-300535D01*
X660948Y-300499D01*
X660911Y-300459D01*
X660868Y-300419D01*
X660817Y-300386D01*
X660810Y-300382D01*
X660791Y-300371D01*
X660758Y-300360D01*
X660715Y-300346D01*
X660664Y-300328D01*
X660598Y-300317D01*
X660529Y-300306D01*
X660453Y-300302D01*
X660416D01*
X660394Y-300306D01*
X660362D01*
X660329Y-300309D01*
X660249Y-300324D01*
X660161Y-300342D01*
X660078Y-300371D01*
X659998Y-300411D01*
X659961Y-300437D01*
X659929Y-300466D01*
X659925Y-300469D01*
X659921Y-300473D01*
X659914Y-300484D01*
X659903Y-300499D01*
X659892Y-300520D01*
X659878Y-300542D01*
X659863Y-300575D01*
X659848Y-300608D01*
X659834Y-300648D01*
X659823Y-300695D01*
X659808Y-300750D01*
X659797Y-300808D01*
X659787Y-300874D01*
X659779Y-300943D01*
X659772Y-301023D01*
Y-301107D01*
Y-302562D01*
X659437D01*
Y-301107D01*
Y-301103D01*
Y-301088D01*
Y-301070D01*
Y-301045D01*
X659441Y-301012D01*
Y-300975D01*
X659445Y-300932D01*
X659448Y-300888D01*
X659459Y-300790D01*
X659474Y-300688D01*
X659495Y-300590D01*
X659510Y-300542D01*
X659524Y-300499D01*
Y-300495D01*
X659528Y-300488D01*
X659536Y-300477D01*
X659543Y-300462D01*
X659565Y-300422D01*
X659597Y-300371D01*
X659641Y-300313D01*
X659692Y-300255D01*
X659758Y-300193D01*
X659838Y-300138D01*
X659841D01*
X659848Y-300131D01*
X659859Y-300127D01*
X659878Y-300116D01*
X659900Y-300106D01*
X659929Y-300095D01*
X659958Y-300084D01*
X659994Y-300069D01*
X660034Y-300055D01*
X660078Y-300044D01*
X660125Y-300033D01*
X660180Y-300022D01*
X660234Y-300014D01*
X660293Y-300007D01*
X660424Y-300000D01*
X660456D01*
X660482Y-300004D01*
D02*
G37*
G36*
X658152Y-302013D02*
X658156Y-302009D01*
X658174Y-301995D01*
X658196Y-301973D01*
X658232Y-301947D01*
X658272Y-301915D01*
X658323Y-301878D01*
X658382Y-301838D01*
X658447Y-301798D01*
X658451D01*
X658454Y-301795D01*
X658476Y-301780D01*
X658513Y-301762D01*
X658556Y-301740D01*
X658607Y-301714D01*
X658662Y-301689D01*
X658716Y-301663D01*
X658771Y-301642D01*
Y-301940D01*
X658767D01*
X658760Y-301947D01*
X658746Y-301951D01*
X658727Y-301962D01*
X658706Y-301973D01*
X658680Y-301987D01*
X658618Y-302024D01*
X658545Y-302064D01*
X658473Y-302115D01*
X658396Y-302173D01*
X658320Y-302235D01*
X658316Y-302239D01*
X658312Y-302242D01*
X658301Y-302253D01*
X658287Y-302264D01*
X658254Y-302301D01*
X658211Y-302344D01*
X658167Y-302395D01*
X658119Y-302453D01*
X658079Y-302512D01*
X658043Y-302573D01*
X657843D01*
Y-300044D01*
X658152D01*
Y-302013D01*
D02*
G37*
G36*
X644694Y-294885D02*
X644730D01*
X644767Y-294889D01*
X644814Y-294893D01*
X644861Y-294900D01*
X644967Y-294918D01*
X645083Y-294944D01*
X645200Y-294980D01*
X645313Y-295031D01*
X645316Y-295035D01*
X645327Y-295038D01*
X645342Y-295046D01*
X645360Y-295060D01*
X645386Y-295075D01*
X645415Y-295093D01*
X645480Y-295140D01*
X645553Y-295202D01*
X645626Y-295275D01*
X645698Y-295359D01*
X645760Y-295457D01*
X645764Y-295461D01*
X645768Y-295472D01*
X645775Y-295486D01*
X645786Y-295504D01*
X645797Y-295533D01*
X645808Y-295563D01*
X645822Y-295599D01*
X645837Y-295639D01*
X645851Y-295683D01*
X645866Y-295730D01*
X645888Y-295832D01*
X645906Y-295948D01*
X645913Y-296069D01*
Y-296105D01*
X645910Y-296130D01*
X645906Y-296163D01*
X645902Y-296203D01*
X645899Y-296243D01*
X645888Y-296290D01*
X645866Y-296389D01*
X645833Y-296498D01*
X645811Y-296553D01*
X645786Y-296604D01*
X645753Y-296655D01*
X645720Y-296706D01*
X645717Y-296709D01*
X645713Y-296716D01*
X645702Y-296731D01*
X645684Y-296749D01*
X645666Y-296767D01*
X645640Y-296793D01*
X645611Y-296818D01*
X645582Y-296847D01*
X645546Y-296877D01*
X645502Y-296906D01*
X645458Y-296938D01*
X645411Y-296968D01*
X645356Y-296993D01*
X645302Y-297022D01*
X645244Y-297044D01*
X645178Y-297066D01*
X645102Y-296738D01*
X645105D01*
X645113Y-296735D01*
X645127Y-296727D01*
X645145Y-296720D01*
X645167Y-296713D01*
X645196Y-296702D01*
X645254Y-296673D01*
X645320Y-296636D01*
X645386Y-296593D01*
X645447Y-296538D01*
X645502Y-296480D01*
X645509Y-296473D01*
X645524Y-296451D01*
X645542Y-296414D01*
X645568Y-296367D01*
X645589Y-296305D01*
X645611Y-296236D01*
X645626Y-296152D01*
X645629Y-296061D01*
Y-296032D01*
X645626Y-296014D01*
Y-295988D01*
X645622Y-295959D01*
X645611Y-295890D01*
X645597Y-295814D01*
X645571Y-295734D01*
X645535Y-295650D01*
X645487Y-295573D01*
Y-295570D01*
X645480Y-295566D01*
X645462Y-295541D01*
X645433Y-295508D01*
X645389Y-295468D01*
X645334Y-295421D01*
X645273Y-295377D01*
X645196Y-295337D01*
X645113Y-295301D01*
X645109D01*
X645102Y-295297D01*
X645091Y-295293D01*
X645073Y-295289D01*
X645051Y-295282D01*
X645025Y-295275D01*
X644963Y-295264D01*
X644890Y-295250D01*
X644810Y-295235D01*
X644723Y-295228D01*
X644628Y-295224D01*
X644625D01*
X644614D01*
X644596D01*
X644574D01*
X644548Y-295228D01*
X644516D01*
X644479Y-295231D01*
X644439Y-295235D01*
X644352Y-295246D01*
X644257Y-295264D01*
X644162Y-295286D01*
X644068Y-295315D01*
X644064D01*
X644057Y-295319D01*
X644046Y-295326D01*
X644028Y-295333D01*
X643984Y-295355D01*
X643933Y-295388D01*
X643875Y-295428D01*
X643813Y-295479D01*
X643758Y-295537D01*
X643707Y-295606D01*
Y-295610D01*
X643704Y-295617D01*
X643696Y-295628D01*
X643689Y-295643D01*
X643682Y-295661D01*
X643671Y-295683D01*
X643649Y-295734D01*
X643627Y-295799D01*
X643609Y-295872D01*
X643595Y-295952D01*
X643591Y-296036D01*
Y-296061D01*
X643595Y-296083D01*
Y-296109D01*
X643598Y-296134D01*
X643613Y-296199D01*
X643631Y-296276D01*
X643660Y-296352D01*
X643700Y-296432D01*
X643722Y-296473D01*
X643751Y-296509D01*
X643755Y-296513D01*
X643758Y-296516D01*
X643769Y-296527D01*
X643780Y-296542D01*
X643798Y-296556D01*
X643820Y-296574D01*
X643842Y-296596D01*
X643871Y-296615D01*
X643904Y-296636D01*
X643940Y-296662D01*
X643977Y-296684D01*
X644021Y-296706D01*
X644068Y-296724D01*
X644119Y-296742D01*
X644173Y-296760D01*
X644232Y-296775D01*
X644148Y-297110D01*
X644144D01*
X644130Y-297106D01*
X644108Y-297099D01*
X644079Y-297088D01*
X644046Y-297077D01*
X644006Y-297062D01*
X643962Y-297044D01*
X643915Y-297022D01*
X643813Y-296971D01*
X643711Y-296906D01*
X643660Y-296866D01*
X643609Y-296826D01*
X643566Y-296782D01*
X643522Y-296731D01*
X643518Y-296727D01*
X643511Y-296720D01*
X643504Y-296702D01*
X643489Y-296684D01*
X643471Y-296655D01*
X643453Y-296625D01*
X643434Y-296585D01*
X643416Y-296545D01*
X643394Y-296498D01*
X643376Y-296447D01*
X643358Y-296392D01*
X643340Y-296334D01*
X643325Y-296272D01*
X643318Y-296207D01*
X643311Y-296138D01*
X643307Y-296065D01*
Y-296025D01*
X643311Y-295996D01*
Y-295963D01*
X643314Y-295923D01*
X643322Y-295879D01*
X643329Y-295828D01*
X643347Y-295723D01*
X643376Y-295614D01*
X643416Y-295504D01*
X643442Y-295453D01*
X643471Y-295402D01*
X643474Y-295399D01*
X643478Y-295391D01*
X643489Y-295377D01*
X643504Y-295362D01*
X643518Y-295340D01*
X643540Y-295315D01*
X643566Y-295286D01*
X643595Y-295257D01*
X643627Y-295228D01*
X643660Y-295195D01*
X643744Y-295129D01*
X643842Y-295068D01*
X643951Y-295013D01*
X643955D01*
X643966Y-295006D01*
X643984Y-295002D01*
X644006Y-294991D01*
X644035Y-294984D01*
X644071Y-294973D01*
X644111Y-294958D01*
X644155Y-294947D01*
X644203Y-294936D01*
X644257Y-294922D01*
X644370Y-294904D01*
X644497Y-294889D01*
X644628Y-294882D01*
X644632D01*
X644647D01*
X644668D01*
X644694Y-294885D01*
D02*
G37*
G36*
X644115Y-297393D02*
X644137D01*
X644162Y-297397D01*
X644221Y-297404D01*
X644286Y-297419D01*
X644352Y-297441D01*
X644421Y-297474D01*
X644486Y-297514D01*
X644490D01*
X644494Y-297521D01*
X644512Y-297535D01*
X644541Y-297565D01*
X644577Y-297605D01*
X644614Y-297656D01*
X644654Y-297717D01*
X644687Y-297787D01*
X644712Y-297870D01*
Y-297867D01*
X644716Y-297863D01*
X644719Y-297852D01*
X644727Y-297837D01*
X644741Y-297805D01*
X644763Y-297761D01*
X644792Y-297714D01*
X644829Y-297666D01*
X644869Y-297623D01*
X644912Y-297583D01*
X644920Y-297579D01*
X644934Y-297568D01*
X644963Y-297554D01*
X645000Y-297539D01*
X645047Y-297521D01*
X645102Y-297506D01*
X645163Y-297495D01*
X645229Y-297492D01*
X645233D01*
X645240D01*
X645254D01*
X645276Y-297495D01*
X645298Y-297499D01*
X645327Y-297503D01*
X645389Y-297517D01*
X645462Y-297539D01*
X645538Y-297575D01*
X645578Y-297597D01*
X645618Y-297623D01*
X645655Y-297656D01*
X645691Y-297688D01*
X645695Y-297692D01*
X645698Y-297699D01*
X645710Y-297710D01*
X645720Y-297725D01*
X645735Y-297743D01*
X645750Y-297768D01*
X645768Y-297797D01*
X645786Y-297827D01*
X645804Y-297863D01*
X645822Y-297903D01*
X645837Y-297947D01*
X645851Y-297994D01*
X645873Y-298096D01*
X645877Y-298154D01*
X645881Y-298212D01*
Y-298245D01*
X645877Y-298267D01*
X645873Y-298296D01*
X645870Y-298329D01*
X645866Y-298365D01*
X645855Y-298402D01*
X645833Y-298489D01*
X645800Y-298576D01*
X645779Y-298620D01*
X645753Y-298664D01*
X645720Y-298704D01*
X645688Y-298744D01*
X645684Y-298747D01*
X645680Y-298751D01*
X645669Y-298762D01*
X645655Y-298777D01*
X645633Y-298791D01*
X645611Y-298809D01*
X645557Y-298846D01*
X645487Y-298882D01*
X645407Y-298915D01*
X645316Y-298940D01*
X645269Y-298944D01*
X645218Y-298948D01*
X645214D01*
X645211D01*
X645189D01*
X645156Y-298944D01*
X645116Y-298937D01*
X645065Y-298926D01*
X645014Y-298908D01*
X644963Y-298886D01*
X644912Y-298853D01*
X644905Y-298849D01*
X644890Y-298835D01*
X644869Y-298813D01*
X644839Y-298784D01*
X644807Y-298744D01*
X644774Y-298697D01*
X644741Y-298642D01*
X644712Y-298576D01*
Y-298580D01*
X644708Y-298587D01*
X644705Y-298598D01*
X644698Y-298613D01*
X644679Y-298657D01*
X644654Y-298708D01*
X644618Y-298762D01*
X644577Y-298820D01*
X644526Y-298875D01*
X644468Y-298926D01*
X644465D01*
X644461Y-298930D01*
X644439Y-298944D01*
X644403Y-298966D01*
X644355Y-298988D01*
X644297Y-299010D01*
X644228Y-299031D01*
X644151Y-299046D01*
X644068Y-299050D01*
X644064D01*
X644053D01*
X644035D01*
X644013Y-299046D01*
X643988Y-299042D01*
X643955Y-299039D01*
X643919Y-299031D01*
X643879Y-299021D01*
X643795Y-298995D01*
X643748Y-298977D01*
X643704Y-298951D01*
X643656Y-298926D01*
X643613Y-298897D01*
X643569Y-298860D01*
X643526Y-298820D01*
X643522Y-298817D01*
X643514Y-298809D01*
X643504Y-298798D01*
X643493Y-298780D01*
X643474Y-298755D01*
X643456Y-298729D01*
X643438Y-298697D01*
X643416Y-298660D01*
X643394Y-298620D01*
X643376Y-298573D01*
X643358Y-298522D01*
X643340Y-298471D01*
X643329Y-298413D01*
X643318Y-298351D01*
X643311Y-298289D01*
X643307Y-298220D01*
Y-298183D01*
X643311Y-298158D01*
X643314Y-298125D01*
X643318Y-298089D01*
X643325Y-298049D01*
X643336Y-298005D01*
X643362Y-297907D01*
X643380Y-297856D01*
X643398Y-297808D01*
X643424Y-297758D01*
X643453Y-297707D01*
X643485Y-297659D01*
X643526Y-297616D01*
X643529Y-297612D01*
X643536Y-297605D01*
X643547Y-297594D01*
X643566Y-297579D01*
X643587Y-297565D01*
X643613Y-297543D01*
X643642Y-297524D01*
X643678Y-297503D01*
X643715Y-297481D01*
X643758Y-297463D01*
X643849Y-297426D01*
X643904Y-297412D01*
X643959Y-297401D01*
X644017Y-297393D01*
X644075Y-297390D01*
X644079D01*
X644086D01*
X644101D01*
X644115Y-297393D01*
D02*
G37*
G36*
X644035Y-299676D02*
X644031D01*
X644024D01*
X644013Y-299679D01*
X643995Y-299683D01*
X643955Y-299694D01*
X643900Y-299709D01*
X643846Y-299730D01*
X643784Y-299760D01*
X643729Y-299796D01*
X643678Y-299839D01*
X643675Y-299847D01*
X643660Y-299861D01*
X643642Y-299890D01*
X643620Y-299931D01*
X643598Y-299974D01*
X643580Y-300029D01*
X643566Y-300091D01*
X643562Y-300160D01*
Y-300182D01*
X643566Y-300196D01*
X643569Y-300240D01*
X643584Y-300291D01*
X643602Y-300353D01*
X643631Y-300415D01*
X643675Y-300480D01*
X643700Y-300509D01*
X643729Y-300538D01*
X643733Y-300542D01*
X643737Y-300546D01*
X643748Y-300553D01*
X643758Y-300564D01*
X643798Y-300589D01*
X643849Y-300619D01*
X643911Y-300644D01*
X643988Y-300670D01*
X644079Y-300688D01*
X644126Y-300695D01*
X644177D01*
X644181D01*
X644188D01*
X644203D01*
X644221Y-300691D01*
X644242D01*
X644268Y-300688D01*
X644326Y-300677D01*
X644395Y-300658D01*
X644465Y-300633D01*
X644530Y-300597D01*
X644592Y-300546D01*
X644596D01*
X644599Y-300538D01*
X644618Y-300520D01*
X644643Y-300487D01*
X644672Y-300444D01*
X644698Y-300385D01*
X644723Y-300320D01*
X644741Y-300244D01*
X644748Y-300200D01*
Y-300131D01*
X644745Y-300102D01*
X644741Y-300065D01*
X644730Y-300022D01*
X644719Y-299978D01*
X644701Y-299931D01*
X644679Y-299883D01*
X644676Y-299880D01*
X644668Y-299865D01*
X644650Y-299843D01*
X644632Y-299814D01*
X644606Y-299785D01*
X644574Y-299756D01*
X644541Y-299723D01*
X644501Y-299698D01*
X644541Y-299406D01*
X645837Y-299650D01*
Y-300902D01*
X645542D01*
Y-299894D01*
X644861Y-299760D01*
X644865Y-299763D01*
X644869Y-299770D01*
X644876Y-299781D01*
X644887Y-299799D01*
X644898Y-299821D01*
X644912Y-299847D01*
X644941Y-299905D01*
X644971Y-299978D01*
X644996Y-300058D01*
X645014Y-300145D01*
X645021Y-300189D01*
Y-300269D01*
X645018Y-300291D01*
X645014Y-300320D01*
X645011Y-300353D01*
X645003Y-300389D01*
X644992Y-300429D01*
X644967Y-300517D01*
X644949Y-300564D01*
X644923Y-300611D01*
X644898Y-300658D01*
X644869Y-300706D01*
X644832Y-300749D01*
X644792Y-300793D01*
X644789Y-300797D01*
X644781Y-300804D01*
X644770Y-300815D01*
X644752Y-300830D01*
X644727Y-300848D01*
X644701Y-300866D01*
X644668Y-300888D01*
X644632Y-300910D01*
X644592Y-300928D01*
X644548Y-300950D01*
X644497Y-300968D01*
X644446Y-300986D01*
X644392Y-301001D01*
X644330Y-301012D01*
X644268Y-301019D01*
X644203Y-301023D01*
X644199D01*
X644188D01*
X644170D01*
X644144Y-301019D01*
X644115Y-301015D01*
X644082Y-301012D01*
X644042Y-301004D01*
X644002Y-300997D01*
X643908Y-300975D01*
X643809Y-300939D01*
X643758Y-300917D01*
X643711Y-300888D01*
X643660Y-300859D01*
X643613Y-300822D01*
X643609Y-300819D01*
X643598Y-300811D01*
X643584Y-300797D01*
X643566Y-300779D01*
X643544Y-300753D01*
X643514Y-300724D01*
X643489Y-300688D01*
X643460Y-300648D01*
X643431Y-300604D01*
X643405Y-300553D01*
X643380Y-300498D01*
X643354Y-300440D01*
X643336Y-300378D01*
X643322Y-300309D01*
X643311Y-300236D01*
X643307Y-300160D01*
Y-300127D01*
X643311Y-300102D01*
X643314Y-300073D01*
X643318Y-300040D01*
X643322Y-300000D01*
X643332Y-299960D01*
X643354Y-299869D01*
X643387Y-299778D01*
X643409Y-299730D01*
X643434Y-299683D01*
X643464Y-299639D01*
X643496Y-299596D01*
X643500Y-299592D01*
X643504Y-299585D01*
X643518Y-299577D01*
X643533Y-299563D01*
X643551Y-299545D01*
X643573Y-299527D01*
X643602Y-299505D01*
X643635Y-299486D01*
X643667Y-299465D01*
X643707Y-299443D01*
X643795Y-299403D01*
X643897Y-299370D01*
X643951Y-299359D01*
X644010Y-299352D01*
X644035Y-299676D01*
D02*
G37*
G36*
X553744Y-126713D02*
X552288D01*
X552284D01*
X552273D01*
X552255D01*
X552233D01*
X552208Y-126716D01*
X552175D01*
X552106Y-126720D01*
X552026Y-126727D01*
X551945Y-126738D01*
X551869Y-126753D01*
X551836Y-126760D01*
X551803Y-126771D01*
X551796Y-126775D01*
X551778Y-126782D01*
X551753Y-126800D01*
X551716Y-126822D01*
X551680Y-126848D01*
X551640Y-126884D01*
X551600Y-126927D01*
X551567Y-126979D01*
X551563Y-126986D01*
X551552Y-127004D01*
X551541Y-127037D01*
X551527Y-127080D01*
X551509Y-127131D01*
X551498Y-127197D01*
X551487Y-127266D01*
X551483Y-127342D01*
Y-127379D01*
X551487Y-127401D01*
Y-127434D01*
X551490Y-127466D01*
X551505Y-127546D01*
X551523Y-127634D01*
X551552Y-127717D01*
X551592Y-127797D01*
X551618Y-127834D01*
X551647Y-127867D01*
X551651Y-127870D01*
X551654Y-127874D01*
X551665Y-127881D01*
X551680Y-127892D01*
X551702Y-127903D01*
X551723Y-127918D01*
X551756Y-127932D01*
X551789Y-127947D01*
X551829Y-127961D01*
X551876Y-127972D01*
X551931Y-127987D01*
X551989Y-127998D01*
X552055Y-128009D01*
X552124Y-128016D01*
X552204Y-128023D01*
X552288D01*
X553744D01*
Y-128358D01*
X552288D01*
X552284D01*
X552269D01*
X552251D01*
X552226D01*
X552193Y-128354D01*
X552157D01*
X552113Y-128351D01*
X552069Y-128347D01*
X551971Y-128336D01*
X551869Y-128322D01*
X551771Y-128300D01*
X551723Y-128285D01*
X551680Y-128271D01*
X551676D01*
X551669Y-128267D01*
X551658Y-128260D01*
X551643Y-128252D01*
X551603Y-128231D01*
X551552Y-128198D01*
X551494Y-128154D01*
X551436Y-128103D01*
X551374Y-128038D01*
X551319Y-127958D01*
Y-127954D01*
X551312Y-127947D01*
X551308Y-127936D01*
X551298Y-127918D01*
X551287Y-127896D01*
X551276Y-127867D01*
X551265Y-127838D01*
X551250Y-127801D01*
X551236Y-127761D01*
X551225Y-127717D01*
X551214Y-127670D01*
X551203Y-127615D01*
X551196Y-127561D01*
X551188Y-127503D01*
X551181Y-127372D01*
Y-127339D01*
X551185Y-127313D01*
Y-127284D01*
X551188Y-127248D01*
X551192Y-127208D01*
X551196Y-127168D01*
X551210Y-127077D01*
X551232Y-126979D01*
X551261Y-126884D01*
X551301Y-126793D01*
Y-126789D01*
X551308Y-126782D01*
X551316Y-126771D01*
X551323Y-126757D01*
X551352Y-126716D01*
X551392Y-126669D01*
X551443Y-126614D01*
X551501Y-126564D01*
X551574Y-126513D01*
X551654Y-126472D01*
X551658D01*
X551665Y-126469D01*
X551680Y-126465D01*
X551698Y-126458D01*
X551720Y-126451D01*
X551749Y-126443D01*
X551782Y-126433D01*
X551822Y-126425D01*
X551865Y-126418D01*
X551913Y-126407D01*
X551964Y-126400D01*
X552018Y-126392D01*
X552080Y-126385D01*
X552146Y-126382D01*
X552215Y-126378D01*
X552288D01*
X553744D01*
Y-126713D01*
D02*
G37*
G36*
X551294Y-128747D02*
X551327Y-128751D01*
X551363Y-128759D01*
X551399Y-128766D01*
X551440Y-128780D01*
X551443D01*
X551447Y-128784D01*
X551469Y-128791D01*
X551501Y-128806D01*
X551545Y-128828D01*
X551596Y-128857D01*
X551654Y-128893D01*
X551713Y-128933D01*
X551774Y-128984D01*
X551778D01*
X551782Y-128991D01*
X551803Y-129010D01*
X551836Y-129042D01*
X551884Y-129090D01*
X551938Y-129144D01*
X552004Y-129214D01*
X552076Y-129297D01*
X552153Y-129388D01*
X552157Y-129392D01*
X552168Y-129406D01*
X552186Y-129428D01*
X552208Y-129454D01*
X552237Y-129487D01*
X552269Y-129526D01*
X552306Y-129567D01*
X552346Y-129614D01*
X552433Y-129705D01*
X552521Y-129796D01*
X552564Y-129840D01*
X552608Y-129880D01*
X552648Y-129916D01*
X552688Y-129945D01*
X552692D01*
X552695Y-129952D01*
X552706Y-129960D01*
X552721Y-129967D01*
X552761Y-129992D01*
X552808Y-130022D01*
X552866Y-130047D01*
X552928Y-130072D01*
X552997Y-130087D01*
X553063Y-130094D01*
X553067D01*
X553070D01*
X553092Y-130091D01*
X553128Y-130087D01*
X553168Y-130076D01*
X553219Y-130062D01*
X553270Y-130036D01*
X553321Y-130003D01*
X553372Y-129960D01*
X553380Y-129952D01*
X553394Y-129934D01*
X553412Y-129909D01*
X553438Y-129869D01*
X553460Y-129818D01*
X553481Y-129760D01*
X553496Y-129690D01*
X553500Y-129614D01*
Y-129592D01*
X553496Y-129578D01*
X553492Y-129534D01*
X553481Y-129483D01*
X553467Y-129428D01*
X553441Y-129366D01*
X553409Y-129308D01*
X553365Y-129253D01*
X553358Y-129246D01*
X553340Y-129232D01*
X553310Y-129210D01*
X553267Y-129188D01*
X553216Y-129163D01*
X553150Y-129141D01*
X553078Y-129126D01*
X552994Y-129119D01*
X553026Y-128802D01*
X553030D01*
X553041Y-128806D01*
X553059D01*
X553085Y-128809D01*
X553114Y-128817D01*
X553147Y-128824D01*
X553187Y-128835D01*
X553227Y-128846D01*
X553314Y-128875D01*
X553402Y-128919D01*
X553445Y-128944D01*
X553489Y-128977D01*
X553529Y-129010D01*
X553565Y-129046D01*
X553569Y-129050D01*
X553573Y-129057D01*
X553583Y-129068D01*
X553594Y-129086D01*
X553609Y-129108D01*
X553623Y-129133D01*
X553642Y-129163D01*
X553660Y-129199D01*
X553678Y-129239D01*
X553696Y-129283D01*
X553711Y-129330D01*
X553725Y-129381D01*
X553736Y-129436D01*
X553747Y-129494D01*
X553751Y-129556D01*
X553755Y-129621D01*
Y-129657D01*
X553751Y-129683D01*
X553747Y-129712D01*
X553744Y-129748D01*
X553736Y-129789D01*
X553729Y-129829D01*
X553704Y-129923D01*
X553667Y-130018D01*
X553645Y-130065D01*
X553620Y-130113D01*
X553587Y-130156D01*
X553551Y-130196D01*
X553547Y-130200D01*
X553543Y-130207D01*
X553529Y-130215D01*
X553514Y-130229D01*
X553496Y-130247D01*
X553471Y-130265D01*
X553445Y-130284D01*
X553412Y-130306D01*
X553343Y-130342D01*
X553256Y-130378D01*
X553212Y-130393D01*
X553161Y-130400D01*
X553110Y-130407D01*
X553056Y-130411D01*
X553048D01*
X553030D01*
X553001Y-130407D01*
X552961Y-130404D01*
X552917Y-130396D01*
X552866Y-130382D01*
X552812Y-130367D01*
X552757Y-130345D01*
X552750Y-130342D01*
X552732Y-130335D01*
X552703Y-130320D01*
X552663Y-130298D01*
X552619Y-130269D01*
X552564Y-130233D01*
X552510Y-130189D01*
X552448Y-130138D01*
X552441Y-130131D01*
X552419Y-130113D01*
X552400Y-130094D01*
X552382Y-130076D01*
X552360Y-130054D01*
X552331Y-130025D01*
X552302Y-129996D01*
X552269Y-129960D01*
X552233Y-129923D01*
X552193Y-129880D01*
X552153Y-129832D01*
X552106Y-129781D01*
X552058Y-129723D01*
X552007Y-129665D01*
X552004Y-129661D01*
X551996Y-129654D01*
X551986Y-129639D01*
X551971Y-129621D01*
X551949Y-129599D01*
X551927Y-129574D01*
X551880Y-129516D01*
X551825Y-129454D01*
X551771Y-129395D01*
X551723Y-129344D01*
X551705Y-129323D01*
X551687Y-129305D01*
X551683Y-129301D01*
X551673Y-129290D01*
X551658Y-129275D01*
X551636Y-129257D01*
X551611Y-129239D01*
X551585Y-129217D01*
X551523Y-129173D01*
Y-130415D01*
X551225D01*
Y-128744D01*
X551228D01*
X551243D01*
X551265D01*
X551294Y-128747D01*
D02*
G37*
G36*
X533532Y-133862D02*
X533565D01*
X533605Y-133865D01*
X533648Y-133873D01*
X533699Y-133880D01*
X533805Y-133898D01*
X533914Y-133927D01*
X534023Y-133967D01*
X534074Y-133993D01*
X534125Y-134022D01*
X534129Y-134026D01*
X534136Y-134029D01*
X534151Y-134040D01*
X534165Y-134055D01*
X534187Y-134069D01*
X534212Y-134091D01*
X534242Y-134117D01*
X534271Y-134146D01*
X534300Y-134178D01*
X534333Y-134211D01*
X534398Y-134295D01*
X534460Y-134393D01*
X534515Y-134502D01*
Y-134506D01*
X534522Y-134517D01*
X534526Y-134535D01*
X534537Y-134557D01*
X534544Y-134586D01*
X534555Y-134623D01*
X534569Y-134663D01*
X534580Y-134706D01*
X534591Y-134754D01*
X534606Y-134808D01*
X534624Y-134921D01*
X534638Y-135048D01*
X534646Y-135179D01*
Y-135183D01*
Y-135198D01*
Y-135220D01*
X534642Y-135245D01*
Y-135282D01*
X534638Y-135318D01*
X534635Y-135365D01*
X534627Y-135413D01*
X534609Y-135518D01*
X534584Y-135635D01*
X534547Y-135751D01*
X534496Y-135864D01*
X534493Y-135868D01*
X534489Y-135878D01*
X534482Y-135893D01*
X534467Y-135911D01*
X534453Y-135937D01*
X534435Y-135966D01*
X534387Y-136031D01*
X534325Y-136104D01*
X534253Y-136177D01*
X534169Y-136250D01*
X534071Y-136312D01*
X534067Y-136315D01*
X534056Y-136319D01*
X534042Y-136326D01*
X534023Y-136337D01*
X533994Y-136348D01*
X533965Y-136359D01*
X533929Y-136373D01*
X533889Y-136388D01*
X533845Y-136403D01*
X533798Y-136417D01*
X533696Y-136439D01*
X533579Y-136457D01*
X533459Y-136465D01*
X533423D01*
X533397Y-136461D01*
X533364Y-136457D01*
X533324Y-136453D01*
X533284Y-136450D01*
X533237Y-136439D01*
X533139Y-136417D01*
X533030Y-136384D01*
X532975Y-136363D01*
X532924Y-136337D01*
X532873Y-136304D01*
X532822Y-136272D01*
X532818Y-136268D01*
X532811Y-136264D01*
X532797Y-136253D01*
X532778Y-136235D01*
X532760Y-136217D01*
X532735Y-136191D01*
X532709Y-136162D01*
X532680Y-136133D01*
X532651Y-136097D01*
X532622Y-136053D01*
X532589Y-136010D01*
X532560Y-135962D01*
X532535Y-135907D01*
X532505Y-135853D01*
X532483Y-135795D01*
X532462Y-135729D01*
X532789Y-135653D01*
Y-135656D01*
X532793Y-135664D01*
X532800Y-135678D01*
X532807Y-135696D01*
X532815Y-135718D01*
X532826Y-135747D01*
X532855Y-135806D01*
X532891Y-135871D01*
X532935Y-135937D01*
X532990Y-135998D01*
X533048Y-136053D01*
X533055Y-136060D01*
X533077Y-136075D01*
X533113Y-136093D01*
X533161Y-136119D01*
X533222Y-136141D01*
X533292Y-136162D01*
X533375Y-136177D01*
X533466Y-136180D01*
X533496D01*
X533514Y-136177D01*
X533539D01*
X533568Y-136173D01*
X533637Y-136162D01*
X533714Y-136148D01*
X533794Y-136122D01*
X533878Y-136086D01*
X533954Y-136039D01*
X533958D01*
X533961Y-136031D01*
X533987Y-136013D01*
X534020Y-135984D01*
X534060Y-135940D01*
X534107Y-135886D01*
X534151Y-135824D01*
X534191Y-135747D01*
X534227Y-135664D01*
Y-135660D01*
X534231Y-135653D01*
X534234Y-135642D01*
X534238Y-135624D01*
X534245Y-135602D01*
X534253Y-135576D01*
X534264Y-135514D01*
X534278Y-135442D01*
X534293Y-135362D01*
X534300Y-135274D01*
X534304Y-135179D01*
Y-135176D01*
Y-135165D01*
Y-135147D01*
Y-135125D01*
X534300Y-135099D01*
Y-135067D01*
X534296Y-135030D01*
X534293Y-134990D01*
X534282Y-134903D01*
X534264Y-134808D01*
X534242Y-134714D01*
X534212Y-134619D01*
Y-134615D01*
X534209Y-134608D01*
X534202Y-134597D01*
X534194Y-134579D01*
X534172Y-134535D01*
X534140Y-134484D01*
X534100Y-134426D01*
X534049Y-134364D01*
X533990Y-134310D01*
X533921Y-134259D01*
X533918D01*
X533910Y-134255D01*
X533899Y-134248D01*
X533885Y-134240D01*
X533867Y-134233D01*
X533845Y-134222D01*
X533794Y-134200D01*
X533728Y-134178D01*
X533656Y-134160D01*
X533575Y-134146D01*
X533492Y-134142D01*
X533466D01*
X533444Y-134146D01*
X533419D01*
X533393Y-134149D01*
X533328Y-134164D01*
X533252Y-134182D01*
X533175Y-134211D01*
X533095Y-134251D01*
X533055Y-134273D01*
X533019Y-134302D01*
X533015Y-134306D01*
X533011Y-134310D01*
X533000Y-134320D01*
X532986Y-134331D01*
X532971Y-134350D01*
X532953Y-134371D01*
X532931Y-134393D01*
X532913Y-134422D01*
X532891Y-134455D01*
X532866Y-134492D01*
X532844Y-134528D01*
X532822Y-134572D01*
X532804Y-134619D01*
X532786Y-134670D01*
X532767Y-134724D01*
X532753Y-134783D01*
X532418Y-134699D01*
Y-134695D01*
X532422Y-134681D01*
X532429Y-134659D01*
X532440Y-134630D01*
X532451Y-134597D01*
X532465Y-134557D01*
X532483Y-134513D01*
X532505Y-134466D01*
X532556Y-134364D01*
X532622Y-134262D01*
X532662Y-134211D01*
X532702Y-134160D01*
X532746Y-134117D01*
X532797Y-134073D01*
X532800Y-134069D01*
X532807Y-134062D01*
X532826Y-134055D01*
X532844Y-134040D01*
X532873Y-134022D01*
X532902Y-134004D01*
X532942Y-133986D01*
X532982Y-133967D01*
X533030Y-133946D01*
X533080Y-133927D01*
X533135Y-133909D01*
X533193Y-133891D01*
X533255Y-133876D01*
X533321Y-133869D01*
X533390Y-133862D01*
X533463Y-133858D01*
X533503D01*
X533532Y-133862D01*
D02*
G37*
G36*
X532178Y-133905D02*
Y-133920D01*
Y-133942D01*
X532174Y-133971D01*
X532170Y-134004D01*
X532163Y-134040D01*
X532156Y-134077D01*
X532141Y-134117D01*
Y-134120D01*
X532138Y-134124D01*
X532130Y-134146D01*
X532116Y-134178D01*
X532094Y-134222D01*
X532065Y-134273D01*
X532028Y-134331D01*
X531988Y-134390D01*
X531938Y-134451D01*
Y-134455D01*
X531930Y-134459D01*
X531912Y-134481D01*
X531879Y-134513D01*
X531832Y-134561D01*
X531777Y-134615D01*
X531708Y-134681D01*
X531625Y-134754D01*
X531533Y-134830D01*
X531530Y-134834D01*
X531515Y-134845D01*
X531494Y-134863D01*
X531468Y-134885D01*
X531435Y-134914D01*
X531395Y-134947D01*
X531355Y-134983D01*
X531308Y-135023D01*
X531217Y-135110D01*
X531126Y-135198D01*
X531082Y-135241D01*
X531042Y-135285D01*
X531006Y-135325D01*
X530977Y-135365D01*
Y-135369D01*
X530969Y-135372D01*
X530962Y-135383D01*
X530955Y-135398D01*
X530929Y-135438D01*
X530900Y-135485D01*
X530875Y-135544D01*
X530849Y-135605D01*
X530835Y-135675D01*
X530827Y-135740D01*
Y-135744D01*
Y-135747D01*
X530831Y-135769D01*
X530835Y-135806D01*
X530845Y-135846D01*
X530860Y-135897D01*
X530886Y-135948D01*
X530918Y-135998D01*
X530962Y-136049D01*
X530969Y-136057D01*
X530988Y-136071D01*
X531013Y-136090D01*
X531053Y-136115D01*
X531104Y-136137D01*
X531162Y-136159D01*
X531231Y-136173D01*
X531308Y-136177D01*
X531330D01*
X531344Y-136173D01*
X531388Y-136170D01*
X531439Y-136159D01*
X531494Y-136144D01*
X531555Y-136119D01*
X531614Y-136086D01*
X531668Y-136042D01*
X531675Y-136035D01*
X531690Y-136017D01*
X531712Y-135988D01*
X531734Y-135944D01*
X531759Y-135893D01*
X531781Y-135828D01*
X531796Y-135755D01*
X531803Y-135671D01*
X532120Y-135704D01*
Y-135707D01*
X532116Y-135718D01*
Y-135737D01*
X532112Y-135762D01*
X532105Y-135791D01*
X532098Y-135824D01*
X532087Y-135864D01*
X532076Y-135904D01*
X532047Y-135991D01*
X532003Y-136079D01*
X531978Y-136122D01*
X531945Y-136166D01*
X531912Y-136206D01*
X531876Y-136242D01*
X531872Y-136246D01*
X531865Y-136250D01*
X531854Y-136261D01*
X531836Y-136272D01*
X531814Y-136286D01*
X531788Y-136301D01*
X531759Y-136319D01*
X531723Y-136337D01*
X531683Y-136355D01*
X531639Y-136373D01*
X531592Y-136388D01*
X531541Y-136403D01*
X531486Y-136414D01*
X531428Y-136424D01*
X531366Y-136428D01*
X531300Y-136432D01*
X531264D01*
X531239Y-136428D01*
X531210Y-136424D01*
X531173Y-136421D01*
X531133Y-136414D01*
X531093Y-136406D01*
X530998Y-136381D01*
X530904Y-136344D01*
X530857Y-136322D01*
X530809Y-136297D01*
X530765Y-136264D01*
X530725Y-136228D01*
X530722Y-136224D01*
X530715Y-136221D01*
X530707Y-136206D01*
X530693Y-136191D01*
X530675Y-136173D01*
X530656Y-136148D01*
X530638Y-136122D01*
X530616Y-136090D01*
X530580Y-136020D01*
X530543Y-135933D01*
X530529Y-135889D01*
X530522Y-135838D01*
X530514Y-135787D01*
X530511Y-135733D01*
Y-135725D01*
Y-135707D01*
X530514Y-135678D01*
X530518Y-135638D01*
X530525Y-135594D01*
X530540Y-135544D01*
X530554Y-135489D01*
X530576Y-135434D01*
X530580Y-135427D01*
X530587Y-135409D01*
X530602Y-135380D01*
X530623Y-135340D01*
X530653Y-135296D01*
X530689Y-135241D01*
X530733Y-135187D01*
X530784Y-135125D01*
X530791Y-135118D01*
X530809Y-135096D01*
X530827Y-135078D01*
X530845Y-135059D01*
X530867Y-135038D01*
X530897Y-135009D01*
X530926Y-134979D01*
X530962Y-134947D01*
X530998Y-134910D01*
X531042Y-134870D01*
X531089Y-134830D01*
X531140Y-134783D01*
X531199Y-134736D01*
X531257Y-134685D01*
X531260Y-134681D01*
X531268Y-134674D01*
X531282Y-134663D01*
X531300Y-134648D01*
X531322Y-134626D01*
X531348Y-134604D01*
X531406Y-134557D01*
X531468Y-134502D01*
X531526Y-134448D01*
X531577Y-134401D01*
X531599Y-134382D01*
X531617Y-134364D01*
X531621Y-134361D01*
X531632Y-134350D01*
X531646Y-134335D01*
X531665Y-134313D01*
X531683Y-134288D01*
X531705Y-134262D01*
X531748Y-134200D01*
X530507D01*
Y-133902D01*
X532178D01*
Y-133905D01*
D02*
G37*
G36*
X529415Y-133862D02*
X529444Y-133865D01*
X529481Y-133873D01*
X529521Y-133880D01*
X529564Y-133891D01*
X529608Y-133905D01*
X529655Y-133920D01*
X529703Y-133942D01*
X529750Y-133967D01*
X529797Y-133996D01*
X529845Y-134033D01*
X529888Y-134073D01*
X529928Y-134117D01*
X529932Y-134120D01*
X529939Y-134131D01*
X529950Y-134149D01*
X529968Y-134178D01*
X529986Y-134211D01*
X530005Y-134255D01*
X530030Y-134306D01*
X530052Y-134364D01*
X530074Y-134430D01*
X530096Y-134506D01*
X530118Y-134590D01*
X530136Y-134685D01*
X530154Y-134786D01*
X530165Y-134896D01*
X530172Y-135016D01*
X530176Y-135143D01*
Y-135147D01*
Y-135161D01*
Y-135187D01*
Y-135216D01*
X530172Y-135256D01*
Y-135300D01*
X530168Y-135347D01*
X530165Y-135402D01*
X530154Y-135514D01*
X530136Y-135635D01*
X530114Y-135755D01*
X530099Y-135809D01*
X530085Y-135864D01*
Y-135868D01*
X530081Y-135875D01*
X530074Y-135889D01*
X530067Y-135907D01*
X530059Y-135933D01*
X530045Y-135959D01*
X530016Y-136020D01*
X529979Y-136086D01*
X529932Y-136155D01*
X529877Y-136224D01*
X529812Y-136283D01*
X529808D01*
X529805Y-136290D01*
X529794Y-136297D01*
X529779Y-136304D01*
X529761Y-136319D01*
X529739Y-136330D01*
X529684Y-136359D01*
X529619Y-136384D01*
X529542Y-136410D01*
X529451Y-136424D01*
X529353Y-136432D01*
X529320D01*
X529280Y-136428D01*
X529233Y-136421D01*
X529178Y-136410D01*
X529120Y-136395D01*
X529058Y-136377D01*
X529000Y-136348D01*
X528996D01*
X528993Y-136344D01*
X528975Y-136333D01*
X528945Y-136315D01*
X528909Y-136290D01*
X528869Y-136253D01*
X528825Y-136213D01*
X528785Y-136166D01*
X528745Y-136111D01*
X528742Y-136104D01*
X528727Y-136086D01*
X528713Y-136053D01*
X528687Y-136006D01*
X528665Y-135951D01*
X528636Y-135889D01*
X528611Y-135817D01*
X528589Y-135737D01*
Y-135733D01*
X528585Y-135725D01*
X528581Y-135715D01*
X528578Y-135696D01*
X528574Y-135675D01*
X528571Y-135649D01*
X528563Y-135616D01*
X528560Y-135580D01*
X528552Y-135540D01*
X528549Y-135496D01*
X528545Y-135445D01*
X528538Y-135394D01*
X528534Y-135336D01*
Y-135278D01*
X528531Y-135212D01*
Y-135143D01*
Y-135140D01*
Y-135125D01*
Y-135099D01*
Y-135070D01*
X528534Y-135030D01*
Y-134987D01*
X528538Y-134939D01*
X528541Y-134888D01*
X528552Y-134772D01*
X528571Y-134652D01*
X528592Y-134535D01*
X528607Y-134481D01*
X528625Y-134426D01*
Y-134422D01*
X528629Y-134415D01*
X528636Y-134401D01*
X528643Y-134382D01*
X528651Y-134357D01*
X528665Y-134331D01*
X528694Y-134269D01*
X528731Y-134204D01*
X528778Y-134131D01*
X528833Y-134066D01*
X528898Y-134004D01*
X528902D01*
X528905Y-133996D01*
X528916Y-133989D01*
X528931Y-133982D01*
X528949Y-133971D01*
X528967Y-133957D01*
X529022Y-133931D01*
X529087Y-133905D01*
X529164Y-133880D01*
X529255Y-133865D01*
X529353Y-133858D01*
X529389D01*
X529415Y-133862D01*
D02*
G37*
G36*
X502273Y-107273D02*
X502299D01*
X502328Y-107276D01*
X502397Y-107291D01*
X502473Y-107309D01*
X502554Y-107338D01*
X502634Y-107382D01*
X502674Y-107407D01*
X502710Y-107437D01*
X502714Y-107440D01*
X502717Y-107444D01*
X502728Y-107455D01*
X502739Y-107466D01*
X502757Y-107484D01*
X502772Y-107506D01*
X502812Y-107557D01*
X502852Y-107622D01*
X502888Y-107702D01*
X502921Y-107793D01*
X502943Y-107895D01*
X502634Y-107921D01*
Y-107917D01*
X502630Y-107913D01*
X502626Y-107891D01*
X502615Y-107859D01*
X502601Y-107819D01*
X502586Y-107775D01*
X502564Y-107731D01*
X502539Y-107691D01*
X502514Y-107659D01*
X502506Y-107651D01*
X502492Y-107637D01*
X502466Y-107615D01*
X502430Y-107589D01*
X502382Y-107568D01*
X502331Y-107546D01*
X502270Y-107531D01*
X502204Y-107524D01*
X502179D01*
X502149Y-107527D01*
X502117Y-107535D01*
X502073Y-107546D01*
X502029Y-107560D01*
X501986Y-107579D01*
X501942Y-107608D01*
X501935Y-107611D01*
X501917Y-107626D01*
X501891Y-107651D01*
X501858Y-107688D01*
X501822Y-107731D01*
X501782Y-107782D01*
X501745Y-107848D01*
X501709Y-107921D01*
Y-107924D01*
X501705Y-107932D01*
X501702Y-107942D01*
X501694Y-107957D01*
X501691Y-107979D01*
X501684Y-108004D01*
X501676Y-108034D01*
X501669Y-108070D01*
X501658Y-108110D01*
X501651Y-108154D01*
X501644Y-108201D01*
X501640Y-108252D01*
X501633Y-108310D01*
X501629Y-108368D01*
X501625Y-108434D01*
Y-108499D01*
X501629Y-108496D01*
X501644Y-108474D01*
X501669Y-108445D01*
X501702Y-108408D01*
X501738Y-108365D01*
X501786Y-108325D01*
X501836Y-108285D01*
X501895Y-108248D01*
X501898D01*
X501902Y-108245D01*
X501924Y-108234D01*
X501957Y-108223D01*
X502000Y-108205D01*
X502051Y-108190D01*
X502109Y-108179D01*
X502171Y-108168D01*
X502237Y-108165D01*
X502266D01*
X502288Y-108168D01*
X502317Y-108172D01*
X502346Y-108176D01*
X502382Y-108183D01*
X502419Y-108194D01*
X502502Y-108219D01*
X502546Y-108237D01*
X502590Y-108263D01*
X502634Y-108288D01*
X502681Y-108317D01*
X502725Y-108354D01*
X502765Y-108394D01*
X502768Y-108397D01*
X502775Y-108405D01*
X502786Y-108416D01*
X502797Y-108434D01*
X502816Y-108459D01*
X502834Y-108485D01*
X502852Y-108518D01*
X502874Y-108554D01*
X502896Y-108594D01*
X502914Y-108638D01*
X502932Y-108689D01*
X502950Y-108740D01*
X502961Y-108794D01*
X502972Y-108856D01*
X502979Y-108918D01*
X502983Y-108984D01*
Y-108987D01*
Y-108994D01*
Y-109005D01*
Y-109024D01*
X502979Y-109045D01*
Y-109067D01*
X502969Y-109125D01*
X502957Y-109195D01*
X502939Y-109267D01*
X502914Y-109347D01*
X502878Y-109424D01*
Y-109428D01*
X502874Y-109431D01*
X502867Y-109442D01*
X502859Y-109457D01*
X502837Y-109493D01*
X502805Y-109540D01*
X502765Y-109591D01*
X502717Y-109642D01*
X502659Y-109693D01*
X502597Y-109737D01*
X502594D01*
X502590Y-109741D01*
X502579Y-109748D01*
X502564Y-109752D01*
X502528Y-109770D01*
X502481Y-109788D01*
X502419Y-109810D01*
X502350Y-109824D01*
X502273Y-109839D01*
X502189Y-109843D01*
X502171D01*
X502153Y-109839D01*
X502124D01*
X502091Y-109835D01*
X502055Y-109828D01*
X502011Y-109817D01*
X501967Y-109806D01*
X501917Y-109792D01*
X501865Y-109773D01*
X501815Y-109752D01*
X501760Y-109722D01*
X501709Y-109690D01*
X501658Y-109653D01*
X501607Y-109610D01*
X501560Y-109559D01*
X501556Y-109555D01*
X501549Y-109544D01*
X501538Y-109529D01*
X501523Y-109504D01*
X501502Y-109471D01*
X501483Y-109435D01*
X501462Y-109388D01*
X501440Y-109337D01*
X501414Y-109275D01*
X501392Y-109206D01*
X501374Y-109129D01*
X501356Y-109045D01*
X501338Y-108951D01*
X501327Y-108849D01*
X501320Y-108740D01*
X501316Y-108623D01*
Y-108619D01*
Y-108616D01*
Y-108605D01*
Y-108590D01*
X501320Y-108554D01*
Y-108503D01*
X501323Y-108445D01*
X501331Y-108376D01*
X501338Y-108299D01*
X501349Y-108215D01*
X501363Y-108132D01*
X501381Y-108041D01*
X501403Y-107953D01*
X501429Y-107866D01*
X501462Y-107782D01*
X501498Y-107702D01*
X501538Y-107626D01*
X501585Y-107560D01*
X501589Y-107557D01*
X501596Y-107549D01*
X501611Y-107535D01*
X501629Y-107513D01*
X501651Y-107491D01*
X501680Y-107469D01*
X501716Y-107440D01*
X501753Y-107415D01*
X501796Y-107389D01*
X501844Y-107360D01*
X501898Y-107338D01*
X501953Y-107313D01*
X502015Y-107295D01*
X502080Y-107280D01*
X502149Y-107273D01*
X502222Y-107269D01*
X502251D01*
X502273Y-107273D01*
D02*
G37*
G36*
X500067Y-107240D02*
X500100Y-107244D01*
X500140Y-107247D01*
X500180Y-107251D01*
X500227Y-107262D01*
X500326Y-107284D01*
X500435Y-107316D01*
X500490Y-107338D01*
X500541Y-107364D01*
X500592Y-107396D01*
X500642Y-107429D01*
X500646Y-107433D01*
X500653Y-107437D01*
X500668Y-107448D01*
X500686Y-107466D01*
X500704Y-107484D01*
X500730Y-107509D01*
X500755Y-107538D01*
X500784Y-107568D01*
X500814Y-107604D01*
X500843Y-107648D01*
X500876Y-107691D01*
X500905Y-107739D01*
X500930Y-107793D01*
X500959Y-107848D01*
X500981Y-107906D01*
X501003Y-107972D01*
X500675Y-108048D01*
Y-108044D01*
X500672Y-108037D01*
X500664Y-108023D01*
X500657Y-108004D01*
X500650Y-107983D01*
X500639Y-107953D01*
X500610Y-107895D01*
X500573Y-107830D01*
X500530Y-107764D01*
X500475Y-107702D01*
X500417Y-107648D01*
X500410Y-107640D01*
X500388Y-107626D01*
X500351Y-107608D01*
X500304Y-107582D01*
X500242Y-107560D01*
X500173Y-107538D01*
X500089Y-107524D01*
X499998Y-107520D01*
X499969D01*
X499951Y-107524D01*
X499925D01*
X499896Y-107527D01*
X499827Y-107538D01*
X499751Y-107553D01*
X499671Y-107579D01*
X499587Y-107615D01*
X499510Y-107662D01*
X499507D01*
X499503Y-107669D01*
X499478Y-107688D01*
X499445Y-107717D01*
X499405Y-107761D01*
X499358Y-107815D01*
X499314Y-107877D01*
X499274Y-107953D01*
X499237Y-108037D01*
Y-108041D01*
X499234Y-108048D01*
X499230Y-108059D01*
X499227Y-108077D01*
X499219Y-108099D01*
X499212Y-108124D01*
X499201Y-108186D01*
X499187Y-108259D01*
X499172Y-108339D01*
X499165Y-108427D01*
X499161Y-108521D01*
Y-108525D01*
Y-108536D01*
Y-108554D01*
Y-108576D01*
X499165Y-108601D01*
Y-108634D01*
X499168Y-108670D01*
X499172Y-108711D01*
X499183Y-108798D01*
X499201Y-108893D01*
X499223Y-108987D01*
X499252Y-109082D01*
Y-109085D01*
X499256Y-109093D01*
X499263Y-109104D01*
X499270Y-109122D01*
X499292Y-109166D01*
X499325Y-109216D01*
X499365Y-109275D01*
X499416Y-109337D01*
X499474Y-109391D01*
X499543Y-109442D01*
X499547D01*
X499554Y-109446D01*
X499565Y-109453D01*
X499580Y-109460D01*
X499598Y-109468D01*
X499620Y-109479D01*
X499671Y-109500D01*
X499736Y-109522D01*
X499809Y-109540D01*
X499889Y-109555D01*
X499973Y-109559D01*
X499998D01*
X500020Y-109555D01*
X500045D01*
X500071Y-109551D01*
X500137Y-109537D01*
X500213Y-109519D01*
X500289Y-109490D01*
X500370Y-109450D01*
X500410Y-109428D01*
X500446Y-109398D01*
X500450Y-109395D01*
X500453Y-109391D01*
X500464Y-109380D01*
X500479Y-109369D01*
X500493Y-109351D01*
X500511Y-109329D01*
X500533Y-109308D01*
X500552Y-109278D01*
X500573Y-109246D01*
X500599Y-109209D01*
X500621Y-109173D01*
X500642Y-109129D01*
X500661Y-109082D01*
X500679Y-109031D01*
X500697Y-108976D01*
X500712Y-108918D01*
X501047Y-109002D01*
Y-109005D01*
X501043Y-109020D01*
X501036Y-109042D01*
X501025Y-109071D01*
X501014Y-109104D01*
X500999Y-109144D01*
X500981Y-109187D01*
X500959Y-109235D01*
X500908Y-109337D01*
X500843Y-109439D01*
X500803Y-109490D01*
X500763Y-109540D01*
X500719Y-109584D01*
X500668Y-109628D01*
X500664Y-109631D01*
X500657Y-109639D01*
X500639Y-109646D01*
X500621Y-109661D01*
X500592Y-109679D01*
X500562Y-109697D01*
X500522Y-109715D01*
X500482Y-109733D01*
X500435Y-109755D01*
X500384Y-109773D01*
X500329Y-109792D01*
X500271Y-109810D01*
X500209Y-109824D01*
X500144Y-109832D01*
X500075Y-109839D01*
X500002Y-109843D01*
X499962D01*
X499933Y-109839D01*
X499900D01*
X499860Y-109835D01*
X499816Y-109828D01*
X499765Y-109821D01*
X499660Y-109802D01*
X499550Y-109773D01*
X499441Y-109733D01*
X499390Y-109708D01*
X499339Y-109679D01*
X499336Y-109675D01*
X499328Y-109671D01*
X499314Y-109661D01*
X499299Y-109646D01*
X499277Y-109631D01*
X499252Y-109610D01*
X499223Y-109584D01*
X499194Y-109555D01*
X499165Y-109522D01*
X499132Y-109490D01*
X499066Y-109406D01*
X499005Y-109308D01*
X498950Y-109198D01*
Y-109195D01*
X498943Y-109184D01*
X498939Y-109166D01*
X498928Y-109144D01*
X498921Y-109115D01*
X498910Y-109078D01*
X498895Y-109038D01*
X498884Y-108994D01*
X498873Y-108947D01*
X498859Y-108893D01*
X498841Y-108780D01*
X498826Y-108652D01*
X498819Y-108521D01*
Y-108518D01*
Y-108503D01*
Y-108481D01*
X498822Y-108456D01*
Y-108419D01*
X498826Y-108383D01*
X498830Y-108336D01*
X498837Y-108288D01*
X498855Y-108183D01*
X498881Y-108066D01*
X498917Y-107950D01*
X498968Y-107837D01*
X498972Y-107833D01*
X498975Y-107822D01*
X498983Y-107808D01*
X498997Y-107790D01*
X499012Y-107764D01*
X499030Y-107735D01*
X499077Y-107669D01*
X499139Y-107597D01*
X499212Y-107524D01*
X499296Y-107451D01*
X499394Y-107389D01*
X499398Y-107386D01*
X499408Y-107382D01*
X499423Y-107375D01*
X499441Y-107364D01*
X499470Y-107353D01*
X499500Y-107342D01*
X499536Y-107327D01*
X499576Y-107313D01*
X499620Y-107298D01*
X499667Y-107284D01*
X499769Y-107262D01*
X499885Y-107244D01*
X500005Y-107236D01*
X500042D01*
X500067Y-107240D01*
D02*
G37*
G36*
X504839Y-107608D02*
X503831D01*
X503696Y-108288D01*
X503700Y-108285D01*
X503707Y-108281D01*
X503718Y-108274D01*
X503736Y-108263D01*
X503758Y-108252D01*
X503784Y-108237D01*
X503842Y-108208D01*
X503915Y-108179D01*
X503995Y-108154D01*
X504082Y-108135D01*
X504126Y-108128D01*
X504206D01*
X504228Y-108132D01*
X504257Y-108135D01*
X504290Y-108139D01*
X504326Y-108146D01*
X504366Y-108157D01*
X504454Y-108183D01*
X504501Y-108201D01*
X504548Y-108226D01*
X504596Y-108252D01*
X504643Y-108281D01*
X504686Y-108317D01*
X504730Y-108357D01*
X504734Y-108361D01*
X504741Y-108368D01*
X504752Y-108379D01*
X504767Y-108397D01*
X504785Y-108423D01*
X504803Y-108449D01*
X504825Y-108481D01*
X504847Y-108518D01*
X504865Y-108558D01*
X504887Y-108601D01*
X504905Y-108652D01*
X504923Y-108703D01*
X504938Y-108758D01*
X504949Y-108820D01*
X504956Y-108882D01*
X504959Y-108947D01*
Y-108951D01*
Y-108962D01*
Y-108980D01*
X504956Y-109005D01*
X504952Y-109035D01*
X504949Y-109067D01*
X504941Y-109107D01*
X504934Y-109147D01*
X504912Y-109242D01*
X504876Y-109340D01*
X504854Y-109391D01*
X504825Y-109439D01*
X504796Y-109490D01*
X504759Y-109537D01*
X504756Y-109540D01*
X504748Y-109551D01*
X504734Y-109566D01*
X504716Y-109584D01*
X504690Y-109606D01*
X504661Y-109635D01*
X504625Y-109661D01*
X504585Y-109690D01*
X504541Y-109719D01*
X504490Y-109744D01*
X504435Y-109770D01*
X504377Y-109795D01*
X504315Y-109813D01*
X504246Y-109828D01*
X504173Y-109839D01*
X504097Y-109843D01*
X504064D01*
X504039Y-109839D01*
X504009Y-109835D01*
X503977Y-109832D01*
X503937Y-109828D01*
X503897Y-109817D01*
X503806Y-109795D01*
X503715Y-109763D01*
X503667Y-109741D01*
X503620Y-109715D01*
X503576Y-109686D01*
X503533Y-109653D01*
X503529Y-109650D01*
X503522Y-109646D01*
X503514Y-109631D01*
X503500Y-109617D01*
X503482Y-109599D01*
X503464Y-109577D01*
X503442Y-109548D01*
X503423Y-109515D01*
X503402Y-109482D01*
X503380Y-109442D01*
X503340Y-109355D01*
X503307Y-109253D01*
X503296Y-109198D01*
X503289Y-109140D01*
X503613Y-109115D01*
Y-109118D01*
Y-109125D01*
X503616Y-109136D01*
X503620Y-109155D01*
X503631Y-109195D01*
X503646Y-109249D01*
X503667Y-109304D01*
X503696Y-109366D01*
X503733Y-109420D01*
X503777Y-109471D01*
X503784Y-109475D01*
X503798Y-109490D01*
X503827Y-109508D01*
X503867Y-109529D01*
X503911Y-109551D01*
X503966Y-109570D01*
X504028Y-109584D01*
X504097Y-109588D01*
X504119D01*
X504133Y-109584D01*
X504177Y-109581D01*
X504228Y-109566D01*
X504290Y-109548D01*
X504352Y-109519D01*
X504417Y-109475D01*
X504446Y-109450D01*
X504475Y-109420D01*
X504479Y-109417D01*
X504483Y-109413D01*
X504490Y-109402D01*
X504501Y-109391D01*
X504526Y-109351D01*
X504556Y-109300D01*
X504581Y-109238D01*
X504606Y-109162D01*
X504625Y-109071D01*
X504632Y-109024D01*
Y-108973D01*
Y-108969D01*
Y-108962D01*
Y-108947D01*
X504628Y-108929D01*
Y-108907D01*
X504625Y-108882D01*
X504614Y-108823D01*
X504596Y-108754D01*
X504570Y-108685D01*
X504534Y-108619D01*
X504483Y-108558D01*
Y-108554D01*
X504475Y-108550D01*
X504457Y-108532D01*
X504424Y-108507D01*
X504381Y-108478D01*
X504322Y-108452D01*
X504257Y-108427D01*
X504181Y-108408D01*
X504137Y-108401D01*
X504068D01*
X504039Y-108405D01*
X504002Y-108408D01*
X503959Y-108419D01*
X503915Y-108430D01*
X503867Y-108449D01*
X503820Y-108470D01*
X503817Y-108474D01*
X503802Y-108481D01*
X503780Y-108499D01*
X503751Y-108518D01*
X503722Y-108543D01*
X503693Y-108576D01*
X503660Y-108609D01*
X503635Y-108649D01*
X503343Y-108609D01*
X503587Y-107313D01*
X504839D01*
Y-107608D01*
D02*
G37*
G36*
X490798Y-122776D02*
X489342D01*
X489338D01*
X489327D01*
X489309D01*
X489287D01*
X489262Y-122780D01*
X489229D01*
X489160Y-122783D01*
X489080Y-122790D01*
X489000Y-122801D01*
X488923Y-122816D01*
X488891Y-122823D01*
X488858Y-122834D01*
X488850Y-122838D01*
X488832Y-122845D01*
X488807Y-122863D01*
X488770Y-122885D01*
X488734Y-122910D01*
X488694Y-122947D01*
X488654Y-122991D01*
X488621Y-123042D01*
X488618Y-123049D01*
X488607Y-123067D01*
X488596Y-123100D01*
X488581Y-123143D01*
X488563Y-123194D01*
X488552Y-123260D01*
X488541Y-123329D01*
X488537Y-123406D01*
Y-123442D01*
X488541Y-123464D01*
Y-123497D01*
X488545Y-123529D01*
X488559Y-123609D01*
X488577Y-123697D01*
X488607Y-123781D01*
X488647Y-123861D01*
X488672Y-123897D01*
X488701Y-123930D01*
X488705Y-123933D01*
X488708Y-123937D01*
X488719Y-123944D01*
X488734Y-123955D01*
X488756Y-123966D01*
X488778Y-123981D01*
X488810Y-123995D01*
X488843Y-124010D01*
X488883Y-124024D01*
X488931Y-124035D01*
X488985Y-124050D01*
X489043Y-124061D01*
X489109Y-124072D01*
X489178Y-124079D01*
X489258Y-124086D01*
X489342D01*
X490798D01*
Y-124421D01*
X489342D01*
X489338D01*
X489324D01*
X489305D01*
X489280D01*
X489247Y-124417D01*
X489211D01*
X489167Y-124414D01*
X489123Y-124410D01*
X489025Y-124399D01*
X488923Y-124385D01*
X488825Y-124363D01*
X488778Y-124348D01*
X488734Y-124334D01*
X488730D01*
X488723Y-124330D01*
X488712Y-124323D01*
X488697Y-124316D01*
X488658Y-124294D01*
X488607Y-124261D01*
X488548Y-124217D01*
X488490Y-124166D01*
X488428Y-124101D01*
X488374Y-124021D01*
Y-124017D01*
X488366Y-124010D01*
X488363Y-123999D01*
X488352Y-123981D01*
X488341Y-123959D01*
X488330Y-123930D01*
X488319Y-123901D01*
X488304Y-123864D01*
X488290Y-123824D01*
X488279Y-123781D01*
X488268Y-123733D01*
X488257Y-123679D01*
X488250Y-123624D01*
X488243Y-123566D01*
X488235Y-123435D01*
Y-123402D01*
X488239Y-123376D01*
Y-123347D01*
X488243Y-123311D01*
X488246Y-123271D01*
X488250Y-123231D01*
X488264Y-123140D01*
X488286Y-123042D01*
X488315Y-122947D01*
X488355Y-122856D01*
Y-122852D01*
X488363Y-122845D01*
X488370Y-122834D01*
X488377Y-122819D01*
X488406Y-122780D01*
X488446Y-122732D01*
X488497Y-122678D01*
X488556Y-122627D01*
X488628Y-122576D01*
X488708Y-122536D01*
X488712D01*
X488719Y-122532D01*
X488734Y-122528D01*
X488752Y-122521D01*
X488774Y-122514D01*
X488803Y-122506D01*
X488836Y-122496D01*
X488876Y-122488D01*
X488920Y-122481D01*
X488967Y-122470D01*
X489018Y-122463D01*
X489073Y-122456D01*
X489134Y-122448D01*
X489200Y-122445D01*
X489269Y-122441D01*
X489342D01*
X490798D01*
Y-122776D01*
D02*
G37*
G36*
X490175Y-125091D02*
X490183Y-125098D01*
X490186Y-125113D01*
X490197Y-125131D01*
X490208Y-125153D01*
X490223Y-125178D01*
X490259Y-125240D01*
X490299Y-125313D01*
X490350Y-125386D01*
X490408Y-125462D01*
X490470Y-125539D01*
X490474Y-125542D01*
X490478Y-125546D01*
X490488Y-125557D01*
X490499Y-125571D01*
X490536Y-125604D01*
X490579Y-125648D01*
X490630Y-125691D01*
X490689Y-125739D01*
X490747Y-125779D01*
X490809Y-125815D01*
Y-126015D01*
X488279D01*
Y-125706D01*
X490248D01*
X490244Y-125702D01*
X490230Y-125684D01*
X490208Y-125662D01*
X490183Y-125626D01*
X490150Y-125586D01*
X490113Y-125535D01*
X490073Y-125477D01*
X490033Y-125411D01*
Y-125408D01*
X490030Y-125404D01*
X490015Y-125382D01*
X489997Y-125346D01*
X489975Y-125302D01*
X489950Y-125251D01*
X489924Y-125196D01*
X489899Y-125142D01*
X489877Y-125087D01*
X490175D01*
Y-125091D01*
D02*
G37*
G36*
X488985Y-127122D02*
X488981D01*
X488974Y-127126D01*
X488960Y-127129D01*
X488941Y-127133D01*
X488920Y-127137D01*
X488894Y-127144D01*
X488839Y-127162D01*
X488774Y-127188D01*
X488712Y-127220D01*
X488654Y-127257D01*
X488603Y-127300D01*
X488599Y-127308D01*
X488585Y-127322D01*
X488566Y-127351D01*
X488548Y-127388D01*
X488526Y-127431D01*
X488508Y-127486D01*
X488494Y-127548D01*
X488490Y-127613D01*
Y-127635D01*
X488494Y-127650D01*
X488497Y-127690D01*
X488508Y-127741D01*
X488526Y-127799D01*
X488552Y-127861D01*
X488588Y-127923D01*
X488639Y-127981D01*
X488647Y-127988D01*
X488668Y-128006D01*
X488701Y-128028D01*
X488745Y-128058D01*
X488799Y-128087D01*
X488861Y-128108D01*
X488934Y-128127D01*
X489014Y-128134D01*
X489018D01*
X489025D01*
X489036D01*
X489051Y-128130D01*
X489091Y-128127D01*
X489138Y-128116D01*
X489196Y-128101D01*
X489255Y-128076D01*
X489313Y-128039D01*
X489367Y-127992D01*
X489375Y-127985D01*
X489389Y-127966D01*
X489411Y-127937D01*
X489436Y-127897D01*
X489462Y-127846D01*
X489484Y-127785D01*
X489498Y-127715D01*
X489506Y-127639D01*
Y-127606D01*
X489502Y-127581D01*
X489498Y-127548D01*
X489491Y-127512D01*
X489484Y-127468D01*
X489473Y-127420D01*
X489746Y-127457D01*
Y-127475D01*
X489742Y-127490D01*
Y-127537D01*
X489749Y-127577D01*
X489757Y-127624D01*
X489768Y-127679D01*
X489786Y-127741D01*
X489811Y-127799D01*
X489844Y-127861D01*
Y-127865D01*
X489848Y-127868D01*
X489862Y-127886D01*
X489888Y-127912D01*
X489921Y-127941D01*
X489968Y-127970D01*
X490023Y-127996D01*
X490084Y-128014D01*
X490121Y-128021D01*
X490161D01*
X490165D01*
X490168D01*
X490190D01*
X490219Y-128014D01*
X490259Y-128006D01*
X490303Y-127992D01*
X490350Y-127974D01*
X490397Y-127945D01*
X490441Y-127905D01*
X490445Y-127901D01*
X490459Y-127883D01*
X490478Y-127857D01*
X490499Y-127824D01*
X490518Y-127781D01*
X490536Y-127730D01*
X490550Y-127672D01*
X490554Y-127606D01*
Y-127577D01*
X490547Y-127544D01*
X490539Y-127500D01*
X490525Y-127453D01*
X490507Y-127406D01*
X490478Y-127355D01*
X490441Y-127308D01*
X490438Y-127304D01*
X490419Y-127289D01*
X490394Y-127268D01*
X490357Y-127242D01*
X490310Y-127217D01*
X490252Y-127191D01*
X490183Y-127169D01*
X490103Y-127155D01*
X490157Y-126845D01*
X490161D01*
X490172Y-126849D01*
X490186Y-126853D01*
X490208Y-126856D01*
X490234Y-126864D01*
X490263Y-126874D01*
X490332Y-126896D01*
X490412Y-126933D01*
X490492Y-126976D01*
X490568Y-127031D01*
X490638Y-127100D01*
X490641Y-127104D01*
X490645Y-127111D01*
X490652Y-127122D01*
X490663Y-127137D01*
X490678Y-127155D01*
X490692Y-127180D01*
X490707Y-127206D01*
X490725Y-127239D01*
X490754Y-127311D01*
X490783Y-127395D01*
X490801Y-127493D01*
X490809Y-127544D01*
Y-127635D01*
X490805Y-127675D01*
X490798Y-127723D01*
X490787Y-127781D01*
X490769Y-127846D01*
X490747Y-127912D01*
X490718Y-127977D01*
Y-127981D01*
X490714Y-127985D01*
X490703Y-128006D01*
X490681Y-128039D01*
X490656Y-128076D01*
X490620Y-128119D01*
X490579Y-128163D01*
X490532Y-128207D01*
X490478Y-128243D01*
X490470Y-128247D01*
X490452Y-128258D01*
X490419Y-128272D01*
X490379Y-128290D01*
X490332Y-128309D01*
X490277Y-128323D01*
X490215Y-128334D01*
X490154Y-128338D01*
X490146D01*
X490124D01*
X490095Y-128334D01*
X490055Y-128327D01*
X490008Y-128316D01*
X489957Y-128298D01*
X489906Y-128276D01*
X489855Y-128247D01*
X489848Y-128243D01*
X489833Y-128232D01*
X489808Y-128210D01*
X489779Y-128181D01*
X489746Y-128145D01*
X489710Y-128101D01*
X489677Y-128050D01*
X489644Y-127988D01*
Y-127992D01*
X489640Y-127999D01*
X489637Y-128010D01*
X489633Y-128025D01*
X489618Y-128065D01*
X489597Y-128116D01*
X489568Y-128174D01*
X489531Y-128232D01*
X489484Y-128287D01*
X489429Y-128338D01*
X489422Y-128341D01*
X489400Y-128356D01*
X489364Y-128378D01*
X489316Y-128400D01*
X489258Y-128421D01*
X489189Y-128443D01*
X489109Y-128458D01*
X489021Y-128462D01*
X489018D01*
X489007D01*
X488989D01*
X488967Y-128458D01*
X488938Y-128454D01*
X488905Y-128447D01*
X488869Y-128440D01*
X488829Y-128432D01*
X488741Y-128403D01*
X488694Y-128381D01*
X488650Y-128360D01*
X488603Y-128331D01*
X488556Y-128298D01*
X488508Y-128261D01*
X488465Y-128218D01*
X488461Y-128214D01*
X488454Y-128207D01*
X488443Y-128192D01*
X488428Y-128174D01*
X488410Y-128152D01*
X488392Y-128123D01*
X488370Y-128090D01*
X488352Y-128050D01*
X488330Y-128010D01*
X488308Y-127963D01*
X488290Y-127916D01*
X488272Y-127861D01*
X488257Y-127803D01*
X488246Y-127741D01*
X488239Y-127679D01*
X488235Y-127610D01*
Y-127577D01*
X488239Y-127555D01*
X488243Y-127526D01*
X488246Y-127493D01*
X488253Y-127457D01*
X488261Y-127417D01*
X488283Y-127330D01*
X488319Y-127239D01*
X488341Y-127191D01*
X488366Y-127147D01*
X488399Y-127104D01*
X488432Y-127060D01*
X488436Y-127057D01*
X488443Y-127049D01*
X488454Y-127038D01*
X488468Y-127027D01*
X488486Y-127009D01*
X488512Y-126991D01*
X488537Y-126969D01*
X488570Y-126947D01*
X488607Y-126925D01*
X488643Y-126904D01*
X488730Y-126864D01*
X488832Y-126831D01*
X488887Y-126820D01*
X488945Y-126813D01*
X488985Y-127122D01*
D02*
G37*
G36*
X47200Y-34944D02*
X47197D01*
X47182D01*
X47160D01*
X47131Y-34940D01*
X47098Y-34937D01*
X47062Y-34929D01*
X47026Y-34922D01*
X46986Y-34907D01*
X46982D01*
X46978Y-34904D01*
X46957Y-34897D01*
X46924Y-34882D01*
X46880Y-34860D01*
X46829Y-34831D01*
X46771Y-34795D01*
X46713Y-34755D01*
X46651Y-34704D01*
X46647D01*
X46643Y-34696D01*
X46622Y-34678D01*
X46589Y-34645D01*
X46542Y-34598D01*
X46487Y-34543D01*
X46422Y-34474D01*
X46349Y-34391D01*
X46272Y-34300D01*
X46269Y-34296D01*
X46258Y-34281D01*
X46240Y-34260D01*
X46218Y-34234D01*
X46189Y-34201D01*
X46156Y-34161D01*
X46119Y-34121D01*
X46079Y-34074D01*
X45992Y-33983D01*
X45905Y-33892D01*
X45861Y-33848D01*
X45817Y-33808D01*
X45777Y-33772D01*
X45737Y-33743D01*
X45733D01*
X45730Y-33735D01*
X45719Y-33728D01*
X45704Y-33721D01*
X45664Y-33695D01*
X45617Y-33666D01*
X45559Y-33641D01*
X45497Y-33615D01*
X45428Y-33601D01*
X45362Y-33593D01*
X45359D01*
X45355D01*
X45333Y-33597D01*
X45297Y-33601D01*
X45257Y-33612D01*
X45206Y-33626D01*
X45155Y-33652D01*
X45104Y-33684D01*
X45053Y-33728D01*
X45046Y-33735D01*
X45031Y-33754D01*
X45013Y-33779D01*
X44987Y-33819D01*
X44965Y-33870D01*
X44944Y-33928D01*
X44929Y-33997D01*
X44925Y-34074D01*
Y-34096D01*
X44929Y-34110D01*
X44933Y-34154D01*
X44944Y-34205D01*
X44958Y-34260D01*
X44984Y-34321D01*
X45016Y-34380D01*
X45060Y-34434D01*
X45067Y-34442D01*
X45086Y-34456D01*
X45115Y-34478D01*
X45158Y-34500D01*
X45209Y-34525D01*
X45275Y-34547D01*
X45348Y-34562D01*
X45431Y-34569D01*
X45399Y-34886D01*
X45395D01*
X45384Y-34882D01*
X45366D01*
X45340Y-34878D01*
X45311Y-34871D01*
X45278Y-34864D01*
X45239Y-34853D01*
X45198Y-34842D01*
X45111Y-34813D01*
X45024Y-34769D01*
X44980Y-34744D01*
X44936Y-34711D01*
X44896Y-34678D01*
X44860Y-34642D01*
X44856Y-34638D01*
X44853Y-34631D01*
X44842Y-34620D01*
X44831Y-34602D01*
X44816Y-34580D01*
X44802Y-34554D01*
X44783Y-34525D01*
X44765Y-34489D01*
X44747Y-34449D01*
X44729Y-34405D01*
X44714Y-34358D01*
X44700Y-34307D01*
X44689Y-34252D01*
X44678Y-34194D01*
X44674Y-34132D01*
X44671Y-34067D01*
Y-34030D01*
X44674Y-34005D01*
X44678Y-33976D01*
X44682Y-33939D01*
X44689Y-33899D01*
X44696Y-33859D01*
X44722Y-33764D01*
X44758Y-33670D01*
X44780Y-33623D01*
X44805Y-33575D01*
X44838Y-33532D01*
X44875Y-33492D01*
X44878Y-33488D01*
X44882Y-33481D01*
X44896Y-33473D01*
X44911Y-33459D01*
X44929Y-33441D01*
X44955Y-33422D01*
X44980Y-33404D01*
X45013Y-33382D01*
X45082Y-33346D01*
X45169Y-33310D01*
X45213Y-33295D01*
X45264Y-33288D01*
X45315Y-33280D01*
X45369Y-33277D01*
X45377D01*
X45395D01*
X45424Y-33280D01*
X45464Y-33284D01*
X45508Y-33291D01*
X45559Y-33306D01*
X45613Y-33320D01*
X45668Y-33342D01*
X45675Y-33346D01*
X45693Y-33353D01*
X45723Y-33368D01*
X45763Y-33390D01*
X45806Y-33419D01*
X45861Y-33455D01*
X45915Y-33499D01*
X45977Y-33550D01*
X45985Y-33557D01*
X46007Y-33575D01*
X46025Y-33593D01*
X46043Y-33612D01*
X46065Y-33634D01*
X46094Y-33663D01*
X46123Y-33692D01*
X46156Y-33728D01*
X46192Y-33764D01*
X46232Y-33808D01*
X46272Y-33856D01*
X46320Y-33906D01*
X46367Y-33965D01*
X46418Y-34023D01*
X46422Y-34027D01*
X46429Y-34034D01*
X46440Y-34049D01*
X46454Y-34067D01*
X46476Y-34089D01*
X46498Y-34114D01*
X46545Y-34172D01*
X46600Y-34234D01*
X46654Y-34292D01*
X46702Y-34343D01*
X46720Y-34365D01*
X46738Y-34383D01*
X46742Y-34387D01*
X46753Y-34398D01*
X46767Y-34413D01*
X46789Y-34431D01*
X46815Y-34449D01*
X46840Y-34471D01*
X46902Y-34514D01*
Y-33273D01*
X47200D01*
Y-34944D01*
D02*
G37*
G36*
X46596Y-35559D02*
X47200D01*
Y-35868D01*
X46596D01*
Y-36964D01*
X46312D01*
X44682Y-35810D01*
Y-35559D01*
X46312D01*
Y-35217D01*
X46596D01*
Y-35559D01*
D02*
G37*
G36*
X46422Y-37146D02*
X46443Y-37153D01*
X46472Y-37164D01*
X46505Y-37175D01*
X46545Y-37190D01*
X46589Y-37208D01*
X46636Y-37230D01*
X46738Y-37281D01*
X46840Y-37346D01*
X46891Y-37386D01*
X46942Y-37426D01*
X46986Y-37470D01*
X47029Y-37521D01*
X47033Y-37525D01*
X47040Y-37532D01*
X47048Y-37550D01*
X47062Y-37568D01*
X47080Y-37597D01*
X47098Y-37627D01*
X47117Y-37667D01*
X47135Y-37707D01*
X47157Y-37754D01*
X47175Y-37805D01*
X47193Y-37859D01*
X47211Y-37918D01*
X47226Y-37980D01*
X47233Y-38045D01*
X47240Y-38114D01*
X47244Y-38187D01*
Y-38227D01*
X47240Y-38256D01*
Y-38289D01*
X47237Y-38329D01*
X47230Y-38373D01*
X47222Y-38424D01*
X47204Y-38529D01*
X47175Y-38638D01*
X47135Y-38748D01*
X47109Y-38799D01*
X47080Y-38850D01*
X47077Y-38853D01*
X47073Y-38860D01*
X47062Y-38875D01*
X47048Y-38890D01*
X47033Y-38912D01*
X47011Y-38937D01*
X46986Y-38966D01*
X46957Y-38995D01*
X46924Y-39024D01*
X46891Y-39057D01*
X46807Y-39123D01*
X46709Y-39184D01*
X46600Y-39239D01*
X46596D01*
X46585Y-39246D01*
X46567Y-39250D01*
X46545Y-39261D01*
X46516Y-39268D01*
X46480Y-39279D01*
X46440Y-39294D01*
X46396Y-39305D01*
X46349Y-39316D01*
X46294Y-39330D01*
X46181Y-39348D01*
X46054Y-39363D01*
X45923Y-39370D01*
X45919D01*
X45905D01*
X45883D01*
X45857Y-39366D01*
X45821D01*
X45785Y-39363D01*
X45737Y-39359D01*
X45690Y-39352D01*
X45584Y-39334D01*
X45468Y-39308D01*
X45351Y-39272D01*
X45239Y-39221D01*
X45235Y-39217D01*
X45224Y-39214D01*
X45209Y-39206D01*
X45191Y-39192D01*
X45166Y-39177D01*
X45137Y-39159D01*
X45071Y-39112D01*
X44998Y-39050D01*
X44925Y-38977D01*
X44853Y-38893D01*
X44791Y-38795D01*
X44787Y-38791D01*
X44783Y-38781D01*
X44776Y-38766D01*
X44765Y-38748D01*
X44754Y-38719D01*
X44743Y-38689D01*
X44729Y-38653D01*
X44714Y-38613D01*
X44700Y-38569D01*
X44685Y-38522D01*
X44663Y-38420D01*
X44645Y-38304D01*
X44638Y-38184D01*
Y-38147D01*
X44642Y-38122D01*
X44645Y-38089D01*
X44649Y-38049D01*
X44652Y-38009D01*
X44663Y-37962D01*
X44685Y-37863D01*
X44718Y-37754D01*
X44740Y-37699D01*
X44765Y-37648D01*
X44798Y-37597D01*
X44831Y-37547D01*
X44834Y-37543D01*
X44838Y-37536D01*
X44849Y-37521D01*
X44867Y-37503D01*
X44885Y-37485D01*
X44911Y-37459D01*
X44940Y-37434D01*
X44969Y-37405D01*
X45006Y-37375D01*
X45049Y-37346D01*
X45093Y-37314D01*
X45140Y-37284D01*
X45195Y-37259D01*
X45249Y-37230D01*
X45308Y-37208D01*
X45373Y-37186D01*
X45450Y-37514D01*
X45446D01*
X45439Y-37517D01*
X45424Y-37525D01*
X45406Y-37532D01*
X45384Y-37539D01*
X45355Y-37550D01*
X45297Y-37579D01*
X45231Y-37616D01*
X45166Y-37659D01*
X45104Y-37714D01*
X45049Y-37772D01*
X45042Y-37780D01*
X45027Y-37801D01*
X45009Y-37838D01*
X44984Y-37885D01*
X44962Y-37947D01*
X44940Y-38016D01*
X44925Y-38100D01*
X44922Y-38191D01*
Y-38220D01*
X44925Y-38238D01*
Y-38264D01*
X44929Y-38293D01*
X44940Y-38362D01*
X44955Y-38438D01*
X44980Y-38518D01*
X45016Y-38602D01*
X45064Y-38679D01*
Y-38682D01*
X45071Y-38686D01*
X45089Y-38711D01*
X45118Y-38744D01*
X45162Y-38784D01*
X45217Y-38831D01*
X45278Y-38875D01*
X45355Y-38915D01*
X45439Y-38952D01*
X45442D01*
X45450Y-38955D01*
X45461Y-38959D01*
X45479Y-38963D01*
X45501Y-38970D01*
X45526Y-38977D01*
X45588Y-38988D01*
X45661Y-39002D01*
X45741Y-39017D01*
X45828Y-39024D01*
X45923Y-39028D01*
X45926D01*
X45937D01*
X45956D01*
X45977D01*
X46003Y-39024D01*
X46036D01*
X46072Y-39021D01*
X46112Y-39017D01*
X46199Y-39006D01*
X46294Y-38988D01*
X46389Y-38966D01*
X46483Y-38937D01*
X46487D01*
X46494Y-38933D01*
X46505Y-38926D01*
X46523Y-38919D01*
X46567Y-38897D01*
X46618Y-38864D01*
X46676Y-38824D01*
X46738Y-38773D01*
X46793Y-38715D01*
X46844Y-38646D01*
Y-38642D01*
X46847Y-38635D01*
X46855Y-38624D01*
X46862Y-38609D01*
X46869Y-38591D01*
X46880Y-38569D01*
X46902Y-38518D01*
X46924Y-38453D01*
X46942Y-38380D01*
X46957Y-38300D01*
X46960Y-38216D01*
Y-38191D01*
X46957Y-38169D01*
Y-38144D01*
X46953Y-38118D01*
X46938Y-38052D01*
X46920Y-37976D01*
X46891Y-37900D01*
X46851Y-37819D01*
X46829Y-37780D01*
X46800Y-37743D01*
X46796Y-37739D01*
X46793Y-37736D01*
X46782Y-37725D01*
X46771Y-37710D01*
X46753Y-37696D01*
X46731Y-37677D01*
X46709Y-37656D01*
X46680Y-37637D01*
X46647Y-37616D01*
X46611Y-37590D01*
X46574Y-37568D01*
X46531Y-37547D01*
X46483Y-37528D01*
X46432Y-37510D01*
X46378Y-37492D01*
X46320Y-37477D01*
X46403Y-37143D01*
X46407D01*
X46422Y-37146D01*
D02*
G37*
G36*
X124366Y-35620D02*
X122397D01*
X122400Y-35623D01*
X122415Y-35641D01*
X122437Y-35663D01*
X122462Y-35700D01*
X122495Y-35740D01*
X122531Y-35791D01*
X122571Y-35849D01*
X122611Y-35914D01*
Y-35918D01*
X122615Y-35922D01*
X122629Y-35944D01*
X122648Y-35980D01*
X122670Y-36024D01*
X122695Y-36075D01*
X122721Y-36129D01*
X122746Y-36184D01*
X122768Y-36238D01*
X122469D01*
Y-36235D01*
X122462Y-36228D01*
X122458Y-36213D01*
X122448Y-36195D01*
X122437Y-36173D01*
X122422Y-36147D01*
X122386Y-36086D01*
X122346Y-36013D01*
X122295Y-35940D01*
X122236Y-35864D01*
X122175Y-35787D01*
X122171Y-35783D01*
X122167Y-35780D01*
X122156Y-35769D01*
X122145Y-35754D01*
X122109Y-35721D01*
X122065Y-35678D01*
X122014Y-35634D01*
X121956Y-35587D01*
X121898Y-35547D01*
X121836Y-35510D01*
Y-35310D01*
X124366D01*
Y-35620D01*
D02*
G37*
G36*
X123762Y-37134D02*
X124366D01*
Y-37443D01*
X123762D01*
Y-38539D01*
X123478D01*
X121847Y-37385D01*
Y-37134D01*
X123478D01*
Y-36792D01*
X123762D01*
Y-37134D01*
D02*
G37*
G36*
X123587Y-38721D02*
X123609Y-38728D01*
X123638Y-38739D01*
X123671Y-38750D01*
X123711Y-38765D01*
X123754Y-38783D01*
X123802Y-38805D01*
X123904Y-38856D01*
X124005Y-38921D01*
X124056Y-38961D01*
X124107Y-39001D01*
X124151Y-39045D01*
X124195Y-39096D01*
X124198Y-39099D01*
X124206Y-39107D01*
X124213Y-39125D01*
X124227Y-39143D01*
X124246Y-39172D01*
X124264Y-39201D01*
X124282Y-39241D01*
X124300Y-39281D01*
X124322Y-39329D01*
X124340Y-39380D01*
X124358Y-39434D01*
X124377Y-39493D01*
X124391Y-39555D01*
X124399Y-39620D01*
X124406Y-39689D01*
X124409Y-39762D01*
Y-39802D01*
X124406Y-39831D01*
Y-39864D01*
X124402Y-39904D01*
X124395Y-39948D01*
X124388Y-39998D01*
X124369Y-40104D01*
X124340Y-40213D01*
X124300Y-40323D01*
X124275Y-40374D01*
X124246Y-40424D01*
X124242Y-40428D01*
X124238Y-40435D01*
X124227Y-40450D01*
X124213Y-40464D01*
X124198Y-40486D01*
X124177Y-40512D01*
X124151Y-40541D01*
X124122Y-40570D01*
X124089Y-40599D01*
X124056Y-40632D01*
X123973Y-40697D01*
X123874Y-40759D01*
X123765Y-40814D01*
X123762D01*
X123751Y-40821D01*
X123732Y-40825D01*
X123711Y-40836D01*
X123681Y-40843D01*
X123645Y-40854D01*
X123605Y-40868D01*
X123561Y-40879D01*
X123514Y-40890D01*
X123459Y-40905D01*
X123347Y-40923D01*
X123219Y-40938D01*
X123088Y-40945D01*
X123084D01*
X123070D01*
X123048D01*
X123023Y-40941D01*
X122986D01*
X122950Y-40938D01*
X122903Y-40934D01*
X122855Y-40927D01*
X122750Y-40909D01*
X122633Y-40883D01*
X122517Y-40847D01*
X122404Y-40796D01*
X122400Y-40792D01*
X122389Y-40788D01*
X122375Y-40781D01*
X122356Y-40767D01*
X122331Y-40752D01*
X122302Y-40734D01*
X122236Y-40687D01*
X122164Y-40625D01*
X122091Y-40552D01*
X122018Y-40468D01*
X121956Y-40370D01*
X121952Y-40366D01*
X121949Y-40355D01*
X121942Y-40341D01*
X121931Y-40323D01*
X121920Y-40293D01*
X121909Y-40264D01*
X121894Y-40228D01*
X121880Y-40188D01*
X121865Y-40144D01*
X121851Y-40097D01*
X121829Y-39995D01*
X121810Y-39878D01*
X121803Y-39758D01*
Y-39722D01*
X121807Y-39696D01*
X121810Y-39664D01*
X121814Y-39624D01*
X121818Y-39584D01*
X121829Y-39536D01*
X121851Y-39438D01*
X121883Y-39329D01*
X121905Y-39274D01*
X121931Y-39223D01*
X121963Y-39172D01*
X121996Y-39121D01*
X122000Y-39118D01*
X122003Y-39110D01*
X122014Y-39096D01*
X122033Y-39078D01*
X122051Y-39059D01*
X122076Y-39034D01*
X122105Y-39008D01*
X122134Y-38979D01*
X122171Y-38950D01*
X122215Y-38921D01*
X122258Y-38888D01*
X122306Y-38859D01*
X122360Y-38834D01*
X122415Y-38805D01*
X122473Y-38783D01*
X122538Y-38761D01*
X122615Y-39088D01*
X122611D01*
X122604Y-39092D01*
X122590Y-39099D01*
X122571Y-39107D01*
X122549Y-39114D01*
X122520Y-39125D01*
X122462Y-39154D01*
X122397Y-39190D01*
X122331Y-39234D01*
X122269Y-39289D01*
X122215Y-39347D01*
X122207Y-39354D01*
X122193Y-39376D01*
X122175Y-39413D01*
X122149Y-39460D01*
X122127Y-39522D01*
X122105Y-39591D01*
X122091Y-39675D01*
X122087Y-39766D01*
Y-39795D01*
X122091Y-39813D01*
Y-39838D01*
X122094Y-39867D01*
X122105Y-39937D01*
X122120Y-40013D01*
X122145Y-40093D01*
X122182Y-40177D01*
X122229Y-40253D01*
Y-40257D01*
X122236Y-40261D01*
X122255Y-40286D01*
X122284Y-40319D01*
X122327Y-40359D01*
X122382Y-40406D01*
X122444Y-40450D01*
X122520Y-40490D01*
X122604Y-40526D01*
X122608D01*
X122615Y-40530D01*
X122626Y-40534D01*
X122644Y-40537D01*
X122666Y-40545D01*
X122691Y-40552D01*
X122753Y-40563D01*
X122826Y-40577D01*
X122906Y-40592D01*
X122994Y-40599D01*
X123088Y-40603D01*
X123092D01*
X123103D01*
X123121D01*
X123143D01*
X123168Y-40599D01*
X123201D01*
X123237Y-40595D01*
X123277Y-40592D01*
X123365Y-40581D01*
X123459Y-40563D01*
X123554Y-40541D01*
X123649Y-40512D01*
X123652D01*
X123660Y-40508D01*
X123671Y-40501D01*
X123689Y-40494D01*
X123732Y-40472D01*
X123783Y-40439D01*
X123842Y-40399D01*
X123904Y-40348D01*
X123958Y-40290D01*
X124009Y-40221D01*
Y-40217D01*
X124013Y-40210D01*
X124020Y-40199D01*
X124027Y-40184D01*
X124035Y-40166D01*
X124046Y-40144D01*
X124067Y-40093D01*
X124089Y-40028D01*
X124107Y-39955D01*
X124122Y-39875D01*
X124126Y-39791D01*
Y-39766D01*
X124122Y-39744D01*
Y-39718D01*
X124118Y-39693D01*
X124104Y-39627D01*
X124085Y-39551D01*
X124056Y-39474D01*
X124016Y-39394D01*
X123995Y-39354D01*
X123965Y-39318D01*
X123962Y-39314D01*
X123958Y-39311D01*
X123947Y-39300D01*
X123936Y-39285D01*
X123918Y-39270D01*
X123896Y-39252D01*
X123874Y-39230D01*
X123845Y-39212D01*
X123812Y-39190D01*
X123776Y-39165D01*
X123740Y-39143D01*
X123696Y-39121D01*
X123649Y-39103D01*
X123598Y-39085D01*
X123543Y-39067D01*
X123485Y-39052D01*
X123569Y-38717D01*
X123572D01*
X123587Y-38721D01*
D02*
G37*
G36*
X673129Y-54123D02*
X673155D01*
X673184Y-54127D01*
X673253Y-54141D01*
X673329Y-54159D01*
X673410Y-54189D01*
X673490Y-54232D01*
X673530Y-54258D01*
X673566Y-54287D01*
X673570Y-54291D01*
X673573Y-54294D01*
X673584Y-54305D01*
X673595Y-54316D01*
X673613Y-54334D01*
X673628Y-54356D01*
X673668Y-54407D01*
X673708Y-54473D01*
X673744Y-54553D01*
X673777Y-54644D01*
X673799Y-54746D01*
X673490Y-54771D01*
Y-54767D01*
X673486Y-54764D01*
X673482Y-54742D01*
X673471Y-54709D01*
X673457Y-54669D01*
X673442Y-54625D01*
X673420Y-54582D01*
X673395Y-54542D01*
X673369Y-54509D01*
X673362Y-54502D01*
X673348Y-54487D01*
X673322Y-54465D01*
X673286Y-54440D01*
X673238Y-54418D01*
X673187Y-54396D01*
X673126Y-54382D01*
X673060Y-54374D01*
X673034D01*
X673005Y-54378D01*
X672973Y-54385D01*
X672929Y-54396D01*
X672885Y-54411D01*
X672842Y-54429D01*
X672798Y-54458D01*
X672791Y-54462D01*
X672773Y-54476D01*
X672747Y-54502D01*
X672714Y-54538D01*
X672678Y-54582D01*
X672638Y-54633D01*
X672601Y-54698D01*
X672565Y-54771D01*
Y-54775D01*
X672561Y-54782D01*
X672558Y-54793D01*
X672550Y-54807D01*
X672547Y-54829D01*
X672540Y-54855D01*
X672532Y-54884D01*
X672525Y-54920D01*
X672514Y-54960D01*
X672507Y-55004D01*
X672499Y-55051D01*
X672496Y-55102D01*
X672488Y-55160D01*
X672485Y-55219D01*
X672481Y-55284D01*
Y-55350D01*
X672485Y-55346D01*
X672499Y-55324D01*
X672525Y-55295D01*
X672558Y-55259D01*
X672594Y-55215D01*
X672641Y-55175D01*
X672692Y-55135D01*
X672751Y-55099D01*
X672754D01*
X672758Y-55095D01*
X672780Y-55084D01*
X672813Y-55073D01*
X672856Y-55055D01*
X672907Y-55040D01*
X672965Y-55029D01*
X673027Y-55019D01*
X673093Y-55015D01*
X673122D01*
X673144Y-55019D01*
X673173Y-55022D01*
X673202Y-55026D01*
X673238Y-55033D01*
X673275Y-55044D01*
X673358Y-55070D01*
X673402Y-55088D01*
X673446Y-55113D01*
X673490Y-55139D01*
X673537Y-55168D01*
X673581Y-55204D01*
X673621Y-55244D01*
X673624Y-55248D01*
X673631Y-55255D01*
X673642Y-55266D01*
X673653Y-55284D01*
X673671Y-55310D01*
X673690Y-55335D01*
X673708Y-55368D01*
X673730Y-55404D01*
X673752Y-55444D01*
X673770Y-55488D01*
X673788Y-55539D01*
X673806Y-55590D01*
X673817Y-55645D01*
X673828Y-55707D01*
X673835Y-55768D01*
X673839Y-55834D01*
Y-55838D01*
Y-55845D01*
Y-55856D01*
Y-55874D01*
X673835Y-55896D01*
Y-55918D01*
X673824Y-55976D01*
X673813Y-56045D01*
X673795Y-56118D01*
X673770Y-56198D01*
X673733Y-56274D01*
Y-56278D01*
X673730Y-56282D01*
X673723Y-56293D01*
X673715Y-56307D01*
X673693Y-56344D01*
X673661Y-56391D01*
X673621Y-56442D01*
X673573Y-56493D01*
X673515Y-56544D01*
X673453Y-56587D01*
X673450D01*
X673446Y-56591D01*
X673435Y-56598D01*
X673420Y-56602D01*
X673384Y-56620D01*
X673337Y-56638D01*
X673275Y-56660D01*
X673206Y-56675D01*
X673129Y-56689D01*
X673045Y-56693D01*
X673027D01*
X673009Y-56689D01*
X672980D01*
X672947Y-56686D01*
X672911Y-56678D01*
X672867Y-56668D01*
X672823Y-56657D01*
X672773Y-56642D01*
X672721Y-56624D01*
X672671Y-56602D01*
X672616Y-56573D01*
X672565Y-56540D01*
X672514Y-56504D01*
X672463Y-56460D01*
X672416Y-56409D01*
X672412Y-56405D01*
X672405Y-56394D01*
X672394Y-56380D01*
X672379Y-56354D01*
X672358Y-56322D01*
X672339Y-56285D01*
X672318Y-56238D01*
X672296Y-56187D01*
X672270Y-56125D01*
X672248Y-56056D01*
X672230Y-55980D01*
X672212Y-55896D01*
X672194Y-55801D01*
X672183Y-55699D01*
X672176Y-55590D01*
X672172Y-55474D01*
Y-55470D01*
Y-55466D01*
Y-55455D01*
Y-55441D01*
X672176Y-55404D01*
Y-55353D01*
X672179Y-55295D01*
X672186Y-55226D01*
X672194Y-55150D01*
X672205Y-55066D01*
X672219Y-54982D01*
X672237Y-54891D01*
X672259Y-54804D01*
X672285Y-54716D01*
X672318Y-54633D01*
X672354Y-54553D01*
X672394Y-54476D01*
X672441Y-54411D01*
X672445Y-54407D01*
X672452Y-54400D01*
X672467Y-54385D01*
X672485Y-54363D01*
X672507Y-54342D01*
X672536Y-54320D01*
X672572Y-54291D01*
X672609Y-54265D01*
X672652Y-54240D01*
X672700Y-54211D01*
X672754Y-54189D01*
X672809Y-54163D01*
X672871Y-54145D01*
X672936Y-54130D01*
X673005Y-54123D01*
X673078Y-54119D01*
X673107D01*
X673129Y-54123D01*
D02*
G37*
G36*
X668965Y-54090D02*
X668998Y-54094D01*
X669038Y-54098D01*
X669078Y-54101D01*
X669125Y-54112D01*
X669223Y-54134D01*
X669333Y-54167D01*
X669387Y-54189D01*
X669438Y-54214D01*
X669489Y-54247D01*
X669540Y-54280D01*
X669544Y-54283D01*
X669551Y-54287D01*
X669566Y-54298D01*
X669584Y-54316D01*
X669602Y-54334D01*
X669628Y-54360D01*
X669653Y-54389D01*
X669682Y-54418D01*
X669711Y-54454D01*
X669740Y-54498D01*
X669773Y-54542D01*
X669802Y-54589D01*
X669828Y-54644D01*
X669857Y-54698D01*
X669879Y-54756D01*
X669901Y-54822D01*
X669573Y-54898D01*
Y-54895D01*
X669569Y-54887D01*
X669562Y-54873D01*
X669555Y-54855D01*
X669547Y-54833D01*
X669536Y-54804D01*
X669507Y-54746D01*
X669471Y-54680D01*
X669427Y-54615D01*
X669373Y-54553D01*
X669314Y-54498D01*
X669307Y-54491D01*
X669285Y-54476D01*
X669249Y-54458D01*
X669202Y-54432D01*
X669140Y-54411D01*
X669071Y-54389D01*
X668987Y-54374D01*
X668896Y-54371D01*
X668867D01*
X668849Y-54374D01*
X668823D01*
X668794Y-54378D01*
X668725Y-54389D01*
X668648Y-54403D01*
X668568Y-54429D01*
X668484Y-54465D01*
X668408Y-54513D01*
X668404D01*
X668401Y-54520D01*
X668375Y-54538D01*
X668343Y-54567D01*
X668302Y-54611D01*
X668255Y-54665D01*
X668212Y-54727D01*
X668172Y-54804D01*
X668135Y-54887D01*
Y-54891D01*
X668131Y-54898D01*
X668128Y-54909D01*
X668124Y-54928D01*
X668117Y-54949D01*
X668110Y-54975D01*
X668099Y-55037D01*
X668084Y-55110D01*
X668070Y-55190D01*
X668062Y-55277D01*
X668059Y-55372D01*
Y-55375D01*
Y-55386D01*
Y-55404D01*
Y-55426D01*
X668062Y-55452D01*
Y-55484D01*
X668066Y-55521D01*
X668070Y-55561D01*
X668081Y-55648D01*
X668099Y-55743D01*
X668120Y-55838D01*
X668150Y-55932D01*
Y-55936D01*
X668153Y-55943D01*
X668161Y-55954D01*
X668168Y-55972D01*
X668190Y-56016D01*
X668223Y-56067D01*
X668262Y-56125D01*
X668314Y-56187D01*
X668372Y-56242D01*
X668441Y-56293D01*
X668444D01*
X668452Y-56296D01*
X668463Y-56304D01*
X668477Y-56311D01*
X668495Y-56318D01*
X668517Y-56329D01*
X668568Y-56351D01*
X668634Y-56373D01*
X668707Y-56391D01*
X668787Y-56405D01*
X668870Y-56409D01*
X668896D01*
X668918Y-56405D01*
X668943D01*
X668969Y-56402D01*
X669034Y-56387D01*
X669111Y-56369D01*
X669187Y-56340D01*
X669267Y-56300D01*
X669307Y-56278D01*
X669344Y-56249D01*
X669347Y-56245D01*
X669351Y-56242D01*
X669362Y-56231D01*
X669376Y-56220D01*
X669391Y-56202D01*
X669409Y-56180D01*
X669431Y-56158D01*
X669449Y-56129D01*
X669471Y-56096D01*
X669496Y-56060D01*
X669518Y-56023D01*
X669540Y-55980D01*
X669558Y-55932D01*
X669577Y-55881D01*
X669595Y-55827D01*
X669609Y-55768D01*
X669944Y-55852D01*
Y-55856D01*
X669941Y-55870D01*
X669933Y-55892D01*
X669922Y-55921D01*
X669911Y-55954D01*
X669897Y-55994D01*
X669879Y-56038D01*
X669857Y-56085D01*
X669806Y-56187D01*
X669740Y-56289D01*
X669700Y-56340D01*
X669660Y-56391D01*
X669617Y-56435D01*
X669566Y-56478D01*
X669562Y-56482D01*
X669555Y-56489D01*
X669536Y-56496D01*
X669518Y-56511D01*
X669489Y-56529D01*
X669460Y-56547D01*
X669420Y-56566D01*
X669380Y-56584D01*
X669333Y-56606D01*
X669282Y-56624D01*
X669227Y-56642D01*
X669169Y-56660D01*
X669107Y-56675D01*
X669041Y-56682D01*
X668972Y-56689D01*
X668899Y-56693D01*
X668859D01*
X668830Y-56689D01*
X668798D01*
X668757Y-56686D01*
X668714Y-56678D01*
X668663Y-56671D01*
X668557Y-56653D01*
X668448Y-56624D01*
X668339Y-56584D01*
X668288Y-56558D01*
X668237Y-56529D01*
X668233Y-56525D01*
X668226Y-56522D01*
X668212Y-56511D01*
X668197Y-56496D01*
X668175Y-56482D01*
X668150Y-56460D01*
X668120Y-56435D01*
X668091Y-56405D01*
X668062Y-56373D01*
X668029Y-56340D01*
X667964Y-56256D01*
X667902Y-56158D01*
X667847Y-56049D01*
Y-56045D01*
X667840Y-56034D01*
X667837Y-56016D01*
X667826Y-55994D01*
X667818Y-55965D01*
X667807Y-55929D01*
X667793Y-55888D01*
X667782Y-55845D01*
X667771Y-55797D01*
X667757Y-55743D01*
X667738Y-55630D01*
X667724Y-55503D01*
X667717Y-55372D01*
Y-55368D01*
Y-55353D01*
Y-55332D01*
X667720Y-55306D01*
Y-55270D01*
X667724Y-55233D01*
X667727Y-55186D01*
X667735Y-55139D01*
X667753Y-55033D01*
X667778Y-54917D01*
X667815Y-54800D01*
X667866Y-54687D01*
X667869Y-54684D01*
X667873Y-54673D01*
X667880Y-54658D01*
X667895Y-54640D01*
X667909Y-54615D01*
X667928Y-54585D01*
X667975Y-54520D01*
X668037Y-54447D01*
X668110Y-54374D01*
X668193Y-54302D01*
X668292Y-54240D01*
X668295Y-54236D01*
X668306Y-54232D01*
X668321Y-54225D01*
X668339Y-54214D01*
X668368Y-54203D01*
X668397Y-54192D01*
X668434Y-54178D01*
X668474Y-54163D01*
X668517Y-54149D01*
X668565Y-54134D01*
X668667Y-54112D01*
X668783Y-54094D01*
X668903Y-54087D01*
X668939D01*
X668965Y-54090D01*
D02*
G37*
G36*
X671779Y-54458D02*
X670770D01*
X670636Y-55139D01*
X670639Y-55135D01*
X670647Y-55131D01*
X670658Y-55124D01*
X670676Y-55113D01*
X670698Y-55102D01*
X670723Y-55088D01*
X670781Y-55059D01*
X670854Y-55029D01*
X670934Y-55004D01*
X671022Y-54986D01*
X671065Y-54979D01*
X671145D01*
X671167Y-54982D01*
X671196Y-54986D01*
X671229Y-54989D01*
X671266Y-54997D01*
X671306Y-55008D01*
X671393Y-55033D01*
X671440Y-55051D01*
X671488Y-55077D01*
X671535Y-55102D01*
X671582Y-55131D01*
X671626Y-55168D01*
X671669Y-55208D01*
X671673Y-55212D01*
X671680Y-55219D01*
X671691Y-55230D01*
X671706Y-55248D01*
X671724Y-55273D01*
X671742Y-55299D01*
X671764Y-55332D01*
X671786Y-55368D01*
X671804Y-55408D01*
X671826Y-55452D01*
X671844Y-55503D01*
X671862Y-55554D01*
X671877Y-55608D01*
X671888Y-55670D01*
X671895Y-55732D01*
X671899Y-55797D01*
Y-55801D01*
Y-55812D01*
Y-55830D01*
X671895Y-55856D01*
X671892Y-55885D01*
X671888Y-55918D01*
X671881Y-55958D01*
X671873Y-55998D01*
X671851Y-56092D01*
X671815Y-56191D01*
X671793Y-56242D01*
X671764Y-56289D01*
X671735Y-56340D01*
X671699Y-56387D01*
X671695Y-56391D01*
X671688Y-56402D01*
X671673Y-56416D01*
X671655Y-56435D01*
X671629Y-56456D01*
X671600Y-56485D01*
X671564Y-56511D01*
X671524Y-56540D01*
X671480Y-56569D01*
X671429Y-56595D01*
X671375Y-56620D01*
X671316Y-56646D01*
X671255Y-56664D01*
X671185Y-56678D01*
X671113Y-56689D01*
X671036Y-56693D01*
X671003D01*
X670978Y-56689D01*
X670949Y-56686D01*
X670916Y-56682D01*
X670876Y-56678D01*
X670836Y-56668D01*
X670745Y-56646D01*
X670654Y-56613D01*
X670607Y-56591D01*
X670559Y-56566D01*
X670516Y-56536D01*
X670472Y-56504D01*
X670468Y-56500D01*
X670461Y-56496D01*
X670454Y-56482D01*
X670439Y-56467D01*
X670421Y-56449D01*
X670403Y-56427D01*
X670381Y-56398D01*
X670363Y-56365D01*
X670341Y-56333D01*
X670319Y-56293D01*
X670279Y-56205D01*
X670246Y-56103D01*
X670235Y-56049D01*
X670228Y-55990D01*
X670552Y-55965D01*
Y-55969D01*
Y-55976D01*
X670556Y-55987D01*
X670559Y-56005D01*
X670570Y-56045D01*
X670585Y-56100D01*
X670607Y-56154D01*
X670636Y-56216D01*
X670672Y-56271D01*
X670716Y-56322D01*
X670723Y-56325D01*
X670738Y-56340D01*
X670767Y-56358D01*
X670807Y-56380D01*
X670851Y-56402D01*
X670905Y-56420D01*
X670967Y-56435D01*
X671036Y-56438D01*
X671058D01*
X671073Y-56435D01*
X671116Y-56431D01*
X671167Y-56416D01*
X671229Y-56398D01*
X671291Y-56369D01*
X671356Y-56325D01*
X671386Y-56300D01*
X671415Y-56271D01*
X671418Y-56267D01*
X671422Y-56263D01*
X671429Y-56252D01*
X671440Y-56242D01*
X671466Y-56202D01*
X671495Y-56151D01*
X671520Y-56089D01*
X671546Y-56012D01*
X671564Y-55921D01*
X671571Y-55874D01*
Y-55823D01*
Y-55819D01*
Y-55812D01*
Y-55797D01*
X671568Y-55779D01*
Y-55757D01*
X671564Y-55732D01*
X671553Y-55674D01*
X671535Y-55605D01*
X671509Y-55535D01*
X671473Y-55470D01*
X671422Y-55408D01*
Y-55404D01*
X671415Y-55401D01*
X671396Y-55383D01*
X671364Y-55357D01*
X671320Y-55328D01*
X671262Y-55303D01*
X671196Y-55277D01*
X671120Y-55259D01*
X671076Y-55251D01*
X671007D01*
X670978Y-55255D01*
X670941Y-55259D01*
X670898Y-55270D01*
X670854Y-55281D01*
X670807Y-55299D01*
X670759Y-55321D01*
X670756Y-55324D01*
X670741Y-55332D01*
X670719Y-55350D01*
X670690Y-55368D01*
X670661Y-55393D01*
X670632Y-55426D01*
X670599Y-55459D01*
X670574Y-55499D01*
X670283Y-55459D01*
X670527Y-54163D01*
X671779D01*
Y-54458D01*
D02*
G37*
G36*
X602250Y-53941D02*
X602280Y-53944D01*
X602312Y-53948D01*
X602352Y-53952D01*
X602392Y-53962D01*
X602483Y-53984D01*
X602574Y-54017D01*
X602622Y-54039D01*
X602669Y-54064D01*
X602713Y-54093D01*
X602756Y-54126D01*
X602760Y-54130D01*
X602767Y-54133D01*
X602775Y-54148D01*
X602789Y-54163D01*
X602807Y-54181D01*
X602825Y-54203D01*
X602847Y-54232D01*
X602866Y-54265D01*
X602887Y-54297D01*
X602909Y-54337D01*
X602949Y-54425D01*
X602982Y-54527D01*
X602993Y-54581D01*
X603000Y-54640D01*
X602676Y-54665D01*
Y-54661D01*
Y-54654D01*
X602673Y-54643D01*
X602669Y-54625D01*
X602658Y-54585D01*
X602643Y-54530D01*
X602622Y-54476D01*
X602593Y-54414D01*
X602556Y-54359D01*
X602513Y-54308D01*
X602505Y-54305D01*
X602491Y-54290D01*
X602461Y-54272D01*
X602422Y-54250D01*
X602378Y-54228D01*
X602323Y-54210D01*
X602261Y-54195D01*
X602192Y-54192D01*
X602170D01*
X602156Y-54195D01*
X602112Y-54199D01*
X602061Y-54214D01*
X601999Y-54232D01*
X601937Y-54261D01*
X601872Y-54305D01*
X601843Y-54330D01*
X601814Y-54359D01*
X601810Y-54363D01*
X601806Y-54366D01*
X601799Y-54377D01*
X601788Y-54388D01*
X601763Y-54428D01*
X601733Y-54479D01*
X601708Y-54541D01*
X601683Y-54618D01*
X601664Y-54709D01*
X601657Y-54756D01*
Y-54807D01*
Y-54811D01*
Y-54818D01*
Y-54832D01*
X601661Y-54851D01*
Y-54872D01*
X601664Y-54898D01*
X601675Y-54956D01*
X601693Y-55025D01*
X601719Y-55094D01*
X601755Y-55160D01*
X601806Y-55222D01*
Y-55225D01*
X601814Y-55229D01*
X601832Y-55247D01*
X601865Y-55273D01*
X601908Y-55302D01*
X601966Y-55327D01*
X602032Y-55353D01*
X602108Y-55371D01*
X602152Y-55378D01*
X602221D01*
X602250Y-55375D01*
X602287Y-55371D01*
X602330Y-55360D01*
X602374Y-55349D01*
X602422Y-55331D01*
X602469Y-55309D01*
X602472Y-55306D01*
X602487Y-55298D01*
X602509Y-55280D01*
X602538Y-55262D01*
X602567Y-55236D01*
X602596Y-55204D01*
X602629Y-55171D01*
X602654Y-55131D01*
X602946Y-55171D01*
X602702Y-56467D01*
X601450D01*
Y-56172D01*
X602458D01*
X602593Y-55491D01*
X602589Y-55495D01*
X602582Y-55498D01*
X602571Y-55506D01*
X602553Y-55517D01*
X602531Y-55528D01*
X602505Y-55542D01*
X602447Y-55571D01*
X602374Y-55600D01*
X602294Y-55626D01*
X602207Y-55644D01*
X602163Y-55651D01*
X602083D01*
X602061Y-55648D01*
X602032Y-55644D01*
X601999Y-55641D01*
X601963Y-55633D01*
X601923Y-55622D01*
X601835Y-55597D01*
X601788Y-55579D01*
X601741Y-55553D01*
X601693Y-55528D01*
X601646Y-55498D01*
X601603Y-55462D01*
X601559Y-55422D01*
X601555Y-55418D01*
X601548Y-55411D01*
X601537Y-55400D01*
X601522Y-55382D01*
X601504Y-55357D01*
X601486Y-55331D01*
X601464Y-55298D01*
X601442Y-55262D01*
X601424Y-55222D01*
X601402Y-55178D01*
X601384Y-55127D01*
X601366Y-55076D01*
X601351Y-55022D01*
X601340Y-54960D01*
X601333Y-54898D01*
X601330Y-54832D01*
Y-54829D01*
Y-54818D01*
Y-54800D01*
X601333Y-54774D01*
X601337Y-54745D01*
X601340Y-54712D01*
X601348Y-54672D01*
X601355Y-54632D01*
X601377Y-54538D01*
X601413Y-54439D01*
X601435Y-54388D01*
X601464Y-54341D01*
X601493Y-54290D01*
X601530Y-54243D01*
X601533Y-54239D01*
X601541Y-54228D01*
X601555Y-54214D01*
X601573Y-54195D01*
X601599Y-54174D01*
X601628Y-54144D01*
X601664Y-54119D01*
X601704Y-54090D01*
X601748Y-54061D01*
X601799Y-54035D01*
X601854Y-54010D01*
X601912Y-53984D01*
X601974Y-53966D01*
X602043Y-53952D01*
X602116Y-53941D01*
X602192Y-53937D01*
X602225D01*
X602250Y-53941D01*
D02*
G37*
G36*
X600292D02*
X600321Y-53944D01*
X600354Y-53948D01*
X600394Y-53952D01*
X600434Y-53962D01*
X600525Y-53984D01*
X600616Y-54017D01*
X600663Y-54039D01*
X600711Y-54064D01*
X600754Y-54093D01*
X600798Y-54126D01*
X600802Y-54130D01*
X600809Y-54133D01*
X600816Y-54148D01*
X600831Y-54163D01*
X600849Y-54181D01*
X600867Y-54203D01*
X600889Y-54232D01*
X600907Y-54265D01*
X600929Y-54297D01*
X600951Y-54337D01*
X600991Y-54425D01*
X601024Y-54527D01*
X601035Y-54581D01*
X601042Y-54640D01*
X600718Y-54665D01*
Y-54661D01*
Y-54654D01*
X600714Y-54643D01*
X600711Y-54625D01*
X600700Y-54585D01*
X600685Y-54530D01*
X600663Y-54476D01*
X600634Y-54414D01*
X600598Y-54359D01*
X600554Y-54308D01*
X600547Y-54305D01*
X600532Y-54290D01*
X600503Y-54272D01*
X600463Y-54250D01*
X600420Y-54228D01*
X600365Y-54210D01*
X600303Y-54195D01*
X600234Y-54192D01*
X600212D01*
X600197Y-54195D01*
X600154Y-54199D01*
X600103Y-54214D01*
X600041Y-54232D01*
X599979Y-54261D01*
X599914Y-54305D01*
X599884Y-54330D01*
X599855Y-54359D01*
X599852Y-54363D01*
X599848Y-54366D01*
X599841Y-54377D01*
X599830Y-54388D01*
X599804Y-54428D01*
X599775Y-54479D01*
X599750Y-54541D01*
X599724Y-54618D01*
X599706Y-54709D01*
X599699Y-54756D01*
Y-54807D01*
Y-54811D01*
Y-54818D01*
Y-54832D01*
X599702Y-54851D01*
Y-54872D01*
X599706Y-54898D01*
X599717Y-54956D01*
X599735Y-55025D01*
X599761Y-55094D01*
X599797Y-55160D01*
X599848Y-55222D01*
Y-55225D01*
X599855Y-55229D01*
X599873Y-55247D01*
X599906Y-55273D01*
X599950Y-55302D01*
X600008Y-55327D01*
X600074Y-55353D01*
X600150Y-55371D01*
X600194Y-55378D01*
X600263D01*
X600292Y-55375D01*
X600328Y-55371D01*
X600372Y-55360D01*
X600416Y-55349D01*
X600463Y-55331D01*
X600511Y-55309D01*
X600514Y-55306D01*
X600529Y-55298D01*
X600551Y-55280D01*
X600580Y-55262D01*
X600609Y-55236D01*
X600638Y-55204D01*
X600671Y-55171D01*
X600696Y-55131D01*
X600987Y-55171D01*
X600743Y-56467D01*
X599491D01*
Y-56172D01*
X600500D01*
X600634Y-55491D01*
X600631Y-55495D01*
X600623Y-55498D01*
X600612Y-55506D01*
X600594Y-55517D01*
X600572Y-55528D01*
X600547Y-55542D01*
X600489Y-55571D01*
X600416Y-55600D01*
X600336Y-55626D01*
X600248Y-55644D01*
X600205Y-55651D01*
X600125D01*
X600103Y-55648D01*
X600074Y-55644D01*
X600041Y-55641D01*
X600004Y-55633D01*
X599965Y-55622D01*
X599877Y-55597D01*
X599830Y-55579D01*
X599783Y-55553D01*
X599735Y-55528D01*
X599688Y-55498D01*
X599644Y-55462D01*
X599601Y-55422D01*
X599597Y-55418D01*
X599590Y-55411D01*
X599579Y-55400D01*
X599564Y-55382D01*
X599546Y-55357D01*
X599528Y-55331D01*
X599506Y-55298D01*
X599484Y-55262D01*
X599466Y-55222D01*
X599444Y-55178D01*
X599426Y-55127D01*
X599408Y-55076D01*
X599393Y-55022D01*
X599382Y-54960D01*
X599375Y-54898D01*
X599371Y-54832D01*
Y-54829D01*
Y-54818D01*
Y-54800D01*
X599375Y-54774D01*
X599378Y-54745D01*
X599382Y-54712D01*
X599389Y-54672D01*
X599397Y-54632D01*
X599418Y-54538D01*
X599455Y-54439D01*
X599477Y-54388D01*
X599506Y-54341D01*
X599535Y-54290D01*
X599571Y-54243D01*
X599575Y-54239D01*
X599582Y-54228D01*
X599597Y-54214D01*
X599615Y-54195D01*
X599641Y-54174D01*
X599670Y-54144D01*
X599706Y-54119D01*
X599746Y-54090D01*
X599790Y-54061D01*
X599841Y-54035D01*
X599895Y-54010D01*
X599954Y-53984D01*
X600015Y-53966D01*
X600085Y-53952D01*
X600157Y-53941D01*
X600234Y-53937D01*
X600267D01*
X600292Y-53941D01*
D02*
G37*
G36*
X604398D02*
X604431D01*
X604471Y-53944D01*
X604515Y-53952D01*
X604565Y-53959D01*
X604671Y-53977D01*
X604780Y-54006D01*
X604889Y-54046D01*
X604940Y-54072D01*
X604991Y-54101D01*
X604995Y-54104D01*
X605002Y-54108D01*
X605017Y-54119D01*
X605031Y-54133D01*
X605053Y-54148D01*
X605079Y-54170D01*
X605108Y-54195D01*
X605137Y-54224D01*
X605166Y-54257D01*
X605199Y-54290D01*
X605264Y-54374D01*
X605326Y-54472D01*
X605381Y-54581D01*
Y-54585D01*
X605388Y-54596D01*
X605392Y-54614D01*
X605403Y-54636D01*
X605410Y-54665D01*
X605421Y-54701D01*
X605435Y-54741D01*
X605446Y-54785D01*
X605457Y-54832D01*
X605472Y-54887D01*
X605490Y-55000D01*
X605505Y-55127D01*
X605512Y-55258D01*
Y-55262D01*
Y-55277D01*
Y-55298D01*
X605508Y-55324D01*
Y-55360D01*
X605505Y-55397D01*
X605501Y-55444D01*
X605494Y-55491D01*
X605475Y-55597D01*
X605450Y-55713D01*
X605414Y-55830D01*
X605363Y-55943D01*
X605359Y-55946D01*
X605355Y-55957D01*
X605348Y-55972D01*
X605334Y-55990D01*
X605319Y-56015D01*
X605301Y-56045D01*
X605253Y-56110D01*
X605192Y-56183D01*
X605119Y-56256D01*
X605035Y-56328D01*
X604937Y-56390D01*
X604933Y-56394D01*
X604922Y-56398D01*
X604908Y-56405D01*
X604889Y-56416D01*
X604860Y-56427D01*
X604831Y-56438D01*
X604795Y-56452D01*
X604755Y-56467D01*
X604711Y-56481D01*
X604664Y-56496D01*
X604562Y-56518D01*
X604445Y-56536D01*
X604325Y-56543D01*
X604289D01*
X604263Y-56540D01*
X604231Y-56536D01*
X604190Y-56532D01*
X604150Y-56529D01*
X604103Y-56518D01*
X604005Y-56496D01*
X603896Y-56463D01*
X603841Y-56441D01*
X603790Y-56416D01*
X603739Y-56383D01*
X603688Y-56350D01*
X603685Y-56347D01*
X603677Y-56343D01*
X603663Y-56332D01*
X603645Y-56314D01*
X603626Y-56296D01*
X603601Y-56270D01*
X603575Y-56241D01*
X603546Y-56212D01*
X603517Y-56176D01*
X603488Y-56132D01*
X603455Y-56088D01*
X603426Y-56041D01*
X603401Y-55986D01*
X603371Y-55932D01*
X603350Y-55873D01*
X603328Y-55808D01*
X603655Y-55731D01*
Y-55735D01*
X603659Y-55742D01*
X603666Y-55757D01*
X603674Y-55775D01*
X603681Y-55797D01*
X603692Y-55826D01*
X603721Y-55884D01*
X603757Y-55950D01*
X603801Y-56015D01*
X603856Y-56077D01*
X603914Y-56132D01*
X603921Y-56139D01*
X603943Y-56154D01*
X603979Y-56172D01*
X604027Y-56197D01*
X604089Y-56219D01*
X604158Y-56241D01*
X604242Y-56256D01*
X604332Y-56259D01*
X604362D01*
X604380Y-56256D01*
X604405D01*
X604434Y-56252D01*
X604504Y-56241D01*
X604580Y-56226D01*
X604660Y-56201D01*
X604744Y-56165D01*
X604820Y-56117D01*
X604824D01*
X604827Y-56110D01*
X604853Y-56092D01*
X604886Y-56063D01*
X604926Y-56019D01*
X604973Y-55964D01*
X605017Y-55903D01*
X605057Y-55826D01*
X605093Y-55742D01*
Y-55739D01*
X605097Y-55731D01*
X605100Y-55721D01*
X605104Y-55702D01*
X605111Y-55681D01*
X605119Y-55655D01*
X605130Y-55593D01*
X605144Y-55520D01*
X605159Y-55440D01*
X605166Y-55353D01*
X605170Y-55258D01*
Y-55255D01*
Y-55244D01*
Y-55225D01*
Y-55204D01*
X605166Y-55178D01*
Y-55145D01*
X605162Y-55109D01*
X605159Y-55069D01*
X605148Y-54982D01*
X605130Y-54887D01*
X605108Y-54792D01*
X605079Y-54698D01*
Y-54694D01*
X605075Y-54687D01*
X605068Y-54676D01*
X605060Y-54658D01*
X605039Y-54614D01*
X605006Y-54563D01*
X604966Y-54505D01*
X604915Y-54443D01*
X604857Y-54388D01*
X604787Y-54337D01*
X604784D01*
X604777Y-54334D01*
X604766Y-54326D01*
X604751Y-54319D01*
X604733Y-54312D01*
X604711Y-54301D01*
X604660Y-54279D01*
X604595Y-54257D01*
X604522Y-54239D01*
X604442Y-54224D01*
X604358Y-54221D01*
X604332D01*
X604311Y-54224D01*
X604285D01*
X604260Y-54228D01*
X604194Y-54243D01*
X604118Y-54261D01*
X604041Y-54290D01*
X603961Y-54330D01*
X603921Y-54352D01*
X603885Y-54381D01*
X603881Y-54385D01*
X603877Y-54388D01*
X603867Y-54399D01*
X603852Y-54410D01*
X603837Y-54428D01*
X603819Y-54450D01*
X603797Y-54472D01*
X603779Y-54501D01*
X603757Y-54534D01*
X603732Y-54570D01*
X603710Y-54607D01*
X603688Y-54650D01*
X603670Y-54698D01*
X603652Y-54749D01*
X603634Y-54803D01*
X603619Y-54861D01*
X603284Y-54778D01*
Y-54774D01*
X603288Y-54760D01*
X603295Y-54738D01*
X603306Y-54709D01*
X603317Y-54676D01*
X603332Y-54636D01*
X603350Y-54592D01*
X603371Y-54545D01*
X603422Y-54443D01*
X603488Y-54341D01*
X603528Y-54290D01*
X603568Y-54239D01*
X603612Y-54195D01*
X603663Y-54152D01*
X603666Y-54148D01*
X603674Y-54141D01*
X603692Y-54133D01*
X603710Y-54119D01*
X603739Y-54101D01*
X603768Y-54083D01*
X603808Y-54064D01*
X603848Y-54046D01*
X603896Y-54024D01*
X603947Y-54006D01*
X604001Y-53988D01*
X604060Y-53970D01*
X604121Y-53955D01*
X604187Y-53948D01*
X604256Y-53941D01*
X604329Y-53937D01*
X604369D01*
X604398Y-53941D01*
D02*
G37*
G36*
X630402Y-165934D02*
X630420D01*
X630446Y-165938D01*
X630508Y-165949D01*
X630577Y-165963D01*
X630653Y-165989D01*
X630730Y-166022D01*
X630806Y-166065D01*
X630810D01*
X630813Y-166072D01*
X630824Y-166080D01*
X630839Y-166091D01*
X630875Y-166120D01*
X630923Y-166160D01*
X630970Y-166214D01*
X631024Y-166280D01*
X631072Y-166356D01*
X631115Y-166444D01*
Y-166447D01*
X631119Y-166455D01*
X631126Y-166469D01*
X631134Y-166487D01*
X631141Y-166513D01*
X631152Y-166546D01*
X631159Y-166582D01*
X631170Y-166622D01*
X631181Y-166669D01*
X631192Y-166724D01*
X631199Y-166782D01*
X631206Y-166844D01*
X631214Y-166913D01*
X631221Y-166986D01*
X631225Y-167066D01*
Y-167150D01*
Y-167154D01*
Y-167172D01*
Y-167197D01*
Y-167230D01*
X631221Y-167270D01*
Y-167317D01*
X631217Y-167372D01*
X631210Y-167427D01*
X631199Y-167550D01*
X631181Y-167681D01*
X631155Y-167805D01*
X631137Y-167867D01*
X631119Y-167922D01*
Y-167925D01*
X631115Y-167932D01*
X631108Y-167947D01*
X631101Y-167969D01*
X631090Y-167991D01*
X631075Y-168020D01*
X631039Y-168082D01*
X630995Y-168151D01*
X630944Y-168224D01*
X630879Y-168293D01*
X630806Y-168355D01*
X630802D01*
X630795Y-168362D01*
X630784Y-168369D01*
X630770Y-168377D01*
X630748Y-168387D01*
X630726Y-168402D01*
X630697Y-168417D01*
X630668Y-168428D01*
X630599Y-168457D01*
X630515Y-168482D01*
X630424Y-168497D01*
X630322Y-168504D01*
X630293D01*
X630275Y-168500D01*
X630249D01*
X630220Y-168497D01*
X630151Y-168482D01*
X630074Y-168464D01*
X629994Y-168435D01*
X629914Y-168395D01*
X629874Y-168369D01*
X629838Y-168340D01*
X629834Y-168337D01*
X629831Y-168333D01*
X629820Y-168322D01*
X629809Y-168311D01*
X629794Y-168293D01*
X629776Y-168271D01*
X629740Y-168220D01*
X629703Y-168155D01*
X629667Y-168075D01*
X629638Y-167983D01*
X629616Y-167878D01*
X629914Y-167852D01*
Y-167856D01*
X629918Y-167863D01*
Y-167871D01*
X629921Y-167885D01*
X629932Y-167925D01*
X629947Y-167969D01*
X629965Y-168020D01*
X629991Y-168071D01*
X630020Y-168118D01*
X630056Y-168158D01*
X630060Y-168162D01*
X630074Y-168173D01*
X630100Y-168187D01*
X630129Y-168202D01*
X630169Y-168220D01*
X630216Y-168235D01*
X630271Y-168246D01*
X630329Y-168249D01*
X630355D01*
X630380Y-168246D01*
X630413Y-168242D01*
X630453Y-168235D01*
X630493Y-168224D01*
X630537Y-168209D01*
X630577Y-168187D01*
X630580Y-168184D01*
X630595Y-168176D01*
X630617Y-168162D01*
X630639Y-168140D01*
X630668Y-168114D01*
X630697Y-168085D01*
X630726Y-168053D01*
X630755Y-168013D01*
X630759Y-168009D01*
X630766Y-167991D01*
X630781Y-167965D01*
X630795Y-167932D01*
X630813Y-167889D01*
X630831Y-167838D01*
X630850Y-167780D01*
X630868Y-167714D01*
Y-167710D01*
X630872Y-167707D01*
Y-167696D01*
X630875Y-167681D01*
X630883Y-167645D01*
X630893Y-167598D01*
X630901Y-167539D01*
X630908Y-167478D01*
X630912Y-167408D01*
X630915Y-167335D01*
Y-167332D01*
Y-167321D01*
Y-167303D01*
Y-167274D01*
X630912Y-167281D01*
X630897Y-167299D01*
X630875Y-167325D01*
X630850Y-167361D01*
X630813Y-167397D01*
X630770Y-167438D01*
X630719Y-167478D01*
X630660Y-167514D01*
X630653Y-167518D01*
X630631Y-167528D01*
X630599Y-167543D01*
X630558Y-167558D01*
X630504Y-167576D01*
X630446Y-167590D01*
X630380Y-167601D01*
X630311Y-167605D01*
X630282D01*
X630260Y-167601D01*
X630231Y-167598D01*
X630202Y-167594D01*
X630165Y-167587D01*
X630129Y-167576D01*
X630045Y-167550D01*
X630002Y-167532D01*
X629958Y-167510D01*
X629911Y-167485D01*
X629867Y-167452D01*
X629823Y-167419D01*
X629783Y-167379D01*
X629780Y-167376D01*
X629772Y-167368D01*
X629765Y-167357D01*
X629750Y-167339D01*
X629732Y-167314D01*
X629714Y-167288D01*
X629696Y-167255D01*
X629678Y-167219D01*
X629656Y-167179D01*
X629638Y-167135D01*
X629619Y-167084D01*
X629601Y-167033D01*
X629587Y-166975D01*
X629579Y-166913D01*
X629572Y-166851D01*
X629568Y-166782D01*
Y-166779D01*
Y-166764D01*
Y-166746D01*
X629572Y-166720D01*
X629576Y-166688D01*
X629579Y-166648D01*
X629587Y-166607D01*
X629598Y-166560D01*
X629623Y-166466D01*
X629641Y-166415D01*
X629663Y-166360D01*
X629689Y-166309D01*
X629721Y-166262D01*
X629754Y-166211D01*
X629794Y-166167D01*
X629798Y-166164D01*
X629805Y-166156D01*
X629816Y-166145D01*
X629834Y-166131D01*
X629856Y-166112D01*
X629885Y-166091D01*
X629914Y-166072D01*
X629951Y-166047D01*
X629987Y-166025D01*
X630031Y-166007D01*
X630129Y-165967D01*
X630180Y-165952D01*
X630238Y-165941D01*
X630296Y-165934D01*
X630358Y-165930D01*
X630384D01*
X630402Y-165934D01*
D02*
G37*
G36*
X628775Y-168460D02*
X628466D01*
Y-166491D01*
X628462Y-166495D01*
X628444Y-166509D01*
X628422Y-166531D01*
X628385Y-166557D01*
X628345Y-166589D01*
X628294Y-166626D01*
X628236Y-166666D01*
X628171Y-166706D01*
X628167D01*
X628163Y-166709D01*
X628142Y-166724D01*
X628105Y-166742D01*
X628061Y-166764D01*
X628011Y-166790D01*
X627956Y-166815D01*
X627901Y-166841D01*
X627847Y-166862D01*
Y-166564D01*
X627850D01*
X627858Y-166557D01*
X627872Y-166553D01*
X627890Y-166542D01*
X627912Y-166531D01*
X627938Y-166517D01*
X628000Y-166480D01*
X628072Y-166440D01*
X628145Y-166389D01*
X628222Y-166331D01*
X628298Y-166269D01*
X628302Y-166265D01*
X628305Y-166262D01*
X628316Y-166251D01*
X628331Y-166240D01*
X628364Y-166203D01*
X628407Y-166160D01*
X628451Y-166109D01*
X628498Y-166051D01*
X628538Y-165992D01*
X628575Y-165930D01*
X628775D01*
Y-168460D01*
D02*
G37*
G36*
X626231Y-165945D02*
X626303Y-165949D01*
X626376Y-165956D01*
X626449Y-165967D01*
X626511Y-165978D01*
X626514D01*
X626522Y-165981D01*
X626533D01*
X626547Y-165989D01*
X626587Y-166000D01*
X626638Y-166018D01*
X626696Y-166043D01*
X626758Y-166076D01*
X626820Y-166112D01*
X626878Y-166160D01*
X626882Y-166164D01*
X626886Y-166167D01*
X626897Y-166178D01*
X626911Y-166189D01*
X626948Y-166225D01*
X626991Y-166276D01*
X627039Y-166338D01*
X627090Y-166411D01*
X627137Y-166495D01*
X627177Y-166589D01*
Y-166593D01*
X627181Y-166600D01*
X627188Y-166615D01*
X627191Y-166637D01*
X627202Y-166662D01*
X627210Y-166691D01*
X627217Y-166724D01*
X627228Y-166764D01*
X627239Y-166804D01*
X627246Y-166851D01*
X627264Y-166953D01*
X627275Y-167066D01*
X627279Y-167190D01*
Y-167194D01*
Y-167201D01*
Y-167219D01*
Y-167237D01*
X627275Y-167263D01*
Y-167292D01*
X627272Y-167361D01*
X627261Y-167441D01*
X627250Y-167525D01*
X627232Y-167612D01*
X627210Y-167700D01*
Y-167703D01*
X627206Y-167710D01*
X627202Y-167721D01*
X627199Y-167736D01*
X627184Y-167776D01*
X627162Y-167827D01*
X627141Y-167885D01*
X627111Y-167943D01*
X627075Y-168005D01*
X627039Y-168064D01*
X627035Y-168071D01*
X627020Y-168089D01*
X626999Y-168114D01*
X626969Y-168147D01*
X626937Y-168184D01*
X626897Y-168220D01*
X626857Y-168260D01*
X626809Y-168293D01*
X626802Y-168297D01*
X626788Y-168307D01*
X626762Y-168322D01*
X626726Y-168340D01*
X626682Y-168362D01*
X626631Y-168380D01*
X626573Y-168402D01*
X626507Y-168420D01*
X626500D01*
X626489Y-168424D01*
X626478Y-168428D01*
X626442Y-168431D01*
X626391Y-168438D01*
X626333Y-168446D01*
X626263Y-168453D01*
X626187Y-168457D01*
X626103Y-168460D01*
X625197D01*
Y-165941D01*
X626165D01*
X626231Y-165945D01*
D02*
G37*
G36*
X32972Y15877D02*
X33019D01*
X33074Y15873D01*
X33128Y15866D01*
X33252Y15855D01*
X33383Y15837D01*
X33507Y15811D01*
X33569Y15793D01*
X33623Y15775D01*
X33627D01*
X33634Y15771D01*
X33649Y15764D01*
X33671Y15757D01*
X33692Y15746D01*
X33722Y15731D01*
X33783Y15695D01*
X33853Y15651D01*
X33925Y15600D01*
X33995Y15535D01*
X34056Y15462D01*
Y15458D01*
X34064Y15451D01*
X34071Y15440D01*
X34078Y15426D01*
X34089Y15404D01*
X34104Y15382D01*
X34118Y15353D01*
X34129Y15324D01*
X34158Y15255D01*
X34184Y15171D01*
X34198Y15080D01*
X34206Y14978D01*
Y14949D01*
X34202Y14931D01*
Y14905D01*
X34198Y14876D01*
X34184Y14807D01*
X34166Y14730D01*
X34137Y14650D01*
X34097Y14570D01*
X34071Y14530D01*
X34042Y14494D01*
X34038Y14490D01*
X34035Y14486D01*
X34024Y14476D01*
X34013Y14465D01*
X33995Y14450D01*
X33973Y14432D01*
X33922Y14395D01*
X33856Y14359D01*
X33776Y14323D01*
X33685Y14293D01*
X33580Y14272D01*
X33554Y14570D01*
X33558D01*
X33565Y14574D01*
X33572D01*
X33587Y14577D01*
X33627Y14588D01*
X33671Y14603D01*
X33722Y14621D01*
X33773Y14647D01*
X33820Y14676D01*
X33860Y14712D01*
X33863Y14716D01*
X33874Y14730D01*
X33889Y14756D01*
X33904Y14785D01*
X33922Y14825D01*
X33936Y14872D01*
X33947Y14927D01*
X33951Y14985D01*
Y15011D01*
X33947Y15036D01*
X33944Y15069D01*
X33936Y15109D01*
X33925Y15149D01*
X33911Y15193D01*
X33889Y15233D01*
X33885Y15236D01*
X33878Y15251D01*
X33863Y15273D01*
X33842Y15294D01*
X33816Y15324D01*
X33787Y15353D01*
X33754Y15382D01*
X33714Y15411D01*
X33711Y15415D01*
X33692Y15422D01*
X33667Y15437D01*
X33634Y15451D01*
X33590Y15469D01*
X33540Y15487D01*
X33481Y15506D01*
X33416Y15524D01*
X33412D01*
X33408Y15528D01*
X33398D01*
X33383Y15531D01*
X33347Y15538D01*
X33299Y15549D01*
X33241Y15557D01*
X33179Y15564D01*
X33110Y15567D01*
X33037Y15571D01*
X33034D01*
X33023D01*
X33005D01*
X32975D01*
X32983Y15567D01*
X33001Y15553D01*
X33026Y15531D01*
X33063Y15506D01*
X33099Y15469D01*
X33139Y15426D01*
X33179Y15375D01*
X33216Y15316D01*
X33219Y15309D01*
X33230Y15287D01*
X33245Y15255D01*
X33259Y15214D01*
X33277Y15160D01*
X33292Y15102D01*
X33303Y15036D01*
X33307Y14967D01*
Y14938D01*
X33303Y14916D01*
X33299Y14887D01*
X33296Y14858D01*
X33288Y14821D01*
X33277Y14785D01*
X33252Y14701D01*
X33234Y14658D01*
X33212Y14614D01*
X33187Y14567D01*
X33154Y14523D01*
X33121Y14479D01*
X33081Y14439D01*
X33077Y14435D01*
X33070Y14428D01*
X33059Y14421D01*
X33041Y14406D01*
X33015Y14388D01*
X32990Y14370D01*
X32957Y14352D01*
X32921Y14334D01*
X32881Y14312D01*
X32837Y14293D01*
X32786Y14275D01*
X32735Y14257D01*
X32677Y14243D01*
X32615Y14235D01*
X32553Y14228D01*
X32484Y14224D01*
X32480D01*
X32466D01*
X32448D01*
X32422Y14228D01*
X32389Y14232D01*
X32349Y14235D01*
X32309Y14243D01*
X32262Y14254D01*
X32167Y14279D01*
X32116Y14297D01*
X32062Y14319D01*
X32011Y14345D01*
X31963Y14377D01*
X31912Y14410D01*
X31869Y14450D01*
X31865Y14454D01*
X31858Y14461D01*
X31847Y14472D01*
X31832Y14490D01*
X31814Y14512D01*
X31792Y14541D01*
X31774Y14570D01*
X31749Y14607D01*
X31727Y14643D01*
X31709Y14687D01*
X31669Y14785D01*
X31654Y14836D01*
X31643Y14894D01*
X31636Y14952D01*
X31632Y15014D01*
Y15040D01*
X31636Y15058D01*
Y15076D01*
X31640Y15102D01*
X31650Y15164D01*
X31665Y15233D01*
X31690Y15309D01*
X31723Y15385D01*
X31767Y15462D01*
Y15466D01*
X31774Y15469D01*
X31781Y15480D01*
X31792Y15495D01*
X31822Y15531D01*
X31861Y15578D01*
X31916Y15626D01*
X31982Y15680D01*
X32058Y15728D01*
X32145Y15771D01*
X32149D01*
X32156Y15775D01*
X32171Y15782D01*
X32189Y15790D01*
X32215Y15797D01*
X32247Y15808D01*
X32284Y15815D01*
X32324Y15826D01*
X32371Y15837D01*
X32426Y15848D01*
X32484Y15855D01*
X32546Y15862D01*
X32615Y15870D01*
X32688Y15877D01*
X32768Y15881D01*
X32852D01*
X32855D01*
X32873D01*
X32899D01*
X32932D01*
X32972Y15877D01*
D02*
G37*
G36*
X32964Y13890D02*
X32994D01*
X33063Y13886D01*
X33143Y13875D01*
X33226Y13864D01*
X33314Y13846D01*
X33401Y13824D01*
X33405D01*
X33412Y13820D01*
X33423Y13817D01*
X33438Y13813D01*
X33478Y13799D01*
X33529Y13777D01*
X33587Y13755D01*
X33645Y13726D01*
X33707Y13689D01*
X33765Y13653D01*
X33773Y13649D01*
X33791Y13635D01*
X33816Y13613D01*
X33849Y13584D01*
X33885Y13551D01*
X33922Y13511D01*
X33962Y13471D01*
X33995Y13424D01*
X33998Y13416D01*
X34009Y13402D01*
X34024Y13376D01*
X34042Y13340D01*
X34064Y13296D01*
X34082Y13245D01*
X34104Y13187D01*
X34122Y13121D01*
Y13114D01*
X34126Y13103D01*
X34129Y13092D01*
X34133Y13056D01*
X34140Y13005D01*
X34147Y12947D01*
X34155Y12878D01*
X34158Y12801D01*
X34162Y12717D01*
Y11811D01*
X31643D01*
Y12779D01*
X31647Y12845D01*
X31650Y12918D01*
X31658Y12990D01*
X31669Y13063D01*
X31679Y13125D01*
Y13129D01*
X31683Y13136D01*
Y13147D01*
X31690Y13161D01*
X31701Y13202D01*
X31720Y13252D01*
X31745Y13311D01*
X31778Y13373D01*
X31814Y13434D01*
X31861Y13493D01*
X31865Y13496D01*
X31869Y13500D01*
X31880Y13511D01*
X31891Y13525D01*
X31927Y13562D01*
X31978Y13606D01*
X32040Y13653D01*
X32113Y13704D01*
X32196Y13751D01*
X32291Y13791D01*
X32295D01*
X32302Y13795D01*
X32316Y13802D01*
X32338Y13806D01*
X32364Y13817D01*
X32393Y13824D01*
X32426Y13831D01*
X32466Y13842D01*
X32506Y13853D01*
X32553Y13860D01*
X32655Y13879D01*
X32768Y13890D01*
X32892Y13893D01*
X32895D01*
X32903D01*
X32921D01*
X32939D01*
X32964Y13890D01*
D02*
G37*
G36*
X26584Y15873D02*
X26613Y15870D01*
X26646Y15862D01*
X26682Y15855D01*
X26723Y15848D01*
X26810Y15819D01*
X26857Y15797D01*
X26901Y15775D01*
X26948Y15746D01*
X26996Y15713D01*
X27043Y15677D01*
X27087Y15633D01*
X27090Y15629D01*
X27097Y15622D01*
X27108Y15608D01*
X27123Y15589D01*
X27141Y15567D01*
X27159Y15538D01*
X27181Y15506D01*
X27199Y15466D01*
X27221Y15426D01*
X27243Y15378D01*
X27261Y15331D01*
X27279Y15276D01*
X27294Y15218D01*
X27305Y15156D01*
X27312Y15094D01*
X27316Y15025D01*
Y14992D01*
X27312Y14971D01*
X27309Y14941D01*
X27305Y14909D01*
X27298Y14872D01*
X27290Y14832D01*
X27269Y14745D01*
X27232Y14654D01*
X27210Y14606D01*
X27185Y14563D01*
X27152Y14519D01*
X27119Y14476D01*
X27116Y14472D01*
X27108Y14465D01*
X27097Y14454D01*
X27083Y14443D01*
X27065Y14424D01*
X27039Y14406D01*
X27014Y14385D01*
X26981Y14363D01*
X26945Y14341D01*
X26908Y14319D01*
X26821Y14279D01*
X26719Y14246D01*
X26664Y14235D01*
X26606Y14228D01*
X26566Y14537D01*
X26570D01*
X26577Y14541D01*
X26592Y14545D01*
X26610Y14548D01*
X26632Y14552D01*
X26657Y14559D01*
X26712Y14577D01*
X26777Y14603D01*
X26839Y14636D01*
X26897Y14672D01*
X26948Y14716D01*
X26952Y14723D01*
X26967Y14738D01*
X26985Y14767D01*
X27003Y14803D01*
X27025Y14847D01*
X27043Y14901D01*
X27057Y14963D01*
X27061Y15029D01*
Y15051D01*
X27057Y15065D01*
X27054Y15105D01*
X27043Y15156D01*
X27025Y15214D01*
X26999Y15276D01*
X26963Y15338D01*
X26912Y15396D01*
X26905Y15404D01*
X26883Y15422D01*
X26850Y15444D01*
X26806Y15473D01*
X26752Y15502D01*
X26690Y15524D01*
X26617Y15542D01*
X26537Y15549D01*
X26533D01*
X26526D01*
X26515D01*
X26500Y15546D01*
X26460Y15542D01*
X26413Y15531D01*
X26355Y15517D01*
X26297Y15491D01*
X26239Y15455D01*
X26184Y15407D01*
X26177Y15400D01*
X26162Y15382D01*
X26140Y15353D01*
X26115Y15313D01*
X26089Y15262D01*
X26067Y15200D01*
X26053Y15131D01*
X26046Y15054D01*
Y15021D01*
X26049Y14996D01*
X26053Y14963D01*
X26060Y14927D01*
X26067Y14883D01*
X26078Y14836D01*
X25805Y14872D01*
Y14890D01*
X25809Y14905D01*
Y14952D01*
X25802Y14992D01*
X25794Y15040D01*
X25784Y15094D01*
X25765Y15156D01*
X25740Y15214D01*
X25707Y15276D01*
Y15280D01*
X25703Y15284D01*
X25689Y15302D01*
X25663Y15327D01*
X25631Y15356D01*
X25583Y15385D01*
X25529Y15411D01*
X25467Y15429D01*
X25430Y15437D01*
X25390D01*
X25387D01*
X25383D01*
X25361D01*
X25332Y15429D01*
X25292Y15422D01*
X25248Y15407D01*
X25201Y15389D01*
X25154Y15360D01*
X25110Y15320D01*
X25106Y15316D01*
X25092Y15298D01*
X25074Y15273D01*
X25052Y15240D01*
X25034Y15196D01*
X25015Y15145D01*
X25001Y15087D01*
X24997Y15021D01*
Y14992D01*
X25005Y14960D01*
X25012Y14916D01*
X25026Y14869D01*
X25045Y14821D01*
X25074Y14770D01*
X25110Y14723D01*
X25114Y14719D01*
X25132Y14705D01*
X25157Y14683D01*
X25194Y14658D01*
X25241Y14632D01*
X25299Y14606D01*
X25368Y14585D01*
X25449Y14570D01*
X25394Y14261D01*
X25390D01*
X25379Y14264D01*
X25365Y14268D01*
X25343Y14272D01*
X25317Y14279D01*
X25288Y14290D01*
X25219Y14312D01*
X25139Y14348D01*
X25059Y14392D01*
X24983Y14446D01*
X24914Y14515D01*
X24910Y14519D01*
X24906Y14526D01*
X24899Y14537D01*
X24888Y14552D01*
X24873Y14570D01*
X24859Y14596D01*
X24844Y14621D01*
X24826Y14654D01*
X24797Y14727D01*
X24768Y14810D01*
X24750Y14909D01*
X24742Y14960D01*
Y15051D01*
X24746Y15091D01*
X24753Y15138D01*
X24764Y15196D01*
X24782Y15262D01*
X24804Y15327D01*
X24833Y15393D01*
Y15396D01*
X24837Y15400D01*
X24848Y15422D01*
X24870Y15455D01*
X24895Y15491D01*
X24932Y15535D01*
X24972Y15578D01*
X25019Y15622D01*
X25074Y15658D01*
X25081Y15662D01*
X25099Y15673D01*
X25132Y15688D01*
X25172Y15706D01*
X25219Y15724D01*
X25274Y15739D01*
X25336Y15750D01*
X25398Y15753D01*
X25405D01*
X25427D01*
X25456Y15750D01*
X25496Y15742D01*
X25543Y15731D01*
X25594Y15713D01*
X25645Y15691D01*
X25696Y15662D01*
X25703Y15658D01*
X25718Y15648D01*
X25743Y15626D01*
X25773Y15597D01*
X25805Y15560D01*
X25842Y15517D01*
X25875Y15466D01*
X25907Y15404D01*
Y15407D01*
X25911Y15415D01*
X25914Y15426D01*
X25918Y15440D01*
X25933Y15480D01*
X25954Y15531D01*
X25984Y15589D01*
X26020Y15648D01*
X26067Y15702D01*
X26122Y15753D01*
X26129Y15757D01*
X26151Y15771D01*
X26188Y15793D01*
X26235Y15815D01*
X26293Y15837D01*
X26362Y15859D01*
X26442Y15873D01*
X26530Y15877D01*
X26533D01*
X26544D01*
X26562D01*
X26584Y15873D01*
D02*
G37*
G36*
X26075Y13890D02*
X26104D01*
X26173Y13886D01*
X26253Y13875D01*
X26337Y13864D01*
X26424Y13846D01*
X26511Y13824D01*
X26515D01*
X26522Y13820D01*
X26533Y13817D01*
X26548Y13813D01*
X26588Y13799D01*
X26639Y13777D01*
X26697Y13755D01*
X26755Y13726D01*
X26817Y13689D01*
X26875Y13653D01*
X26883Y13649D01*
X26901Y13635D01*
X26926Y13613D01*
X26959Y13584D01*
X26996Y13551D01*
X27032Y13511D01*
X27072Y13471D01*
X27105Y13424D01*
X27108Y13416D01*
X27119Y13402D01*
X27134Y13376D01*
X27152Y13340D01*
X27174Y13296D01*
X27192Y13245D01*
X27214Y13187D01*
X27232Y13121D01*
Y13114D01*
X27236Y13103D01*
X27240Y13092D01*
X27243Y13056D01*
X27250Y13005D01*
X27258Y12947D01*
X27265Y12878D01*
X27269Y12801D01*
X27272Y12717D01*
Y11811D01*
X24753D01*
Y12779D01*
X24757Y12845D01*
X24761Y12918D01*
X24768Y12990D01*
X24779Y13063D01*
X24790Y13125D01*
Y13129D01*
X24793Y13136D01*
Y13147D01*
X24801Y13161D01*
X24812Y13202D01*
X24830Y13252D01*
X24855Y13311D01*
X24888Y13373D01*
X24924Y13434D01*
X24972Y13493D01*
X24975Y13496D01*
X24979Y13500D01*
X24990Y13511D01*
X25001Y13525D01*
X25037Y13562D01*
X25088Y13605D01*
X25150Y13653D01*
X25223Y13704D01*
X25307Y13751D01*
X25401Y13791D01*
X25405D01*
X25412Y13795D01*
X25427Y13802D01*
X25449Y13806D01*
X25474Y13817D01*
X25503Y13824D01*
X25536Y13831D01*
X25576Y13842D01*
X25616Y13853D01*
X25663Y13860D01*
X25765Y13879D01*
X25878Y13890D01*
X26002Y13893D01*
X26006D01*
X26013D01*
X26031D01*
X26049D01*
X26075Y13890D01*
D02*
G37*
G36*
X670933Y-21020D02*
X670966Y-21023D01*
X671006Y-21027D01*
X671046Y-21030D01*
X671094Y-21041D01*
X671192Y-21063D01*
X671301Y-21096D01*
X671356Y-21118D01*
X671407Y-21143D01*
X671458Y-21176D01*
X671509Y-21209D01*
X671512Y-21212D01*
X671520Y-21216D01*
X671534Y-21227D01*
X671552Y-21245D01*
X671570Y-21263D01*
X671596Y-21289D01*
X671622Y-21318D01*
X671651Y-21347D01*
X671680Y-21384D01*
X671709Y-21427D01*
X671742Y-21471D01*
X671771Y-21518D01*
X671796Y-21573D01*
X671825Y-21627D01*
X671847Y-21686D01*
X671869Y-21751D01*
X671541Y-21828D01*
Y-21824D01*
X671538Y-21817D01*
X671530Y-21802D01*
X671523Y-21784D01*
X671516Y-21762D01*
X671505Y-21733D01*
X671476Y-21675D01*
X671440Y-21609D01*
X671396Y-21544D01*
X671341Y-21482D01*
X671283Y-21427D01*
X671276Y-21420D01*
X671254Y-21405D01*
X671217Y-21387D01*
X671170Y-21362D01*
X671108Y-21340D01*
X671039Y-21318D01*
X670955Y-21303D01*
X670864Y-21300D01*
X670835D01*
X670817Y-21303D01*
X670792D01*
X670762Y-21307D01*
X670693Y-21318D01*
X670617Y-21332D01*
X670537Y-21358D01*
X670453Y-21394D01*
X670377Y-21442D01*
X670373D01*
X670369Y-21449D01*
X670344Y-21467D01*
X670311Y-21496D01*
X670271Y-21540D01*
X670224Y-21595D01*
X670180Y-21656D01*
X670140Y-21733D01*
X670104Y-21817D01*
Y-21820D01*
X670100Y-21828D01*
X670096Y-21838D01*
X670093Y-21857D01*
X670085Y-21879D01*
X670078Y-21904D01*
X670067Y-21966D01*
X670053Y-22039D01*
X670038Y-22119D01*
X670031Y-22206D01*
X670027Y-22301D01*
Y-22304D01*
Y-22315D01*
Y-22333D01*
Y-22355D01*
X670031Y-22381D01*
Y-22414D01*
X670034Y-22450D01*
X670038Y-22490D01*
X670049Y-22577D01*
X670067Y-22672D01*
X670089Y-22767D01*
X670118Y-22861D01*
Y-22865D01*
X670122Y-22872D01*
X670129Y-22883D01*
X670136Y-22901D01*
X670158Y-22945D01*
X670191Y-22996D01*
X670231Y-23054D01*
X670282Y-23116D01*
X670340Y-23171D01*
X670409Y-23222D01*
X670413D01*
X670420Y-23225D01*
X670431Y-23233D01*
X670446Y-23240D01*
X670464Y-23247D01*
X670486Y-23258D01*
X670537Y-23280D01*
X670602Y-23302D01*
X670675Y-23320D01*
X670755Y-23335D01*
X670839Y-23338D01*
X670864D01*
X670886Y-23335D01*
X670912D01*
X670937Y-23331D01*
X671003Y-23316D01*
X671079Y-23298D01*
X671156Y-23269D01*
X671236Y-23229D01*
X671276Y-23207D01*
X671312Y-23178D01*
X671316Y-23174D01*
X671319Y-23171D01*
X671330Y-23160D01*
X671345Y-23149D01*
X671359Y-23131D01*
X671378Y-23109D01*
X671399Y-23087D01*
X671418Y-23058D01*
X671440Y-23025D01*
X671465Y-22989D01*
X671487Y-22952D01*
X671509Y-22909D01*
X671527Y-22861D01*
X671545Y-22810D01*
X671563Y-22756D01*
X671578Y-22697D01*
X671913Y-22781D01*
Y-22785D01*
X671909Y-22799D01*
X671902Y-22821D01*
X671891Y-22850D01*
X671880Y-22883D01*
X671865Y-22923D01*
X671847Y-22967D01*
X671825Y-23014D01*
X671774Y-23116D01*
X671709Y-23218D01*
X671669Y-23269D01*
X671629Y-23320D01*
X671585Y-23364D01*
X671534Y-23407D01*
X671530Y-23411D01*
X671523Y-23418D01*
X671505Y-23426D01*
X671487Y-23440D01*
X671458Y-23458D01*
X671428Y-23476D01*
X671388Y-23495D01*
X671348Y-23513D01*
X671301Y-23535D01*
X671250Y-23553D01*
X671196Y-23571D01*
X671137Y-23589D01*
X671075Y-23604D01*
X671010Y-23611D01*
X670941Y-23618D01*
X670868Y-23622D01*
X670828D01*
X670799Y-23618D01*
X670766D01*
X670726Y-23615D01*
X670682Y-23607D01*
X670631Y-23600D01*
X670526Y-23582D01*
X670417Y-23553D01*
X670307Y-23513D01*
X670257Y-23487D01*
X670205Y-23458D01*
X670202Y-23455D01*
X670195Y-23451D01*
X670180Y-23440D01*
X670165Y-23426D01*
X670144Y-23411D01*
X670118Y-23389D01*
X670089Y-23364D01*
X670060Y-23335D01*
X670031Y-23302D01*
X669998Y-23269D01*
X669933Y-23185D01*
X669871Y-23087D01*
X669816Y-22978D01*
Y-22974D01*
X669809Y-22963D01*
X669805Y-22945D01*
X669794Y-22923D01*
X669787Y-22894D01*
X669776Y-22858D01*
X669761Y-22818D01*
X669750Y-22774D01*
X669740Y-22727D01*
X669725Y-22672D01*
X669707Y-22559D01*
X669692Y-22432D01*
X669685Y-22301D01*
Y-22297D01*
Y-22283D01*
Y-22261D01*
X669689Y-22235D01*
Y-22199D01*
X669692Y-22163D01*
X669696Y-22115D01*
X669703Y-22068D01*
X669721Y-21962D01*
X669747Y-21846D01*
X669783Y-21729D01*
X669834Y-21617D01*
X669838Y-21613D01*
X669841Y-21602D01*
X669849Y-21587D01*
X669863Y-21569D01*
X669878Y-21544D01*
X669896Y-21515D01*
X669943Y-21449D01*
X670005Y-21376D01*
X670078Y-21303D01*
X670162Y-21231D01*
X670260Y-21169D01*
X670264Y-21165D01*
X670275Y-21161D01*
X670289Y-21154D01*
X670307Y-21143D01*
X670336Y-21132D01*
X670366Y-21121D01*
X670402Y-21107D01*
X670442Y-21092D01*
X670486Y-21078D01*
X670533Y-21063D01*
X670635Y-21041D01*
X670751Y-21023D01*
X670872Y-21016D01*
X670908D01*
X670933Y-21020D01*
D02*
G37*
G36*
X673063Y-21052D02*
X673110Y-21059D01*
X673169Y-21070D01*
X673234Y-21089D01*
X673300Y-21111D01*
X673365Y-21140D01*
X673369D01*
X673372Y-21143D01*
X673394Y-21154D01*
X673427Y-21176D01*
X673463Y-21202D01*
X673507Y-21238D01*
X673551Y-21278D01*
X673594Y-21325D01*
X673631Y-21380D01*
X673634Y-21387D01*
X673645Y-21405D01*
X673660Y-21438D01*
X673678Y-21478D01*
X673696Y-21526D01*
X673711Y-21580D01*
X673722Y-21642D01*
X673725Y-21704D01*
Y-21711D01*
Y-21733D01*
X673722Y-21762D01*
X673714Y-21802D01*
X673703Y-21849D01*
X673685Y-21900D01*
X673664Y-21951D01*
X673634Y-22002D01*
X673631Y-22010D01*
X673620Y-22024D01*
X673598Y-22050D01*
X673569Y-22079D01*
X673532Y-22111D01*
X673489Y-22148D01*
X673438Y-22181D01*
X673376Y-22213D01*
X673380D01*
X673387Y-22217D01*
X673398Y-22221D01*
X673412Y-22224D01*
X673452Y-22239D01*
X673503Y-22261D01*
X673562Y-22290D01*
X673620Y-22326D01*
X673674Y-22374D01*
X673725Y-22428D01*
X673729Y-22435D01*
X673744Y-22457D01*
X673765Y-22494D01*
X673787Y-22541D01*
X673809Y-22599D01*
X673831Y-22668D01*
X673845Y-22749D01*
X673849Y-22836D01*
Y-22840D01*
Y-22850D01*
Y-22869D01*
X673845Y-22891D01*
X673842Y-22920D01*
X673835Y-22952D01*
X673827Y-22989D01*
X673820Y-23029D01*
X673791Y-23116D01*
X673769Y-23164D01*
X673747Y-23207D01*
X673718Y-23255D01*
X673685Y-23302D01*
X673649Y-23349D01*
X673605Y-23393D01*
X673602Y-23396D01*
X673594Y-23404D01*
X673580Y-23415D01*
X673562Y-23429D01*
X673540Y-23447D01*
X673511Y-23466D01*
X673478Y-23487D01*
X673438Y-23506D01*
X673398Y-23528D01*
X673350Y-23549D01*
X673303Y-23568D01*
X673248Y-23586D01*
X673190Y-23600D01*
X673128Y-23611D01*
X673067Y-23618D01*
X672997Y-23622D01*
X672965D01*
X672943Y-23618D01*
X672914Y-23615D01*
X672881Y-23611D01*
X672845Y-23604D01*
X672804Y-23597D01*
X672717Y-23575D01*
X672626Y-23538D01*
X672579Y-23516D01*
X672535Y-23491D01*
X672491Y-23458D01*
X672448Y-23426D01*
X672444Y-23422D01*
X672437Y-23415D01*
X672426Y-23404D01*
X672415Y-23389D01*
X672397Y-23371D01*
X672379Y-23346D01*
X672357Y-23320D01*
X672335Y-23287D01*
X672313Y-23251D01*
X672291Y-23214D01*
X672251Y-23127D01*
X672218Y-23025D01*
X672207Y-22971D01*
X672200Y-22912D01*
X672510Y-22872D01*
Y-22876D01*
X672513Y-22883D01*
X672517Y-22898D01*
X672521Y-22916D01*
X672524Y-22938D01*
X672532Y-22963D01*
X672550Y-23018D01*
X672575Y-23083D01*
X672608Y-23145D01*
X672644Y-23203D01*
X672688Y-23255D01*
X672695Y-23258D01*
X672710Y-23273D01*
X672739Y-23291D01*
X672775Y-23309D01*
X672819Y-23331D01*
X672874Y-23349D01*
X672935Y-23364D01*
X673001Y-23367D01*
X673023D01*
X673037Y-23364D01*
X673077Y-23360D01*
X673128Y-23349D01*
X673187Y-23331D01*
X673248Y-23305D01*
X673310Y-23269D01*
X673369Y-23218D01*
X673376Y-23211D01*
X673394Y-23189D01*
X673416Y-23156D01*
X673445Y-23112D01*
X673474Y-23058D01*
X673496Y-22996D01*
X673514Y-22923D01*
X673522Y-22843D01*
Y-22840D01*
Y-22832D01*
Y-22821D01*
X673518Y-22807D01*
X673514Y-22767D01*
X673503Y-22719D01*
X673489Y-22661D01*
X673463Y-22603D01*
X673427Y-22545D01*
X673380Y-22490D01*
X673372Y-22483D01*
X673354Y-22468D01*
X673325Y-22446D01*
X673285Y-22421D01*
X673234Y-22395D01*
X673172Y-22374D01*
X673103Y-22359D01*
X673027Y-22352D01*
X672994D01*
X672968Y-22355D01*
X672935Y-22359D01*
X672899Y-22366D01*
X672855Y-22374D01*
X672808Y-22385D01*
X672845Y-22111D01*
X672863D01*
X672877Y-22115D01*
X672925D01*
X672965Y-22108D01*
X673012Y-22101D01*
X673067Y-22090D01*
X673128Y-22072D01*
X673187Y-22046D01*
X673248Y-22013D01*
X673252D01*
X673256Y-22010D01*
X673274Y-21995D01*
X673300Y-21970D01*
X673329Y-21937D01*
X673358Y-21890D01*
X673383Y-21835D01*
X673401Y-21773D01*
X673409Y-21737D01*
Y-21697D01*
Y-21693D01*
Y-21689D01*
Y-21667D01*
X673401Y-21638D01*
X673394Y-21598D01*
X673380Y-21555D01*
X673361Y-21507D01*
X673332Y-21460D01*
X673292Y-21416D01*
X673289Y-21413D01*
X673270Y-21398D01*
X673245Y-21380D01*
X673212Y-21358D01*
X673169Y-21340D01*
X673117Y-21322D01*
X673059Y-21307D01*
X672994Y-21303D01*
X672965D01*
X672932Y-21311D01*
X672888Y-21318D01*
X672841Y-21332D01*
X672793Y-21351D01*
X672743Y-21380D01*
X672695Y-21416D01*
X672692Y-21420D01*
X672677Y-21438D01*
X672655Y-21464D01*
X672630Y-21500D01*
X672604Y-21547D01*
X672579Y-21606D01*
X672557Y-21675D01*
X672542Y-21755D01*
X672233Y-21700D01*
Y-21697D01*
X672237Y-21686D01*
X672240Y-21671D01*
X672244Y-21649D01*
X672251Y-21624D01*
X672262Y-21595D01*
X672284Y-21526D01*
X672320Y-21445D01*
X672364Y-21365D01*
X672419Y-21289D01*
X672488Y-21220D01*
X672491Y-21216D01*
X672499Y-21212D01*
X672510Y-21205D01*
X672524Y-21194D01*
X672542Y-21180D01*
X672568Y-21165D01*
X672593Y-21150D01*
X672626Y-21132D01*
X672699Y-21103D01*
X672783Y-21074D01*
X672881Y-21056D01*
X672932Y-21049D01*
X673023D01*
X673063Y-21052D01*
D02*
G37*
G36*
X675706Y-21387D02*
X674697D01*
X674563Y-22068D01*
X674566Y-22064D01*
X674574Y-22061D01*
X674584Y-22053D01*
X674603Y-22042D01*
X674624Y-22031D01*
X674650Y-22017D01*
X674708Y-21988D01*
X674781Y-21959D01*
X674861Y-21933D01*
X674948Y-21915D01*
X674992Y-21908D01*
X675072D01*
X675094Y-21911D01*
X675123Y-21915D01*
X675156Y-21919D01*
X675192Y-21926D01*
X675232Y-21937D01*
X675320Y-21962D01*
X675367Y-21981D01*
X675414Y-22006D01*
X675462Y-22031D01*
X675509Y-22061D01*
X675553Y-22097D01*
X675596Y-22137D01*
X675600Y-22141D01*
X675607Y-22148D01*
X675618Y-22159D01*
X675633Y-22177D01*
X675651Y-22203D01*
X675669Y-22228D01*
X675691Y-22261D01*
X675713Y-22297D01*
X675731Y-22337D01*
X675753Y-22381D01*
X675771Y-22432D01*
X675789Y-22483D01*
X675804Y-22537D01*
X675815Y-22599D01*
X675822Y-22661D01*
X675826Y-22727D01*
Y-22730D01*
Y-22741D01*
Y-22759D01*
X675822Y-22785D01*
X675818Y-22814D01*
X675815Y-22847D01*
X675808Y-22887D01*
X675800Y-22927D01*
X675778Y-23021D01*
X675742Y-23120D01*
X675720Y-23171D01*
X675691Y-23218D01*
X675662Y-23269D01*
X675626Y-23316D01*
X675622Y-23320D01*
X675615Y-23331D01*
X675600Y-23346D01*
X675582Y-23364D01*
X675556Y-23385D01*
X675527Y-23415D01*
X675491Y-23440D01*
X675451Y-23469D01*
X675407Y-23498D01*
X675356Y-23524D01*
X675302Y-23549D01*
X675243Y-23575D01*
X675181Y-23593D01*
X675112Y-23607D01*
X675039Y-23618D01*
X674963Y-23622D01*
X674930D01*
X674905Y-23618D01*
X674876Y-23615D01*
X674843Y-23611D01*
X674803Y-23607D01*
X674763Y-23597D01*
X674672Y-23575D01*
X674581Y-23542D01*
X674534Y-23520D01*
X674486Y-23495D01*
X674442Y-23466D01*
X674399Y-23433D01*
X674395Y-23429D01*
X674388Y-23426D01*
X674381Y-23411D01*
X674366Y-23396D01*
X674348Y-23378D01*
X674330Y-23356D01*
X674308Y-23327D01*
X674290Y-23294D01*
X674268Y-23262D01*
X674246Y-23222D01*
X674206Y-23134D01*
X674173Y-23032D01*
X674162Y-22978D01*
X674155Y-22920D01*
X674479Y-22894D01*
Y-22898D01*
Y-22905D01*
X674482Y-22916D01*
X674486Y-22934D01*
X674497Y-22974D01*
X674512Y-23029D01*
X674534Y-23083D01*
X674563Y-23145D01*
X674599Y-23200D01*
X674643Y-23251D01*
X674650Y-23255D01*
X674664Y-23269D01*
X674694Y-23287D01*
X674734Y-23309D01*
X674777Y-23331D01*
X674832Y-23349D01*
X674894Y-23364D01*
X674963Y-23367D01*
X674985D01*
X674999Y-23364D01*
X675043Y-23360D01*
X675094Y-23346D01*
X675156Y-23327D01*
X675218Y-23298D01*
X675283Y-23255D01*
X675312Y-23229D01*
X675342Y-23200D01*
X675345Y-23196D01*
X675349Y-23193D01*
X675356Y-23182D01*
X675367Y-23171D01*
X675392Y-23131D01*
X675422Y-23080D01*
X675447Y-23018D01*
X675473Y-22941D01*
X675491Y-22850D01*
X675498Y-22803D01*
Y-22752D01*
Y-22749D01*
Y-22741D01*
Y-22727D01*
X675494Y-22708D01*
Y-22687D01*
X675491Y-22661D01*
X675480Y-22603D01*
X675462Y-22534D01*
X675436Y-22465D01*
X675400Y-22399D01*
X675349Y-22337D01*
Y-22333D01*
X675342Y-22330D01*
X675323Y-22312D01*
X675291Y-22286D01*
X675247Y-22257D01*
X675189Y-22232D01*
X675123Y-22206D01*
X675047Y-22188D01*
X675003Y-22181D01*
X674934D01*
X674905Y-22184D01*
X674868Y-22188D01*
X674825Y-22199D01*
X674781Y-22210D01*
X674734Y-22228D01*
X674686Y-22250D01*
X674683Y-22253D01*
X674668Y-22261D01*
X674646Y-22279D01*
X674617Y-22297D01*
X674588Y-22323D01*
X674559Y-22355D01*
X674526Y-22388D01*
X674501Y-22428D01*
X674209Y-22388D01*
X674453Y-21092D01*
X675706D01*
Y-21387D01*
D02*
G37*
G36*
X609931Y-21509D02*
X609960Y-21513D01*
X609993Y-21516D01*
X610030Y-21524D01*
X610070Y-21531D01*
X610157Y-21553D01*
X610248Y-21589D01*
X610295Y-21611D01*
X610339Y-21636D01*
X610383Y-21669D01*
X610426Y-21702D01*
X610430Y-21706D01*
X610437Y-21713D01*
X610448Y-21724D01*
X610459Y-21738D01*
X610477Y-21757D01*
X610495Y-21782D01*
X610517Y-21808D01*
X610539Y-21840D01*
X610561Y-21877D01*
X610583Y-21913D01*
X610623Y-22001D01*
X610656Y-22102D01*
X610667Y-22157D01*
X610674Y-22215D01*
X610364Y-22255D01*
Y-22252D01*
X610361Y-22244D01*
X610357Y-22230D01*
X610354Y-22212D01*
X610350Y-22190D01*
X610343Y-22164D01*
X610324Y-22110D01*
X610299Y-22044D01*
X610266Y-21982D01*
X610230Y-21924D01*
X610186Y-21873D01*
X610179Y-21869D01*
X610164Y-21855D01*
X610135Y-21837D01*
X610099Y-21818D01*
X610055Y-21797D01*
X610000Y-21779D01*
X609938Y-21764D01*
X609873Y-21760D01*
X609851D01*
X609837Y-21764D01*
X609797Y-21768D01*
X609746Y-21779D01*
X609687Y-21797D01*
X609625Y-21822D01*
X609564Y-21858D01*
X609505Y-21910D01*
X609498Y-21917D01*
X609480Y-21939D01*
X609458Y-21971D01*
X609429Y-22015D01*
X609400Y-22070D01*
X609378Y-22131D01*
X609360Y-22204D01*
X609352Y-22284D01*
Y-22288D01*
Y-22295D01*
Y-22306D01*
X609356Y-22321D01*
X609360Y-22361D01*
X609371Y-22408D01*
X609385Y-22466D01*
X609411Y-22525D01*
X609447Y-22583D01*
X609494Y-22637D01*
X609502Y-22645D01*
X609520Y-22659D01*
X609549Y-22681D01*
X609589Y-22707D01*
X609640Y-22732D01*
X609702Y-22754D01*
X609771Y-22769D01*
X609847Y-22776D01*
X609880D01*
X609906Y-22772D01*
X609938Y-22769D01*
X609975Y-22761D01*
X610019Y-22754D01*
X610066Y-22743D01*
X610030Y-23016D01*
X610011D01*
X609997Y-23012D01*
X609949D01*
X609909Y-23020D01*
X609862Y-23027D01*
X609807Y-23038D01*
X609746Y-23056D01*
X609687Y-23082D01*
X609625Y-23114D01*
X609622D01*
X609618Y-23118D01*
X609600Y-23133D01*
X609575Y-23158D01*
X609545Y-23191D01*
X609516Y-23238D01*
X609491Y-23293D01*
X609473Y-23355D01*
X609465Y-23391D01*
Y-23431D01*
Y-23435D01*
Y-23438D01*
Y-23460D01*
X609473Y-23489D01*
X609480Y-23529D01*
X609494Y-23573D01*
X609513Y-23620D01*
X609542Y-23668D01*
X609582Y-23711D01*
X609585Y-23715D01*
X609604Y-23730D01*
X609629Y-23748D01*
X609662Y-23769D01*
X609706Y-23788D01*
X609757Y-23806D01*
X609815Y-23821D01*
X609880Y-23824D01*
X609909D01*
X609942Y-23817D01*
X609986Y-23810D01*
X610033Y-23795D01*
X610080Y-23777D01*
X610131Y-23748D01*
X610179Y-23711D01*
X610182Y-23708D01*
X610197Y-23689D01*
X610219Y-23664D01*
X610244Y-23628D01*
X610270Y-23580D01*
X610295Y-23522D01*
X610317Y-23453D01*
X610332Y-23373D01*
X610641Y-23427D01*
Y-23431D01*
X610637Y-23442D01*
X610634Y-23457D01*
X610630Y-23478D01*
X610623Y-23504D01*
X610612Y-23533D01*
X610590Y-23602D01*
X610554Y-23682D01*
X610510Y-23762D01*
X610455Y-23839D01*
X610386Y-23908D01*
X610383Y-23911D01*
X610375Y-23915D01*
X610364Y-23922D01*
X610350Y-23933D01*
X610332Y-23948D01*
X610306Y-23963D01*
X610281Y-23977D01*
X610248Y-23995D01*
X610175Y-24024D01*
X610091Y-24054D01*
X609993Y-24072D01*
X609942Y-24079D01*
X609851D01*
X609811Y-24075D01*
X609764Y-24068D01*
X609706Y-24057D01*
X609640Y-24039D01*
X609575Y-24017D01*
X609509Y-23988D01*
X609505D01*
X609502Y-23984D01*
X609480Y-23973D01*
X609447Y-23952D01*
X609411Y-23926D01*
X609367Y-23890D01*
X609323Y-23850D01*
X609280Y-23802D01*
X609243Y-23748D01*
X609240Y-23740D01*
X609229Y-23722D01*
X609214Y-23689D01*
X609196Y-23649D01*
X609178Y-23602D01*
X609163Y-23548D01*
X609152Y-23486D01*
X609149Y-23424D01*
Y-23416D01*
Y-23395D01*
X609152Y-23366D01*
X609160Y-23325D01*
X609170Y-23278D01*
X609189Y-23227D01*
X609210Y-23176D01*
X609240Y-23125D01*
X609243Y-23118D01*
X609254Y-23103D01*
X609276Y-23078D01*
X609305Y-23049D01*
X609342Y-23016D01*
X609385Y-22980D01*
X609436Y-22947D01*
X609498Y-22914D01*
X609494D01*
X609487Y-22910D01*
X609476Y-22907D01*
X609462Y-22903D01*
X609422Y-22889D01*
X609371Y-22867D01*
X609312Y-22838D01*
X609254Y-22801D01*
X609200Y-22754D01*
X609149Y-22699D01*
X609145Y-22692D01*
X609130Y-22670D01*
X609109Y-22634D01*
X609087Y-22587D01*
X609065Y-22528D01*
X609043Y-22459D01*
X609028Y-22379D01*
X609025Y-22292D01*
Y-22288D01*
Y-22277D01*
Y-22259D01*
X609028Y-22237D01*
X609032Y-22208D01*
X609039Y-22175D01*
X609047Y-22139D01*
X609054Y-22099D01*
X609083Y-22011D01*
X609105Y-21964D01*
X609127Y-21920D01*
X609156Y-21873D01*
X609189Y-21826D01*
X609225Y-21779D01*
X609269Y-21735D01*
X609272Y-21731D01*
X609280Y-21724D01*
X609294Y-21713D01*
X609312Y-21698D01*
X609334Y-21680D01*
X609363Y-21662D01*
X609396Y-21640D01*
X609436Y-21622D01*
X609476Y-21600D01*
X609523Y-21578D01*
X609571Y-21560D01*
X609625Y-21542D01*
X609684Y-21527D01*
X609746Y-21516D01*
X609807Y-21509D01*
X609877Y-21506D01*
X609909D01*
X609931Y-21509D01*
D02*
G37*
G36*
X612075D02*
X612108D01*
X612148Y-21513D01*
X612192Y-21520D01*
X612243Y-21527D01*
X612348Y-21545D01*
X612457Y-21575D01*
X612567Y-21615D01*
X612618Y-21640D01*
X612669Y-21669D01*
X612672Y-21673D01*
X612679Y-21677D01*
X612694Y-21688D01*
X612709Y-21702D01*
X612730Y-21717D01*
X612756Y-21738D01*
X612785Y-21764D01*
X612814Y-21793D01*
X612843Y-21826D01*
X612876Y-21858D01*
X612942Y-21942D01*
X613003Y-22040D01*
X613058Y-22150D01*
Y-22153D01*
X613065Y-22164D01*
X613069Y-22183D01*
X613080Y-22204D01*
X613087Y-22233D01*
X613098Y-22270D01*
X613113Y-22310D01*
X613124Y-22354D01*
X613134Y-22401D01*
X613149Y-22456D01*
X613167Y-22568D01*
X613182Y-22696D01*
X613189Y-22827D01*
Y-22830D01*
Y-22845D01*
Y-22867D01*
X613185Y-22892D01*
Y-22929D01*
X613182Y-22965D01*
X613178Y-23012D01*
X613171Y-23060D01*
X613153Y-23165D01*
X613127Y-23282D01*
X613091Y-23398D01*
X613040Y-23511D01*
X613036Y-23515D01*
X613032Y-23526D01*
X613025Y-23540D01*
X613011Y-23558D01*
X612996Y-23584D01*
X612978Y-23613D01*
X612931Y-23678D01*
X612869Y-23751D01*
X612796Y-23824D01*
X612712Y-23897D01*
X612614Y-23959D01*
X612610Y-23963D01*
X612599Y-23966D01*
X612585Y-23973D01*
X612567Y-23984D01*
X612537Y-23995D01*
X612508Y-24006D01*
X612472Y-24021D01*
X612432Y-24035D01*
X612388Y-24050D01*
X612341Y-24064D01*
X612239Y-24086D01*
X612122Y-24104D01*
X612002Y-24112D01*
X611966D01*
X611940Y-24108D01*
X611908Y-24104D01*
X611868Y-24101D01*
X611828Y-24097D01*
X611780Y-24086D01*
X611682Y-24064D01*
X611573Y-24032D01*
X611518Y-24010D01*
X611467Y-23984D01*
X611416Y-23952D01*
X611365Y-23919D01*
X611362Y-23915D01*
X611354Y-23911D01*
X611340Y-23901D01*
X611322Y-23882D01*
X611304Y-23864D01*
X611278Y-23839D01*
X611252Y-23810D01*
X611223Y-23780D01*
X611194Y-23744D01*
X611165Y-23700D01*
X611132Y-23657D01*
X611103Y-23609D01*
X611078Y-23555D01*
X611049Y-23500D01*
X611027Y-23442D01*
X611005Y-23376D01*
X611333Y-23300D01*
Y-23304D01*
X611336Y-23311D01*
X611343Y-23325D01*
X611351Y-23344D01*
X611358Y-23366D01*
X611369Y-23395D01*
X611398Y-23453D01*
X611435Y-23518D01*
X611478Y-23584D01*
X611533Y-23646D01*
X611591Y-23700D01*
X611598Y-23708D01*
X611620Y-23722D01*
X611657Y-23740D01*
X611704Y-23766D01*
X611766Y-23788D01*
X611835Y-23810D01*
X611919Y-23824D01*
X612010Y-23828D01*
X612039D01*
X612057Y-23824D01*
X612082D01*
X612112Y-23821D01*
X612181Y-23810D01*
X612257Y-23795D01*
X612337Y-23769D01*
X612421Y-23733D01*
X612497Y-23686D01*
X612501D01*
X612505Y-23678D01*
X612530Y-23660D01*
X612563Y-23631D01*
X612603Y-23587D01*
X612650Y-23533D01*
X612694Y-23471D01*
X612734Y-23395D01*
X612770Y-23311D01*
Y-23307D01*
X612774Y-23300D01*
X612778Y-23289D01*
X612781Y-23271D01*
X612789Y-23249D01*
X612796Y-23223D01*
X612807Y-23162D01*
X612821Y-23089D01*
X612836Y-23009D01*
X612843Y-22921D01*
X612847Y-22827D01*
Y-22823D01*
Y-22812D01*
Y-22794D01*
Y-22772D01*
X612843Y-22747D01*
Y-22714D01*
X612840Y-22678D01*
X612836Y-22637D01*
X612825Y-22550D01*
X612807Y-22456D01*
X612785Y-22361D01*
X612756Y-22266D01*
Y-22263D01*
X612752Y-22255D01*
X612745Y-22244D01*
X612738Y-22226D01*
X612716Y-22183D01*
X612683Y-22131D01*
X612643Y-22073D01*
X612592Y-22011D01*
X612534Y-21957D01*
X612465Y-21906D01*
X612461D01*
X612454Y-21902D01*
X612443Y-21895D01*
X612428Y-21888D01*
X612410Y-21880D01*
X612388Y-21869D01*
X612337Y-21848D01*
X612272Y-21826D01*
X612199Y-21808D01*
X612119Y-21793D01*
X612035Y-21789D01*
X612010D01*
X611988Y-21793D01*
X611962D01*
X611937Y-21797D01*
X611871Y-21811D01*
X611795Y-21829D01*
X611719Y-21858D01*
X611638Y-21899D01*
X611598Y-21920D01*
X611562Y-21949D01*
X611558Y-21953D01*
X611555Y-21957D01*
X611544Y-21968D01*
X611529Y-21979D01*
X611515Y-21997D01*
X611496Y-22019D01*
X611475Y-22040D01*
X611456Y-22070D01*
X611435Y-22102D01*
X611409Y-22139D01*
X611387Y-22175D01*
X611365Y-22219D01*
X611347Y-22266D01*
X611329Y-22317D01*
X611311Y-22372D01*
X611296Y-22430D01*
X610961Y-22346D01*
Y-22343D01*
X610965Y-22328D01*
X610972Y-22306D01*
X610983Y-22277D01*
X610994Y-22244D01*
X611009Y-22204D01*
X611027Y-22161D01*
X611049Y-22113D01*
X611100Y-22011D01*
X611165Y-21910D01*
X611205Y-21858D01*
X611245Y-21808D01*
X611289Y-21764D01*
X611340Y-21720D01*
X611343Y-21717D01*
X611351Y-21709D01*
X611369Y-21702D01*
X611387Y-21688D01*
X611416Y-21669D01*
X611446Y-21651D01*
X611485Y-21633D01*
X611526Y-21615D01*
X611573Y-21593D01*
X611624Y-21575D01*
X611678Y-21556D01*
X611737Y-21538D01*
X611798Y-21524D01*
X611864Y-21516D01*
X611933Y-21509D01*
X612006Y-21506D01*
X612046D01*
X612075Y-21509D01*
D02*
G37*
G36*
X607729Y-22153D02*
X608825D01*
Y-22437D01*
X607671Y-24068D01*
X607420D01*
Y-22437D01*
X607078D01*
Y-22153D01*
X607420D01*
Y-21549D01*
X607729D01*
Y-22153D01*
D02*
G37*
G36*
X90954Y-94344D02*
X90990D01*
X91027Y-94347D01*
X91074Y-94351D01*
X91121Y-94358D01*
X91227Y-94376D01*
X91343Y-94402D01*
X91460Y-94438D01*
X91573Y-94489D01*
X91576Y-94493D01*
X91587Y-94497D01*
X91602Y-94504D01*
X91620Y-94519D01*
X91645Y-94533D01*
X91675Y-94551D01*
X91740Y-94599D01*
X91813Y-94661D01*
X91886Y-94733D01*
X91958Y-94817D01*
X92020Y-94915D01*
X92024Y-94919D01*
X92027Y-94930D01*
X92035Y-94944D01*
X92046Y-94963D01*
X92057Y-94992D01*
X92068Y-95021D01*
X92082Y-95057D01*
X92097Y-95097D01*
X92111Y-95141D01*
X92126Y-95188D01*
X92148Y-95290D01*
X92166Y-95407D01*
X92173Y-95527D01*
Y-95563D01*
X92169Y-95589D01*
X92166Y-95621D01*
X92162Y-95661D01*
X92159Y-95701D01*
X92148Y-95749D01*
X92126Y-95847D01*
X92093Y-95956D01*
X92071Y-96011D01*
X92046Y-96062D01*
X92013Y-96113D01*
X91980Y-96164D01*
X91977Y-96167D01*
X91973Y-96175D01*
X91962Y-96189D01*
X91944Y-96207D01*
X91926Y-96226D01*
X91900Y-96251D01*
X91871Y-96277D01*
X91842Y-96306D01*
X91805Y-96335D01*
X91762Y-96364D01*
X91718Y-96397D01*
X91671Y-96426D01*
X91616Y-96451D01*
X91562Y-96480D01*
X91503Y-96502D01*
X91438Y-96524D01*
X91361Y-96197D01*
X91365D01*
X91372Y-96193D01*
X91387Y-96186D01*
X91405Y-96178D01*
X91427Y-96171D01*
X91456Y-96160D01*
X91514Y-96131D01*
X91580Y-96095D01*
X91645Y-96051D01*
X91707Y-95996D01*
X91762Y-95938D01*
X91769Y-95931D01*
X91784Y-95909D01*
X91802Y-95873D01*
X91827Y-95825D01*
X91849Y-95763D01*
X91871Y-95694D01*
X91886Y-95610D01*
X91889Y-95520D01*
Y-95490D01*
X91886Y-95472D01*
Y-95447D01*
X91882Y-95418D01*
X91871Y-95348D01*
X91856Y-95272D01*
X91831Y-95192D01*
X91795Y-95108D01*
X91747Y-95032D01*
Y-95028D01*
X91740Y-95025D01*
X91722Y-94999D01*
X91693Y-94966D01*
X91649Y-94926D01*
X91594Y-94879D01*
X91532Y-94835D01*
X91456Y-94795D01*
X91372Y-94759D01*
X91369D01*
X91361Y-94755D01*
X91351Y-94751D01*
X91332Y-94748D01*
X91311Y-94740D01*
X91285Y-94733D01*
X91223Y-94722D01*
X91150Y-94708D01*
X91070Y-94693D01*
X90983Y-94686D01*
X90888Y-94682D01*
X90885D01*
X90874D01*
X90855D01*
X90834D01*
X90808Y-94686D01*
X90775D01*
X90739Y-94690D01*
X90699Y-94693D01*
X90612Y-94704D01*
X90517Y-94722D01*
X90422Y-94744D01*
X90328Y-94773D01*
X90324D01*
X90317Y-94777D01*
X90306Y-94784D01*
X90288Y-94792D01*
X90244Y-94813D01*
X90193Y-94846D01*
X90135Y-94886D01*
X90073Y-94937D01*
X90018Y-94995D01*
X89967Y-95065D01*
Y-95068D01*
X89964Y-95075D01*
X89956Y-95086D01*
X89949Y-95101D01*
X89942Y-95119D01*
X89931Y-95141D01*
X89909Y-95192D01*
X89887Y-95257D01*
X89869Y-95330D01*
X89855Y-95410D01*
X89851Y-95494D01*
Y-95520D01*
X89855Y-95541D01*
Y-95567D01*
X89858Y-95592D01*
X89873Y-95658D01*
X89891Y-95734D01*
X89920Y-95811D01*
X89960Y-95891D01*
X89982Y-95931D01*
X90011Y-95967D01*
X90015Y-95971D01*
X90018Y-95974D01*
X90029Y-95985D01*
X90040Y-96000D01*
X90058Y-96014D01*
X90080Y-96033D01*
X90102Y-96055D01*
X90131Y-96073D01*
X90164Y-96095D01*
X90200Y-96120D01*
X90237Y-96142D01*
X90280Y-96164D01*
X90328Y-96182D01*
X90379Y-96200D01*
X90433Y-96218D01*
X90491Y-96233D01*
X90408Y-96568D01*
X90404D01*
X90390Y-96564D01*
X90368Y-96557D01*
X90339Y-96546D01*
X90306Y-96535D01*
X90266Y-96521D01*
X90222Y-96502D01*
X90175Y-96480D01*
X90073Y-96430D01*
X89971Y-96364D01*
X89920Y-96324D01*
X89869Y-96284D01*
X89825Y-96240D01*
X89782Y-96189D01*
X89778Y-96186D01*
X89771Y-96178D01*
X89763Y-96160D01*
X89749Y-96142D01*
X89731Y-96113D01*
X89713Y-96084D01*
X89694Y-96044D01*
X89676Y-96004D01*
X89654Y-95956D01*
X89636Y-95905D01*
X89618Y-95851D01*
X89600Y-95793D01*
X89585Y-95731D01*
X89578Y-95665D01*
X89571Y-95596D01*
X89567Y-95523D01*
Y-95483D01*
X89571Y-95454D01*
Y-95421D01*
X89574Y-95381D01*
X89582Y-95337D01*
X89589Y-95287D01*
X89607Y-95181D01*
X89636Y-95072D01*
X89676Y-94963D01*
X89702Y-94912D01*
X89731Y-94861D01*
X89734Y-94857D01*
X89738Y-94850D01*
X89749Y-94835D01*
X89763Y-94821D01*
X89778Y-94799D01*
X89800Y-94773D01*
X89825Y-94744D01*
X89855Y-94715D01*
X89887Y-94686D01*
X89920Y-94653D01*
X90004Y-94588D01*
X90102Y-94526D01*
X90211Y-94471D01*
X90215D01*
X90226Y-94464D01*
X90244Y-94460D01*
X90266Y-94449D01*
X90295Y-94442D01*
X90331Y-94431D01*
X90371Y-94417D01*
X90415Y-94406D01*
X90462Y-94395D01*
X90517Y-94380D01*
X90630Y-94362D01*
X90757Y-94347D01*
X90888Y-94340D01*
X90892D01*
X90906D01*
X90928D01*
X90954Y-94344D01*
D02*
G37*
G36*
X90855Y-96841D02*
X90906D01*
X90965Y-96844D01*
X91034Y-96852D01*
X91110Y-96859D01*
X91194Y-96870D01*
X91278Y-96885D01*
X91369Y-96903D01*
X91456Y-96925D01*
X91543Y-96950D01*
X91627Y-96983D01*
X91707Y-97019D01*
X91784Y-97059D01*
X91849Y-97106D01*
X91853Y-97110D01*
X91860Y-97117D01*
X91875Y-97132D01*
X91896Y-97150D01*
X91918Y-97172D01*
X91940Y-97201D01*
X91969Y-97238D01*
X91995Y-97274D01*
X92020Y-97318D01*
X92049Y-97365D01*
X92071Y-97420D01*
X92097Y-97474D01*
X92115Y-97536D01*
X92129Y-97602D01*
X92137Y-97671D01*
X92140Y-97743D01*
Y-97773D01*
X92137Y-97795D01*
Y-97820D01*
X92133Y-97849D01*
X92119Y-97918D01*
X92100Y-97995D01*
X92071Y-98075D01*
X92027Y-98155D01*
X92002Y-98195D01*
X91973Y-98231D01*
X91969Y-98235D01*
X91966Y-98239D01*
X91955Y-98250D01*
X91944Y-98260D01*
X91926Y-98279D01*
X91904Y-98293D01*
X91853Y-98333D01*
X91787Y-98373D01*
X91707Y-98410D01*
X91616Y-98442D01*
X91514Y-98464D01*
X91489Y-98155D01*
X91492D01*
X91496Y-98151D01*
X91518Y-98148D01*
X91551Y-98137D01*
X91591Y-98122D01*
X91634Y-98107D01*
X91678Y-98086D01*
X91718Y-98060D01*
X91751Y-98035D01*
X91758Y-98027D01*
X91773Y-98013D01*
X91795Y-97987D01*
X91820Y-97951D01*
X91842Y-97904D01*
X91864Y-97853D01*
X91878Y-97791D01*
X91886Y-97725D01*
Y-97700D01*
X91882Y-97671D01*
X91875Y-97638D01*
X91864Y-97594D01*
X91849Y-97551D01*
X91831Y-97507D01*
X91802Y-97463D01*
X91798Y-97456D01*
X91784Y-97438D01*
X91758Y-97412D01*
X91722Y-97379D01*
X91678Y-97343D01*
X91627Y-97303D01*
X91562Y-97267D01*
X91489Y-97230D01*
X91485D01*
X91478Y-97227D01*
X91467Y-97223D01*
X91452Y-97216D01*
X91431Y-97212D01*
X91405Y-97205D01*
X91376Y-97198D01*
X91340Y-97190D01*
X91299Y-97179D01*
X91256Y-97172D01*
X91209Y-97165D01*
X91158Y-97161D01*
X91099Y-97154D01*
X91041Y-97150D01*
X90976Y-97147D01*
X90910D01*
X90914Y-97150D01*
X90936Y-97165D01*
X90965Y-97190D01*
X91001Y-97223D01*
X91045Y-97259D01*
X91085Y-97307D01*
X91125Y-97358D01*
X91161Y-97416D01*
Y-97420D01*
X91165Y-97423D01*
X91176Y-97445D01*
X91187Y-97478D01*
X91205Y-97522D01*
X91220Y-97572D01*
X91230Y-97631D01*
X91241Y-97693D01*
X91245Y-97758D01*
Y-97787D01*
X91241Y-97809D01*
X91238Y-97838D01*
X91234Y-97867D01*
X91227Y-97904D01*
X91216Y-97940D01*
X91190Y-98024D01*
X91172Y-98067D01*
X91147Y-98111D01*
X91121Y-98155D01*
X91092Y-98202D01*
X91056Y-98246D01*
X91016Y-98286D01*
X91012Y-98290D01*
X91005Y-98297D01*
X90994Y-98308D01*
X90976Y-98319D01*
X90950Y-98337D01*
X90925Y-98355D01*
X90892Y-98373D01*
X90855Y-98395D01*
X90815Y-98417D01*
X90772Y-98435D01*
X90721Y-98453D01*
X90670Y-98471D01*
X90615Y-98482D01*
X90553Y-98493D01*
X90491Y-98501D01*
X90426Y-98504D01*
X90422D01*
X90415D01*
X90404D01*
X90386D01*
X90364Y-98501D01*
X90342D01*
X90284Y-98490D01*
X90215Y-98479D01*
X90142Y-98461D01*
X90062Y-98435D01*
X89986Y-98399D01*
X89982D01*
X89978Y-98395D01*
X89967Y-98388D01*
X89953Y-98381D01*
X89916Y-98359D01*
X89869Y-98326D01*
X89818Y-98286D01*
X89767Y-98239D01*
X89716Y-98180D01*
X89672Y-98118D01*
Y-98115D01*
X89669Y-98111D01*
X89662Y-98100D01*
X89658Y-98086D01*
X89640Y-98049D01*
X89622Y-98002D01*
X89600Y-97940D01*
X89585Y-97871D01*
X89571Y-97795D01*
X89567Y-97711D01*
Y-97693D01*
X89571Y-97674D01*
Y-97645D01*
X89574Y-97613D01*
X89582Y-97576D01*
X89592Y-97532D01*
X89603Y-97489D01*
X89618Y-97438D01*
X89636Y-97387D01*
X89658Y-97336D01*
X89687Y-97281D01*
X89720Y-97230D01*
X89756Y-97179D01*
X89800Y-97128D01*
X89851Y-97081D01*
X89855Y-97077D01*
X89865Y-97070D01*
X89880Y-97059D01*
X89905Y-97045D01*
X89938Y-97023D01*
X89975Y-97005D01*
X90022Y-96983D01*
X90073Y-96961D01*
X90135Y-96935D01*
X90204Y-96914D01*
X90280Y-96895D01*
X90364Y-96877D01*
X90459Y-96859D01*
X90561Y-96848D01*
X90670Y-96841D01*
X90786Y-96837D01*
X90790D01*
X90794D01*
X90804D01*
X90819D01*
X90855Y-96841D01*
D02*
G37*
G36*
X90965Y-98814D02*
X91008D01*
X91056Y-98817D01*
X91110Y-98821D01*
X91223Y-98832D01*
X91343Y-98850D01*
X91463Y-98872D01*
X91518Y-98887D01*
X91573Y-98901D01*
X91576D01*
X91584Y-98905D01*
X91598Y-98912D01*
X91616Y-98919D01*
X91642Y-98927D01*
X91667Y-98941D01*
X91729Y-98970D01*
X91795Y-99007D01*
X91864Y-99054D01*
X91933Y-99108D01*
X91991Y-99174D01*
Y-99178D01*
X91998Y-99181D01*
X92006Y-99192D01*
X92013Y-99207D01*
X92027Y-99225D01*
X92039Y-99247D01*
X92068Y-99301D01*
X92093Y-99367D01*
X92119Y-99443D01*
X92133Y-99534D01*
X92140Y-99633D01*
Y-99665D01*
X92137Y-99705D01*
X92129Y-99753D01*
X92119Y-99807D01*
X92104Y-99866D01*
X92086Y-99928D01*
X92057Y-99986D01*
Y-99989D01*
X92053Y-99993D01*
X92042Y-100011D01*
X92024Y-100040D01*
X91998Y-100077D01*
X91962Y-100117D01*
X91922Y-100161D01*
X91875Y-100200D01*
X91820Y-100241D01*
X91813Y-100244D01*
X91795Y-100259D01*
X91762Y-100273D01*
X91715Y-100299D01*
X91660Y-100321D01*
X91598Y-100350D01*
X91525Y-100375D01*
X91445Y-100397D01*
X91442D01*
X91434Y-100401D01*
X91423Y-100404D01*
X91405Y-100408D01*
X91383Y-100412D01*
X91358Y-100415D01*
X91325Y-100423D01*
X91289Y-100426D01*
X91249Y-100434D01*
X91205Y-100437D01*
X91154Y-100441D01*
X91103Y-100448D01*
X91045Y-100452D01*
X90987D01*
X90921Y-100455D01*
X90852D01*
X90848D01*
X90834D01*
X90808D01*
X90779D01*
X90739Y-100452D01*
X90695D01*
X90648Y-100448D01*
X90597Y-100444D01*
X90481Y-100434D01*
X90360Y-100415D01*
X90244Y-100393D01*
X90189Y-100379D01*
X90135Y-100361D01*
X90131D01*
X90124Y-100357D01*
X90109Y-100350D01*
X90091Y-100343D01*
X90066Y-100335D01*
X90040Y-100321D01*
X89978Y-100292D01*
X89913Y-100255D01*
X89840Y-100208D01*
X89774Y-100153D01*
X89713Y-100088D01*
Y-100084D01*
X89705Y-100080D01*
X89698Y-100069D01*
X89691Y-100055D01*
X89680Y-100037D01*
X89665Y-100019D01*
X89640Y-99964D01*
X89614Y-99898D01*
X89589Y-99822D01*
X89574Y-99731D01*
X89567Y-99633D01*
Y-99596D01*
X89571Y-99571D01*
X89574Y-99542D01*
X89582Y-99505D01*
X89589Y-99465D01*
X89600Y-99422D01*
X89614Y-99378D01*
X89629Y-99331D01*
X89651Y-99283D01*
X89676Y-99236D01*
X89705Y-99189D01*
X89742Y-99141D01*
X89782Y-99098D01*
X89825Y-99058D01*
X89829Y-99054D01*
X89840Y-99047D01*
X89858Y-99036D01*
X89887Y-99018D01*
X89920Y-98999D01*
X89964Y-98981D01*
X90015Y-98956D01*
X90073Y-98934D01*
X90138Y-98912D01*
X90215Y-98890D01*
X90299Y-98868D01*
X90393Y-98850D01*
X90495Y-98832D01*
X90604Y-98821D01*
X90724Y-98814D01*
X90852Y-98810D01*
X90855D01*
X90870D01*
X90895D01*
X90925D01*
X90965Y-98814D01*
D02*
G37*
G36*
X124418Y-76037D02*
X124455D01*
X124491Y-76040D01*
X124538Y-76044D01*
X124586Y-76051D01*
X124691Y-76069D01*
X124808Y-76095D01*
X124924Y-76131D01*
X125037Y-76182D01*
X125041Y-76186D01*
X125052Y-76190D01*
X125066Y-76197D01*
X125084Y-76211D01*
X125110Y-76226D01*
X125139Y-76244D01*
X125205Y-76292D01*
X125277Y-76353D01*
X125350Y-76426D01*
X125423Y-76510D01*
X125485Y-76608D01*
X125488Y-76612D01*
X125492Y-76623D01*
X125499Y-76637D01*
X125510Y-76656D01*
X125521Y-76685D01*
X125532Y-76714D01*
X125547Y-76750D01*
X125561Y-76790D01*
X125576Y-76834D01*
X125590Y-76881D01*
X125612Y-76983D01*
X125630Y-77100D01*
X125638Y-77220D01*
Y-77256D01*
X125634Y-77282D01*
X125630Y-77314D01*
X125627Y-77354D01*
X125623Y-77394D01*
X125612Y-77442D01*
X125590Y-77540D01*
X125558Y-77649D01*
X125536Y-77704D01*
X125510Y-77755D01*
X125478Y-77806D01*
X125445Y-77857D01*
X125441Y-77860D01*
X125437Y-77868D01*
X125427Y-77882D01*
X125408Y-77900D01*
X125390Y-77919D01*
X125365Y-77944D01*
X125336Y-77969D01*
X125306Y-77999D01*
X125270Y-78028D01*
X125226Y-78057D01*
X125183Y-78090D01*
X125135Y-78119D01*
X125081Y-78144D01*
X125026Y-78173D01*
X124968Y-78195D01*
X124902Y-78217D01*
X124826Y-77889D01*
X124830D01*
X124837Y-77886D01*
X124852Y-77878D01*
X124870Y-77871D01*
X124891Y-77864D01*
X124921Y-77853D01*
X124979Y-77824D01*
X125044Y-77788D01*
X125110Y-77744D01*
X125172Y-77689D01*
X125226Y-77631D01*
X125234Y-77624D01*
X125248Y-77602D01*
X125266Y-77565D01*
X125292Y-77518D01*
X125314Y-77456D01*
X125336Y-77387D01*
X125350Y-77303D01*
X125354Y-77212D01*
Y-77183D01*
X125350Y-77165D01*
Y-77140D01*
X125347Y-77110D01*
X125336Y-77041D01*
X125321Y-76965D01*
X125295Y-76885D01*
X125259Y-76801D01*
X125212Y-76725D01*
Y-76721D01*
X125205Y-76717D01*
X125186Y-76692D01*
X125157Y-76659D01*
X125113Y-76619D01*
X125059Y-76572D01*
X124997Y-76528D01*
X124921Y-76488D01*
X124837Y-76452D01*
X124833D01*
X124826Y-76448D01*
X124815Y-76444D01*
X124797Y-76441D01*
X124775Y-76433D01*
X124750Y-76426D01*
X124688Y-76415D01*
X124615Y-76401D01*
X124535Y-76386D01*
X124447Y-76379D01*
X124353Y-76375D01*
X124349D01*
X124338D01*
X124320D01*
X124298D01*
X124273Y-76379D01*
X124240D01*
X124204Y-76382D01*
X124163Y-76386D01*
X124076Y-76397D01*
X123981Y-76415D01*
X123887Y-76437D01*
X123792Y-76466D01*
X123789D01*
X123781Y-76470D01*
X123770Y-76477D01*
X123752Y-76484D01*
X123708Y-76506D01*
X123658Y-76539D01*
X123599Y-76579D01*
X123537Y-76630D01*
X123483Y-76688D01*
X123432Y-76757D01*
Y-76761D01*
X123428Y-76768D01*
X123421Y-76779D01*
X123414Y-76794D01*
X123406Y-76812D01*
X123396Y-76834D01*
X123374Y-76885D01*
X123352Y-76950D01*
X123334Y-77023D01*
X123319Y-77103D01*
X123315Y-77187D01*
Y-77212D01*
X123319Y-77234D01*
Y-77260D01*
X123323Y-77285D01*
X123337Y-77351D01*
X123355Y-77427D01*
X123384Y-77504D01*
X123425Y-77584D01*
X123446Y-77624D01*
X123476Y-77660D01*
X123479Y-77664D01*
X123483Y-77667D01*
X123494Y-77678D01*
X123505Y-77693D01*
X123523Y-77707D01*
X123545Y-77726D01*
X123566Y-77747D01*
X123596Y-77766D01*
X123628Y-77788D01*
X123665Y-77813D01*
X123701Y-77835D01*
X123745Y-77857D01*
X123792Y-77875D01*
X123843Y-77893D01*
X123898Y-77911D01*
X123956Y-77926D01*
X123872Y-78261D01*
X123869D01*
X123854Y-78257D01*
X123832Y-78250D01*
X123803Y-78239D01*
X123770Y-78228D01*
X123730Y-78213D01*
X123687Y-78195D01*
X123639Y-78173D01*
X123537Y-78122D01*
X123435Y-78057D01*
X123384Y-78017D01*
X123334Y-77977D01*
X123290Y-77933D01*
X123246Y-77882D01*
X123243Y-77878D01*
X123235Y-77871D01*
X123228Y-77853D01*
X123214Y-77835D01*
X123195Y-77806D01*
X123177Y-77777D01*
X123159Y-77737D01*
X123141Y-77697D01*
X123119Y-77649D01*
X123101Y-77598D01*
X123082Y-77544D01*
X123064Y-77485D01*
X123050Y-77424D01*
X123042Y-77358D01*
X123035Y-77289D01*
X123031Y-77216D01*
Y-77176D01*
X123035Y-77147D01*
Y-77114D01*
X123039Y-77074D01*
X123046Y-77030D01*
X123053Y-76979D01*
X123072Y-76874D01*
X123101Y-76765D01*
X123141Y-76656D01*
X123166Y-76604D01*
X123195Y-76554D01*
X123199Y-76550D01*
X123203Y-76543D01*
X123214Y-76528D01*
X123228Y-76513D01*
X123243Y-76492D01*
X123264Y-76466D01*
X123290Y-76437D01*
X123319Y-76408D01*
X123352Y-76379D01*
X123384Y-76346D01*
X123468Y-76281D01*
X123566Y-76219D01*
X123676Y-76164D01*
X123679D01*
X123690Y-76157D01*
X123708Y-76153D01*
X123730Y-76142D01*
X123759Y-76135D01*
X123796Y-76124D01*
X123836Y-76109D01*
X123880Y-76099D01*
X123927Y-76088D01*
X123981Y-76073D01*
X124094Y-76055D01*
X124222Y-76040D01*
X124353Y-76033D01*
X124356D01*
X124371D01*
X124393D01*
X124418Y-76037D01*
D02*
G37*
G36*
X123759Y-78869D02*
X123756D01*
X123749D01*
X123738Y-78872D01*
X123719Y-78876D01*
X123679Y-78887D01*
X123625Y-78901D01*
X123570Y-78923D01*
X123508Y-78952D01*
X123454Y-78989D01*
X123403Y-79032D01*
X123399Y-79040D01*
X123384Y-79054D01*
X123366Y-79083D01*
X123345Y-79123D01*
X123323Y-79167D01*
X123304Y-79222D01*
X123290Y-79284D01*
X123286Y-79353D01*
Y-79375D01*
X123290Y-79389D01*
X123293Y-79433D01*
X123308Y-79484D01*
X123326Y-79546D01*
X123355Y-79607D01*
X123399Y-79673D01*
X123425Y-79702D01*
X123454Y-79731D01*
X123457Y-79735D01*
X123461Y-79739D01*
X123472Y-79746D01*
X123483Y-79757D01*
X123523Y-79782D01*
X123574Y-79811D01*
X123636Y-79837D01*
X123712Y-79862D01*
X123803Y-79880D01*
X123851Y-79888D01*
X123901D01*
X123905D01*
X123912D01*
X123927D01*
X123945Y-79884D01*
X123967D01*
X123992Y-79880D01*
X124051Y-79870D01*
X124120Y-79851D01*
X124189Y-79826D01*
X124255Y-79790D01*
X124316Y-79739D01*
X124320D01*
X124324Y-79731D01*
X124342Y-79713D01*
X124367Y-79680D01*
X124397Y-79637D01*
X124422Y-79578D01*
X124447Y-79513D01*
X124466Y-79436D01*
X124473Y-79393D01*
Y-79324D01*
X124469Y-79295D01*
X124466Y-79258D01*
X124455Y-79214D01*
X124444Y-79171D01*
X124426Y-79123D01*
X124404Y-79076D01*
X124400Y-79072D01*
X124393Y-79058D01*
X124375Y-79036D01*
X124356Y-79007D01*
X124331Y-78978D01*
X124298Y-78949D01*
X124265Y-78916D01*
X124225Y-78890D01*
X124265Y-78599D01*
X125561Y-78843D01*
Y-80095D01*
X125266D01*
Y-79087D01*
X124586Y-78952D01*
X124589Y-78956D01*
X124593Y-78963D01*
X124600Y-78974D01*
X124611Y-78992D01*
X124622Y-79014D01*
X124637Y-79040D01*
X124666Y-79098D01*
X124695Y-79171D01*
X124720Y-79251D01*
X124739Y-79338D01*
X124746Y-79382D01*
Y-79462D01*
X124742Y-79484D01*
X124739Y-79513D01*
X124735Y-79546D01*
X124728Y-79582D01*
X124717Y-79622D01*
X124691Y-79709D01*
X124673Y-79757D01*
X124648Y-79804D01*
X124622Y-79851D01*
X124593Y-79899D01*
X124557Y-79942D01*
X124517Y-79986D01*
X124513Y-79990D01*
X124506Y-79997D01*
X124495Y-80008D01*
X124477Y-80023D01*
X124451Y-80041D01*
X124426Y-80059D01*
X124393Y-80081D01*
X124356Y-80103D01*
X124316Y-80121D01*
X124273Y-80143D01*
X124222Y-80161D01*
X124171Y-80179D01*
X124116Y-80194D01*
X124054Y-80204D01*
X123992Y-80212D01*
X123927Y-80215D01*
X123923D01*
X123912D01*
X123894D01*
X123869Y-80212D01*
X123839Y-80208D01*
X123807Y-80204D01*
X123767Y-80197D01*
X123727Y-80190D01*
X123632Y-80168D01*
X123534Y-80132D01*
X123483Y-80110D01*
X123435Y-80081D01*
X123384Y-80052D01*
X123337Y-80015D01*
X123334Y-80012D01*
X123323Y-80004D01*
X123308Y-79990D01*
X123290Y-79971D01*
X123268Y-79946D01*
X123239Y-79917D01*
X123214Y-79880D01*
X123184Y-79840D01*
X123155Y-79797D01*
X123130Y-79746D01*
X123104Y-79691D01*
X123079Y-79633D01*
X123061Y-79571D01*
X123046Y-79502D01*
X123035Y-79429D01*
X123031Y-79353D01*
Y-79320D01*
X123035Y-79295D01*
X123039Y-79265D01*
X123042Y-79233D01*
X123046Y-79193D01*
X123057Y-79153D01*
X123079Y-79062D01*
X123111Y-78970D01*
X123133Y-78923D01*
X123159Y-78876D01*
X123188Y-78832D01*
X123221Y-78789D01*
X123224Y-78785D01*
X123228Y-78778D01*
X123243Y-78770D01*
X123257Y-78756D01*
X123275Y-78738D01*
X123297Y-78719D01*
X123326Y-78698D01*
X123359Y-78679D01*
X123392Y-78658D01*
X123432Y-78636D01*
X123519Y-78596D01*
X123621Y-78563D01*
X123676Y-78552D01*
X123734Y-78545D01*
X123759Y-78869D01*
D02*
G37*
G36*
X123839Y-80503D02*
X123861D01*
X123887Y-80507D01*
X123945Y-80514D01*
X124011Y-80528D01*
X124076Y-80550D01*
X124145Y-80583D01*
X124211Y-80623D01*
X124214D01*
X124218Y-80630D01*
X124236Y-80645D01*
X124265Y-80674D01*
X124302Y-80714D01*
X124338Y-80765D01*
X124378Y-80827D01*
X124411Y-80896D01*
X124436Y-80980D01*
Y-80976D01*
X124440Y-80972D01*
X124444Y-80962D01*
X124451Y-80947D01*
X124466Y-80914D01*
X124487Y-80871D01*
X124517Y-80823D01*
X124553Y-80776D01*
X124593Y-80732D01*
X124637Y-80692D01*
X124644Y-80689D01*
X124659Y-80678D01*
X124688Y-80663D01*
X124724Y-80649D01*
X124771Y-80630D01*
X124826Y-80616D01*
X124888Y-80605D01*
X124953Y-80601D01*
X124957D01*
X124964D01*
X124979D01*
X125001Y-80605D01*
X125022Y-80608D01*
X125052Y-80612D01*
X125113Y-80627D01*
X125186Y-80649D01*
X125263Y-80685D01*
X125303Y-80707D01*
X125343Y-80732D01*
X125379Y-80765D01*
X125416Y-80798D01*
X125419Y-80801D01*
X125423Y-80809D01*
X125434Y-80820D01*
X125445Y-80834D01*
X125459Y-80852D01*
X125474Y-80878D01*
X125492Y-80907D01*
X125510Y-80936D01*
X125529Y-80972D01*
X125547Y-81013D01*
X125561Y-81056D01*
X125576Y-81104D01*
X125598Y-81205D01*
X125601Y-81264D01*
X125605Y-81322D01*
Y-81355D01*
X125601Y-81377D01*
X125598Y-81406D01*
X125594Y-81438D01*
X125590Y-81475D01*
X125580Y-81511D01*
X125558Y-81599D01*
X125525Y-81686D01*
X125503Y-81730D01*
X125478Y-81773D01*
X125445Y-81813D01*
X125412Y-81853D01*
X125408Y-81857D01*
X125405Y-81861D01*
X125394Y-81872D01*
X125379Y-81886D01*
X125357Y-81901D01*
X125336Y-81919D01*
X125281Y-81955D01*
X125212Y-81992D01*
X125132Y-82025D01*
X125041Y-82050D01*
X124993Y-82054D01*
X124943Y-82057D01*
X124939D01*
X124935D01*
X124913D01*
X124881Y-82054D01*
X124840Y-82046D01*
X124790Y-82035D01*
X124739Y-82017D01*
X124688Y-81995D01*
X124637Y-81963D01*
X124629Y-81959D01*
X124615Y-81944D01*
X124593Y-81923D01*
X124564Y-81893D01*
X124531Y-81853D01*
X124498Y-81806D01*
X124466Y-81752D01*
X124436Y-81686D01*
Y-81690D01*
X124433Y-81697D01*
X124429Y-81708D01*
X124422Y-81722D01*
X124404Y-81766D01*
X124378Y-81817D01*
X124342Y-81872D01*
X124302Y-81930D01*
X124251Y-81984D01*
X124193Y-82035D01*
X124189D01*
X124185Y-82039D01*
X124163Y-82054D01*
X124127Y-82075D01*
X124080Y-82097D01*
X124021Y-82119D01*
X123952Y-82141D01*
X123876Y-82156D01*
X123792Y-82159D01*
X123789D01*
X123778D01*
X123759D01*
X123738Y-82156D01*
X123712Y-82152D01*
X123679Y-82148D01*
X123643Y-82141D01*
X123603Y-82130D01*
X123519Y-82105D01*
X123472Y-82086D01*
X123428Y-82061D01*
X123381Y-82035D01*
X123337Y-82006D01*
X123293Y-81970D01*
X123250Y-81930D01*
X123246Y-81926D01*
X123239Y-81919D01*
X123228Y-81908D01*
X123217Y-81890D01*
X123199Y-81864D01*
X123181Y-81839D01*
X123162Y-81806D01*
X123141Y-81770D01*
X123119Y-81730D01*
X123101Y-81682D01*
X123082Y-81631D01*
X123064Y-81580D01*
X123053Y-81522D01*
X123042Y-81460D01*
X123035Y-81398D01*
X123031Y-81329D01*
Y-81293D01*
X123035Y-81267D01*
X123039Y-81235D01*
X123042Y-81198D01*
X123050Y-81158D01*
X123061Y-81115D01*
X123086Y-81016D01*
X123104Y-80965D01*
X123123Y-80918D01*
X123148Y-80867D01*
X123177Y-80816D01*
X123210Y-80769D01*
X123250Y-80725D01*
X123254Y-80721D01*
X123261Y-80714D01*
X123272Y-80703D01*
X123290Y-80689D01*
X123312Y-80674D01*
X123337Y-80652D01*
X123366Y-80634D01*
X123403Y-80612D01*
X123439Y-80590D01*
X123483Y-80572D01*
X123574Y-80536D01*
X123628Y-80521D01*
X123683Y-80510D01*
X123741Y-80503D01*
X123800Y-80499D01*
X123803D01*
X123810D01*
X123825D01*
X123839Y-80503D01*
D02*
G37*
G36*
X517728Y-124486D02*
Y-124490D01*
Y-124505D01*
Y-124523D01*
Y-124548D01*
X517725Y-124581D01*
Y-124618D01*
X517721Y-124661D01*
X517717Y-124705D01*
X517706Y-124803D01*
X517692Y-124905D01*
X517670Y-125003D01*
X517655Y-125051D01*
X517641Y-125094D01*
Y-125098D01*
X517637Y-125105D01*
X517630Y-125116D01*
X517623Y-125131D01*
X517601Y-125171D01*
X517568Y-125222D01*
X517524Y-125280D01*
X517473Y-125338D01*
X517408Y-125400D01*
X517328Y-125455D01*
X517324D01*
X517317Y-125462D01*
X517306Y-125466D01*
X517288Y-125477D01*
X517266Y-125487D01*
X517237Y-125498D01*
X517208Y-125509D01*
X517171Y-125524D01*
X517131Y-125539D01*
X517088Y-125549D01*
X517040Y-125560D01*
X516986Y-125571D01*
X516931Y-125578D01*
X516873Y-125586D01*
X516742Y-125593D01*
X516709D01*
X516683Y-125590D01*
X516654D01*
X516618Y-125586D01*
X516578Y-125582D01*
X516538Y-125578D01*
X516447Y-125564D01*
X516349Y-125542D01*
X516254Y-125513D01*
X516163Y-125473D01*
X516159D01*
X516152Y-125466D01*
X516141Y-125458D01*
X516127Y-125451D01*
X516086Y-125422D01*
X516039Y-125382D01*
X515985Y-125331D01*
X515934Y-125273D01*
X515883Y-125200D01*
X515843Y-125120D01*
Y-125116D01*
X515839Y-125109D01*
X515835Y-125094D01*
X515828Y-125076D01*
X515821Y-125054D01*
X515814Y-125025D01*
X515803Y-124993D01*
X515795Y-124952D01*
X515788Y-124909D01*
X515777Y-124861D01*
X515770Y-124811D01*
X515763Y-124756D01*
X515755Y-124694D01*
X515752Y-124628D01*
X515748Y-124559D01*
Y-124486D01*
Y-123030D01*
X516083D01*
Y-124486D01*
Y-124490D01*
Y-124501D01*
Y-124519D01*
Y-124541D01*
X516086Y-124567D01*
Y-124599D01*
X516090Y-124669D01*
X516097Y-124749D01*
X516108Y-124829D01*
X516123Y-124905D01*
X516130Y-124938D01*
X516141Y-124971D01*
X516145Y-124978D01*
X516152Y-124996D01*
X516170Y-125022D01*
X516192Y-125058D01*
X516218Y-125094D01*
X516254Y-125134D01*
X516298Y-125174D01*
X516349Y-125207D01*
X516356Y-125211D01*
X516374Y-125222D01*
X516407Y-125233D01*
X516451Y-125247D01*
X516502Y-125266D01*
X516567Y-125276D01*
X516636Y-125287D01*
X516713Y-125291D01*
X516749D01*
X516771Y-125287D01*
X516804D01*
X516836Y-125284D01*
X516917Y-125269D01*
X517004Y-125251D01*
X517088Y-125222D01*
X517168Y-125182D01*
X517204Y-125156D01*
X517237Y-125127D01*
X517240Y-125124D01*
X517244Y-125120D01*
X517251Y-125109D01*
X517262Y-125094D01*
X517273Y-125073D01*
X517288Y-125051D01*
X517302Y-125018D01*
X517317Y-124985D01*
X517331Y-124945D01*
X517342Y-124898D01*
X517357Y-124843D01*
X517368Y-124785D01*
X517379Y-124720D01*
X517386Y-124650D01*
X517393Y-124570D01*
Y-124486D01*
Y-123030D01*
X517728D01*
Y-124486D01*
D02*
G37*
G36*
X521416Y-124661D02*
X521758D01*
Y-124945D01*
X521416D01*
Y-125549D01*
X521106D01*
Y-124945D01*
X520011D01*
Y-124661D01*
X521164Y-123030D01*
X521416D01*
Y-124661D01*
D02*
G37*
G36*
X519322Y-125549D02*
X519013D01*
Y-123580D01*
X519009Y-123584D01*
X518991Y-123598D01*
X518969Y-123620D01*
X518933Y-123646D01*
X518893Y-123678D01*
X518842Y-123715D01*
X518784Y-123755D01*
X518718Y-123795D01*
X518715D01*
X518711Y-123799D01*
X518689Y-123813D01*
X518653Y-123831D01*
X518609Y-123853D01*
X518558Y-123879D01*
X518504Y-123904D01*
X518449Y-123930D01*
X518394Y-123951D01*
Y-123653D01*
X518398D01*
X518405Y-123646D01*
X518420Y-123642D01*
X518438Y-123631D01*
X518460Y-123620D01*
X518485Y-123606D01*
X518547Y-123569D01*
X518620Y-123529D01*
X518693Y-123478D01*
X518769Y-123420D01*
X518846Y-123358D01*
X518849Y-123354D01*
X518853Y-123351D01*
X518864Y-123340D01*
X518878Y-123329D01*
X518911Y-123293D01*
X518955Y-123249D01*
X518998Y-123198D01*
X519046Y-123140D01*
X519086Y-123082D01*
X519122Y-123020D01*
X519322D01*
Y-125549D01*
D02*
G37*
G36*
X462451Y-126171D02*
X460995D01*
X460992D01*
X460981D01*
X460963D01*
X460941D01*
X460915Y-126175D01*
X460883D01*
X460813Y-126178D01*
X460733Y-126186D01*
X460653Y-126197D01*
X460577Y-126211D01*
X460544Y-126218D01*
X460511Y-126229D01*
X460504Y-126233D01*
X460486Y-126240D01*
X460460Y-126259D01*
X460424Y-126280D01*
X460388Y-126306D01*
X460348Y-126342D01*
X460307Y-126386D01*
X460275Y-126437D01*
X460271Y-126444D01*
X460260Y-126462D01*
X460249Y-126495D01*
X460235Y-126539D01*
X460216Y-126590D01*
X460206Y-126655D01*
X460195Y-126724D01*
X460191Y-126801D01*
Y-126837D01*
X460195Y-126859D01*
Y-126892D01*
X460198Y-126925D01*
X460213Y-127005D01*
X460231Y-127092D01*
X460260Y-127176D01*
X460300Y-127256D01*
X460326Y-127292D01*
X460355Y-127325D01*
X460358Y-127329D01*
X460362Y-127332D01*
X460373Y-127340D01*
X460388Y-127350D01*
X460409Y-127361D01*
X460431Y-127376D01*
X460464Y-127391D01*
X460497Y-127405D01*
X460537Y-127420D01*
X460584Y-127430D01*
X460639Y-127445D01*
X460697Y-127456D01*
X460762Y-127467D01*
X460832Y-127474D01*
X460912Y-127481D01*
X460995D01*
X462451D01*
Y-127816D01*
X460995D01*
X460992D01*
X460977D01*
X460959D01*
X460933D01*
X460901Y-127813D01*
X460864D01*
X460821Y-127809D01*
X460777Y-127805D01*
X460679Y-127795D01*
X460577Y-127780D01*
X460478Y-127758D01*
X460431Y-127744D01*
X460388Y-127729D01*
X460384D01*
X460377Y-127725D01*
X460366Y-127718D01*
X460351Y-127711D01*
X460311Y-127689D01*
X460260Y-127656D01*
X460202Y-127613D01*
X460144Y-127562D01*
X460082Y-127496D01*
X460027Y-127416D01*
Y-127412D01*
X460020Y-127405D01*
X460016Y-127394D01*
X460005Y-127376D01*
X459994Y-127354D01*
X459983Y-127325D01*
X459972Y-127296D01*
X459958Y-127260D01*
X459943Y-127219D01*
X459933Y-127176D01*
X459922Y-127128D01*
X459911Y-127074D01*
X459903Y-127019D01*
X459896Y-126961D01*
X459889Y-126830D01*
Y-126797D01*
X459893Y-126772D01*
Y-126743D01*
X459896Y-126706D01*
X459900Y-126666D01*
X459903Y-126626D01*
X459918Y-126535D01*
X459940Y-126437D01*
X459969Y-126342D01*
X460009Y-126251D01*
Y-126248D01*
X460016Y-126240D01*
X460023Y-126229D01*
X460031Y-126215D01*
X460060Y-126175D01*
X460100Y-126127D01*
X460151Y-126073D01*
X460209Y-126022D01*
X460282Y-125971D01*
X460362Y-125931D01*
X460366D01*
X460373Y-125927D01*
X460388Y-125924D01*
X460406Y-125916D01*
X460428Y-125909D01*
X460457Y-125902D01*
X460489Y-125891D01*
X460529Y-125883D01*
X460573Y-125876D01*
X460620Y-125865D01*
X460671Y-125858D01*
X460726Y-125851D01*
X460788Y-125844D01*
X460853Y-125840D01*
X460923Y-125836D01*
X460995D01*
X462451D01*
Y-126171D01*
D02*
G37*
G36*
X462419Y-129899D02*
X462175D01*
X462171Y-129895D01*
X462164Y-129888D01*
X462149Y-129873D01*
X462127Y-129858D01*
X462102Y-129837D01*
X462073Y-129807D01*
X462036Y-129778D01*
X461993Y-129746D01*
X461949Y-129713D01*
X461898Y-129673D01*
X461840Y-129633D01*
X461782Y-129593D01*
X461716Y-129549D01*
X461647Y-129505D01*
X461571Y-129462D01*
X461494Y-129418D01*
X461490Y-129414D01*
X461476Y-129407D01*
X461454Y-129396D01*
X461421Y-129378D01*
X461381Y-129360D01*
X461338Y-129338D01*
X461287Y-129312D01*
X461228Y-129287D01*
X461163Y-129258D01*
X461097Y-129225D01*
X461025Y-129196D01*
X460948Y-129167D01*
X460791Y-129109D01*
X460624Y-129054D01*
X460620D01*
X460609Y-129050D01*
X460591Y-129047D01*
X460569Y-129039D01*
X460540Y-129032D01*
X460504Y-129025D01*
X460464Y-129014D01*
X460420Y-129007D01*
X460369Y-128996D01*
X460315Y-128985D01*
X460198Y-128967D01*
X460071Y-128948D01*
X459933Y-128937D01*
Y-128621D01*
X459936D01*
X459947D01*
X459962D01*
X459983Y-128624D01*
X460013D01*
X460049Y-128628D01*
X460089Y-128632D01*
X460133Y-128635D01*
X460184Y-128643D01*
X460235Y-128650D01*
X460296Y-128661D01*
X460358Y-128672D01*
X460424Y-128683D01*
X460497Y-128697D01*
X460646Y-128734D01*
X460650D01*
X460664Y-128737D01*
X460686Y-128745D01*
X460719Y-128755D01*
X460755Y-128766D01*
X460799Y-128781D01*
X460850Y-128796D01*
X460904Y-128817D01*
X460966Y-128839D01*
X461028Y-128861D01*
X461166Y-128916D01*
X461312Y-128981D01*
X461458Y-129054D01*
X461461Y-129058D01*
X461476Y-129065D01*
X461494Y-129076D01*
X461523Y-129090D01*
X461556Y-129109D01*
X461596Y-129134D01*
X461640Y-129159D01*
X461687Y-129189D01*
X461793Y-129258D01*
X461902Y-129331D01*
X462015Y-129414D01*
X462120Y-129502D01*
Y-128268D01*
X462419D01*
Y-129899D01*
D02*
G37*
%LPC*%
G36*
X688109Y-27894D02*
X687275D01*
Y-28644D01*
X687279Y-28687D01*
X687283Y-28738D01*
X687286Y-28797D01*
X687294Y-28855D01*
X687305Y-28913D01*
X687319Y-28964D01*
X687323Y-28971D01*
X687330Y-28986D01*
X687341Y-29008D01*
X687356Y-29037D01*
X687377Y-29070D01*
X687403Y-29102D01*
X687436Y-29135D01*
X687472Y-29161D01*
X687476Y-29164D01*
X687490Y-29172D01*
X687512Y-29182D01*
X687541Y-29197D01*
X687574Y-29208D01*
X687610Y-29219D01*
X687654Y-29226D01*
X687698Y-29230D01*
X687701D01*
X687705D01*
X687727Y-29226D01*
X687760Y-29223D01*
X687803Y-29215D01*
X687847Y-29197D01*
X687898Y-29175D01*
X687945Y-29142D01*
X687992Y-29099D01*
X687996Y-29092D01*
X688011Y-29073D01*
X688029Y-29044D01*
X688051Y-28997D01*
X688073Y-28942D01*
X688091Y-28869D01*
X688105Y-28786D01*
X688109Y-28687D01*
Y-27894D01*
D02*
G37*
G36*
X687756Y-30384D02*
X687752D01*
X687749D01*
X687727Y-30387D01*
X687694Y-30391D01*
X687654Y-30398D01*
X687607Y-30413D01*
X687559Y-30431D01*
X687508Y-30460D01*
X687465Y-30496D01*
X687461Y-30500D01*
X687446Y-30518D01*
X687428Y-30544D01*
X687410Y-30577D01*
X687388Y-30620D01*
X687370Y-30671D01*
X687356Y-30729D01*
X687352Y-30795D01*
Y-30802D01*
X687356Y-30824D01*
X687359Y-30857D01*
X687366Y-30900D01*
X687381Y-30948D01*
X687399Y-30995D01*
X687428Y-31046D01*
X687465Y-31090D01*
X687468Y-31093D01*
X687487Y-31108D01*
X687508Y-31126D01*
X687541Y-31148D01*
X687581Y-31170D01*
X687629Y-31188D01*
X687683Y-31203D01*
X687741Y-31206D01*
X687745D01*
X687749D01*
X687771D01*
X687803Y-31199D01*
X687843Y-31192D01*
X687887Y-31177D01*
X687934Y-31155D01*
X687982Y-31126D01*
X688029Y-31086D01*
X688033Y-31082D01*
X688047Y-31064D01*
X688065Y-31039D01*
X688087Y-31006D01*
X688109Y-30962D01*
X688127Y-30915D01*
X688142Y-30857D01*
X688145Y-30795D01*
Y-30766D01*
X688138Y-30733D01*
X688131Y-30689D01*
X688116Y-30642D01*
X688098Y-30591D01*
X688069Y-30544D01*
X688029Y-30496D01*
X688025Y-30493D01*
X688011Y-30478D01*
X687985Y-30460D01*
X687953Y-30442D01*
X687912Y-30420D01*
X687865Y-30402D01*
X687814Y-30387D01*
X687756Y-30384D01*
D02*
G37*
G36*
X686595Y-30282D02*
X686587D01*
X686573D01*
X686547Y-30285D01*
X686515Y-30289D01*
X686475Y-30296D01*
X686431Y-30307D01*
X686387Y-30322D01*
X686340Y-30340D01*
X686336Y-30344D01*
X686318Y-30351D01*
X686296Y-30365D01*
X686271Y-30387D01*
X686238Y-30413D01*
X686205Y-30446D01*
X686176Y-30482D01*
X686147Y-30526D01*
X686143Y-30533D01*
X686136Y-30547D01*
X686125Y-30573D01*
X686114Y-30606D01*
X686103Y-30646D01*
X686092Y-30693D01*
X686085Y-30744D01*
X686082Y-30795D01*
Y-30817D01*
X686085Y-30831D01*
X686089Y-30875D01*
X686100Y-30926D01*
X686118Y-30984D01*
X686140Y-31046D01*
X686176Y-31104D01*
X686224Y-31163D01*
X686231Y-31170D01*
X686249Y-31185D01*
X686282Y-31210D01*
X686322Y-31235D01*
X686373Y-31261D01*
X686435Y-31286D01*
X686507Y-31301D01*
X686584Y-31308D01*
X686587D01*
X686595D01*
X686606D01*
X686620Y-31305D01*
X686660Y-31301D01*
X686715Y-31290D01*
X686769Y-31272D01*
X686831Y-31246D01*
X686893Y-31210D01*
X686951Y-31159D01*
X686959Y-31152D01*
X686973Y-31133D01*
X686999Y-31101D01*
X687028Y-31057D01*
X687053Y-31003D01*
X687079Y-30937D01*
X687093Y-30864D01*
X687101Y-30784D01*
Y-30762D01*
X687097Y-30748D01*
X687093Y-30708D01*
X687082Y-30657D01*
X687064Y-30598D01*
X687039Y-30540D01*
X687002Y-30478D01*
X686955Y-30424D01*
X686948Y-30416D01*
X686930Y-30402D01*
X686897Y-30380D01*
X686857Y-30355D01*
X686802Y-30325D01*
X686740Y-30304D01*
X686671Y-30289D01*
X686595Y-30282D01*
D02*
G37*
G36*
X686320Y-32329D02*
X686304Y-32338D01*
X686245Y-32375D01*
X686194Y-32418D01*
X686191Y-32426D01*
X686176Y-32440D01*
X686158Y-32469D01*
X686140Y-32506D01*
X686118Y-32550D01*
X686100Y-32604D01*
X686085Y-32666D01*
X686082Y-32732D01*
Y-32753D01*
X686085Y-32768D01*
X686089Y-32808D01*
X686100Y-32859D01*
X686118Y-32917D01*
X686120Y-32923D01*
X686137Y-32914D01*
X686196Y-32878D01*
X686247Y-32834D01*
X686250Y-32827D01*
X686265Y-32812D01*
X686283Y-32783D01*
X686301Y-32747D01*
X686323Y-32703D01*
X686341Y-32648D01*
X686356Y-32587D01*
X686359Y-32521D01*
Y-32499D01*
X686356Y-32485D01*
X686352Y-32445D01*
X686341Y-32394D01*
X686323Y-32335D01*
X686320Y-32329D01*
D02*
G37*
G36*
X684878Y-33970D02*
X684874D01*
X684867D01*
X684852D01*
X684834Y-33973D01*
X684809D01*
X684783Y-33977D01*
X684725Y-33988D01*
X684656Y-34002D01*
X684583Y-34028D01*
X684514Y-34064D01*
X684452Y-34112D01*
X684448D01*
X684445Y-34119D01*
X684427Y-34137D01*
X684401Y-34166D01*
X684372Y-34206D01*
X684346Y-34257D01*
X684321Y-34315D01*
X684303Y-34381D01*
X684296Y-34417D01*
Y-34476D01*
X684299Y-34490D01*
X684303Y-34530D01*
X684317Y-34578D01*
X684336Y-34636D01*
X684368Y-34698D01*
X684408Y-34760D01*
X684438Y-34789D01*
X684467Y-34818D01*
X684470D01*
X684474Y-34825D01*
X684485Y-34832D01*
X684496Y-34840D01*
X684532Y-34865D01*
X684583Y-34891D01*
X684645Y-34920D01*
X684721Y-34945D01*
X684809Y-34960D01*
X684903Y-34967D01*
X684907D01*
X684914D01*
X684925D01*
X684943Y-34963D01*
X684965D01*
X684987Y-34960D01*
X685042Y-34949D01*
X685104Y-34931D01*
X685169Y-34909D01*
X685235Y-34872D01*
X685293Y-34825D01*
X685300Y-34818D01*
X685315Y-34800D01*
X685340Y-34767D01*
X685366Y-34727D01*
X685395Y-34672D01*
X685420Y-34610D01*
X685435Y-34541D01*
X685442Y-34465D01*
Y-34443D01*
X685438Y-34428D01*
X685435Y-34388D01*
X685424Y-34341D01*
X685406Y-34283D01*
X685380Y-34225D01*
X685344Y-34166D01*
X685293Y-34112D01*
X685286Y-34104D01*
X685264Y-34090D01*
X685231Y-34068D01*
X685184Y-34039D01*
X685125Y-34013D01*
X685056Y-33992D01*
X684973Y-33977D01*
X684878Y-33970D01*
D02*
G37*
G36*
X685886Y-323846D02*
X685136D01*
X685092Y-323850D01*
X685041Y-323853D01*
X684983Y-323857D01*
X684925Y-323864D01*
X684866Y-323875D01*
X684816Y-323890D01*
X684808Y-323893D01*
X684794Y-323901D01*
X684772Y-323911D01*
X684743Y-323926D01*
X684710Y-323948D01*
X684677Y-323973D01*
X684644Y-324006D01*
X684619Y-324043D01*
X684615Y-324046D01*
X684608Y-324061D01*
X684597Y-324082D01*
X684583Y-324112D01*
X684572Y-324144D01*
X684561Y-324181D01*
X684553Y-324224D01*
X684550Y-324268D01*
Y-324272D01*
Y-324275D01*
X684553Y-324297D01*
X684557Y-324330D01*
X684564Y-324374D01*
X684583Y-324417D01*
X684604Y-324468D01*
X684637Y-324516D01*
X684681Y-324563D01*
X684688Y-324567D01*
X684706Y-324581D01*
X684735Y-324599D01*
X684783Y-324621D01*
X684837Y-324643D01*
X684910Y-324661D01*
X684994Y-324676D01*
X685092Y-324679D01*
X685886D01*
Y-323846D01*
D02*
G37*
G36*
X672500Y-322786D02*
X671903D01*
X671877Y-322789D01*
X671823Y-322793D01*
X671761Y-322797D01*
X671695Y-322804D01*
X671630Y-322815D01*
X671575Y-322829D01*
X671568Y-322833D01*
X671550Y-322837D01*
X671524Y-322848D01*
X671491Y-322862D01*
X671455Y-322884D01*
X671419Y-322906D01*
X671382Y-322931D01*
X671346Y-322960D01*
X671342Y-322968D01*
X671328Y-322982D01*
X671306Y-323008D01*
X671280Y-323044D01*
X671251Y-323092D01*
X671218Y-323146D01*
X671189Y-323208D01*
X671164Y-323277D01*
Y-323281D01*
X671160Y-323288D01*
X671157Y-323299D01*
X671153Y-323313D01*
X671149Y-323332D01*
X671142Y-323357D01*
X671135Y-323383D01*
X671128Y-323412D01*
X671117Y-323485D01*
X671106Y-323568D01*
X671098Y-323663D01*
X671095Y-323765D01*
Y-323768D01*
Y-323783D01*
Y-323801D01*
X671098Y-323830D01*
Y-323863D01*
X671102Y-323900D01*
X671106Y-323943D01*
X671109Y-323987D01*
X671128Y-324085D01*
X671149Y-324187D01*
X671182Y-324282D01*
X671204Y-324329D01*
X671226Y-324369D01*
Y-324373D01*
X671233Y-324380D01*
X671240Y-324391D01*
X671248Y-324406D01*
X671277Y-324442D01*
X671313Y-324486D01*
X671360Y-324533D01*
X671415Y-324580D01*
X671477Y-324620D01*
X671543Y-324653D01*
X671550Y-324657D01*
X671568Y-324660D01*
X671601Y-324671D01*
X671648Y-324682D01*
X671706Y-324689D01*
X671779Y-324700D01*
X671823Y-324704D01*
X671870D01*
X671917Y-324708D01*
X672500D01*
Y-322786D01*
D02*
G37*
G36*
X670225Y-323375D02*
X669431D01*
Y-324504D01*
X670225Y-323375D01*
D02*
G37*
G36*
X672500Y-315349D02*
X671903D01*
X671877Y-315353D01*
X671823Y-315356D01*
X671761Y-315360D01*
X671695Y-315367D01*
X671630Y-315378D01*
X671575Y-315393D01*
X671568Y-315396D01*
X671550Y-315400D01*
X671524Y-315411D01*
X671491Y-315425D01*
X671455Y-315447D01*
X671419Y-315469D01*
X671382Y-315495D01*
X671346Y-315524D01*
X671342Y-315531D01*
X671328Y-315546D01*
X671306Y-315571D01*
X671280Y-315608D01*
X671251Y-315655D01*
X671218Y-315709D01*
X671189Y-315771D01*
X671164Y-315841D01*
Y-315844D01*
X671160Y-315851D01*
X671157Y-315862D01*
X671153Y-315877D01*
X671149Y-315895D01*
X671142Y-315921D01*
X671135Y-315946D01*
X671128Y-315975D01*
X671116Y-316048D01*
X671106Y-316132D01*
X671098Y-316226D01*
X671095Y-316328D01*
Y-316332D01*
Y-316347D01*
Y-316365D01*
X671098Y-316394D01*
Y-316426D01*
X671102Y-316463D01*
X671106Y-316507D01*
X671109Y-316550D01*
X671128Y-316649D01*
X671149Y-316751D01*
X671182Y-316845D01*
X671204Y-316893D01*
X671226Y-316933D01*
Y-316936D01*
X671233Y-316943D01*
X671240Y-316954D01*
X671248Y-316969D01*
X671277Y-317005D01*
X671313Y-317049D01*
X671360Y-317096D01*
X671415Y-317144D01*
X671477Y-317184D01*
X671542Y-317216D01*
X671550Y-317220D01*
X671568Y-317224D01*
X671601Y-317235D01*
X671648Y-317246D01*
X671706Y-317253D01*
X671779Y-317264D01*
X671823Y-317267D01*
X671870D01*
X671917Y-317271D01*
X672500D01*
Y-315349D01*
D02*
G37*
G36*
X667640Y-315262D02*
X667619D01*
X667604Y-315265D01*
X667567Y-315273D01*
X667517Y-315287D01*
X667462Y-315313D01*
X667400Y-315349D01*
X667371Y-315371D01*
X667342Y-315400D01*
X667313Y-315429D01*
X667284Y-315466D01*
Y-315469D01*
X667276Y-315476D01*
X667269Y-315487D01*
X667262Y-315506D01*
X667247Y-315531D01*
X667236Y-315564D01*
X667222Y-315600D01*
X667207Y-315644D01*
X667196Y-315699D01*
X667182Y-315757D01*
X667167Y-315826D01*
X667156Y-315899D01*
X667149Y-315986D01*
X667142Y-316077D01*
X667134Y-316179D01*
Y-316292D01*
Y-316296D01*
Y-316299D01*
Y-316317D01*
Y-316350D01*
X667138Y-316394D01*
Y-316441D01*
X667142Y-316499D01*
X667145Y-316561D01*
X667153Y-316630D01*
X667171Y-316769D01*
X667182Y-316838D01*
X667196Y-316903D01*
X667211Y-316965D01*
X667233Y-317023D01*
X667254Y-317074D01*
X667280Y-317118D01*
Y-317122D01*
X667287Y-317125D01*
X667295Y-317136D01*
X667306Y-317151D01*
X667338Y-317184D01*
X667378Y-317224D01*
X667433Y-317260D01*
X667495Y-317293D01*
X667527Y-317307D01*
X667564Y-317318D01*
X667604Y-317322D01*
X667644Y-317326D01*
X667666D01*
X667680Y-317322D01*
X667720Y-317315D01*
X667768Y-317304D01*
X667822Y-317282D01*
X667881Y-317249D01*
X667910Y-317227D01*
X667939Y-317206D01*
X667964Y-317176D01*
X667990Y-317144D01*
Y-317140D01*
X667997Y-317133D01*
X668004Y-317118D01*
X668015Y-317100D01*
X668026Y-317071D01*
X668041Y-317038D01*
X668052Y-316998D01*
X668066Y-316951D01*
X668081Y-316896D01*
X668095Y-316834D01*
X668110Y-316765D01*
X668121Y-316689D01*
X668132Y-316601D01*
X668139Y-316507D01*
X668143Y-316405D01*
X668146Y-316292D01*
Y-316285D01*
Y-316266D01*
Y-316234D01*
X668143Y-316190D01*
Y-316143D01*
X668139Y-316084D01*
X668135Y-316022D01*
X668128Y-315957D01*
X668110Y-315815D01*
X668099Y-315746D01*
X668084Y-315680D01*
X668070Y-315618D01*
X668048Y-315560D01*
X668026Y-315509D01*
X668001Y-315466D01*
Y-315462D01*
X667993Y-315458D01*
X667975Y-315433D01*
X667942Y-315400D01*
X667902Y-315364D01*
X667848Y-315327D01*
X667786Y-315295D01*
X667717Y-315269D01*
X667680Y-315265D01*
X667640Y-315262D01*
D02*
G37*
G36*
X685886Y-317153D02*
X685136D01*
X685092Y-317157D01*
X685041Y-317160D01*
X684983Y-317164D01*
X684925Y-317171D01*
X684866Y-317182D01*
X684816Y-317197D01*
X684808Y-317200D01*
X684794Y-317208D01*
X684772Y-317218D01*
X684743Y-317233D01*
X684710Y-317255D01*
X684677Y-317280D01*
X684644Y-317313D01*
X684619Y-317350D01*
X684615Y-317353D01*
X684608Y-317368D01*
X684597Y-317390D01*
X684583Y-317419D01*
X684572Y-317452D01*
X684561Y-317488D01*
X684553Y-317532D01*
X684550Y-317575D01*
Y-317579D01*
Y-317583D01*
X684553Y-317604D01*
X684557Y-317637D01*
X684564Y-317681D01*
X684583Y-317724D01*
X684604Y-317776D01*
X684637Y-317823D01*
X684681Y-317870D01*
X684688Y-317874D01*
X684706Y-317888D01*
X684735Y-317906D01*
X684783Y-317928D01*
X684837Y-317950D01*
X684910Y-317968D01*
X684994Y-317983D01*
X685092Y-317987D01*
X685886D01*
Y-317153D01*
D02*
G37*
G36*
X693067Y-86181D02*
X691939D01*
X693067Y-86974D01*
Y-86181D01*
D02*
G37*
G36*
X685002Y-47453D02*
X684889D01*
X684886D01*
X684882D01*
X684864D01*
X684831D01*
X684787Y-47457D01*
X684740D01*
X684682Y-47460D01*
X684620Y-47464D01*
X684551Y-47471D01*
X684412Y-47489D01*
X684343Y-47500D01*
X684278Y-47515D01*
X684216Y-47529D01*
X684158Y-47551D01*
X684107Y-47573D01*
X684063Y-47599D01*
X684059D01*
X684056Y-47606D01*
X684045Y-47613D01*
X684030Y-47624D01*
X683997Y-47657D01*
X683957Y-47697D01*
X683921Y-47752D01*
X683888Y-47813D01*
X683874Y-47846D01*
X683863Y-47883D01*
X683859Y-47923D01*
X683855Y-47963D01*
Y-47984D01*
X683859Y-47999D01*
X683866Y-48039D01*
X683877Y-48086D01*
X683899Y-48141D01*
X683932Y-48199D01*
X683954Y-48228D01*
X683976Y-48257D01*
X684005Y-48283D01*
X684037Y-48308D01*
X684041D01*
X684048Y-48316D01*
X684063Y-48323D01*
X684081Y-48334D01*
X684110Y-48345D01*
X684143Y-48359D01*
X684183Y-48370D01*
X684230Y-48385D01*
X684285Y-48399D01*
X684347Y-48414D01*
X684416Y-48428D01*
X684492Y-48439D01*
X684580Y-48450D01*
X684675Y-48458D01*
X684776Y-48461D01*
X684889Y-48465D01*
X684897D01*
X684915D01*
X684947D01*
X684991Y-48461D01*
X685039D01*
X685097Y-48458D01*
X685159Y-48454D01*
X685224Y-48447D01*
X685366Y-48428D01*
X685435Y-48418D01*
X685501Y-48403D01*
X685563Y-48388D01*
X685621Y-48367D01*
X685672Y-48345D01*
X685715Y-48319D01*
X685719D01*
X685723Y-48312D01*
X685748Y-48294D01*
X685781Y-48261D01*
X685817Y-48221D01*
X685854Y-48166D01*
X685887Y-48105D01*
X685912Y-48035D01*
X685916Y-47999D01*
X685919Y-47959D01*
Y-47937D01*
X685916Y-47923D01*
X685909Y-47886D01*
X685894Y-47835D01*
X685868Y-47781D01*
X685832Y-47719D01*
X685810Y-47690D01*
X685781Y-47660D01*
X685752Y-47631D01*
X685715Y-47602D01*
X685712D01*
X685705Y-47595D01*
X685694Y-47588D01*
X685675Y-47580D01*
X685650Y-47566D01*
X685617Y-47555D01*
X685581Y-47540D01*
X685537Y-47526D01*
X685483Y-47515D01*
X685424Y-47500D01*
X685355Y-47486D01*
X685282Y-47475D01*
X685195Y-47468D01*
X685104Y-47460D01*
X685002Y-47453D01*
D02*
G37*
G36*
X674661Y-106394D02*
X673904D01*
Y-107013D01*
X673908Y-107060D01*
X673911Y-107111D01*
X673915Y-107162D01*
X673922Y-107213D01*
X673930Y-107253D01*
X673933Y-107260D01*
X673937Y-107275D01*
X673948Y-107297D01*
X673962Y-107326D01*
X673977Y-107355D01*
X673999Y-107388D01*
X674028Y-107420D01*
X674057Y-107446D01*
X674061Y-107450D01*
X674072Y-107457D01*
X674093Y-107468D01*
X674119Y-107479D01*
X674148Y-107490D01*
X674185Y-107501D01*
X674228Y-107508D01*
X674275Y-107511D01*
X674283D01*
X674297D01*
X674319Y-107508D01*
X674348Y-107504D01*
X674385Y-107497D01*
X674421Y-107486D01*
X674457Y-107471D01*
X674494Y-107450D01*
X674498Y-107446D01*
X674508Y-107439D01*
X674527Y-107424D01*
X674545Y-107406D01*
X674567Y-107380D01*
X674588Y-107351D01*
X674610Y-107315D01*
X674625Y-107275D01*
Y-107271D01*
X674632Y-107253D01*
X674636Y-107228D01*
X674643Y-107187D01*
X674650Y-107133D01*
X674654Y-107071D01*
X674661Y-106991D01*
Y-106394D01*
D02*
G37*
G36*
X673606D02*
X672739D01*
Y-107111D01*
X672743Y-107187D01*
X672747Y-107220D01*
X672750Y-107249D01*
Y-107253D01*
X672754Y-107268D01*
X672758Y-107289D01*
X672765Y-107315D01*
X672787Y-107377D01*
X672816Y-107439D01*
X672819Y-107442D01*
X672827Y-107453D01*
X672838Y-107468D01*
X672852Y-107486D01*
X672874Y-107504D01*
X672896Y-107530D01*
X672925Y-107548D01*
X672958Y-107570D01*
X672961Y-107573D01*
X672972Y-107577D01*
X672994Y-107584D01*
X673020Y-107595D01*
X673049Y-107606D01*
X673085Y-107613D01*
X673129Y-107617D01*
X673173Y-107621D01*
X673180D01*
X673194D01*
X673223Y-107617D01*
X673256Y-107610D01*
X673293Y-107602D01*
X673333Y-107588D01*
X673373Y-107570D01*
X673413Y-107544D01*
X673416Y-107541D01*
X673431Y-107530D01*
X673449Y-107515D01*
X673471Y-107493D01*
X673496Y-107464D01*
X673522Y-107428D01*
X673544Y-107388D01*
X673562Y-107340D01*
X673566Y-107333D01*
X673569Y-107318D01*
X673577Y-107286D01*
X673584Y-107246D01*
X673591Y-107195D01*
X673598Y-107133D01*
X673606Y-107056D01*
Y-106394D01*
D02*
G37*
G36*
X660843Y-111061D02*
X660821D01*
X660806Y-111065D01*
X660766Y-111068D01*
X660719Y-111079D01*
X660661Y-111097D01*
X660602Y-111123D01*
X660544Y-111159D01*
X660490Y-111210D01*
X660482Y-111217D01*
X660468Y-111239D01*
X660446Y-111272D01*
X660417Y-111319D01*
X660391Y-111378D01*
X660369Y-111447D01*
X660355Y-111530D01*
X660348Y-111625D01*
Y-111629D01*
Y-111636D01*
Y-111651D01*
X660351Y-111669D01*
Y-111694D01*
X660355Y-111720D01*
X660366Y-111778D01*
X660380Y-111847D01*
X660406Y-111920D01*
X660442Y-111989D01*
X660490Y-112051D01*
Y-112055D01*
X660497Y-112058D01*
X660515Y-112076D01*
X660544Y-112102D01*
X660584Y-112131D01*
X660635Y-112156D01*
X660693Y-112182D01*
X660759Y-112200D01*
X660795Y-112207D01*
X660853D01*
X660868Y-112204D01*
X660908Y-112200D01*
X660955Y-112186D01*
X661014Y-112167D01*
X661076Y-112135D01*
X661137Y-112095D01*
X661167Y-112065D01*
X661196Y-112036D01*
Y-112033D01*
X661203Y-112029D01*
X661210Y-112018D01*
X661218Y-112007D01*
X661243Y-111971D01*
X661269Y-111920D01*
X661298Y-111858D01*
X661323Y-111782D01*
X661338Y-111694D01*
X661345Y-111600D01*
Y-111596D01*
Y-111589D01*
Y-111578D01*
X661341Y-111560D01*
Y-111538D01*
X661338Y-111516D01*
X661327Y-111461D01*
X661309Y-111399D01*
X661287Y-111334D01*
X661250Y-111268D01*
X661203Y-111210D01*
X661196Y-111203D01*
X661177Y-111188D01*
X661145Y-111163D01*
X661105Y-111137D01*
X661050Y-111108D01*
X660988Y-111083D01*
X660919Y-111068D01*
X660843Y-111061D01*
D02*
G37*
G36*
X658881Y-110144D02*
X658859D01*
X658844Y-110147D01*
X658808Y-110154D01*
X658757Y-110169D01*
X658702Y-110195D01*
X658640Y-110231D01*
X658611Y-110253D01*
X658582Y-110282D01*
X658553Y-110311D01*
X658524Y-110347D01*
Y-110351D01*
X658517Y-110358D01*
X658509Y-110369D01*
X658502Y-110388D01*
X658488Y-110413D01*
X658477Y-110446D01*
X658462Y-110482D01*
X658448Y-110526D01*
X658437Y-110580D01*
X658422Y-110639D01*
X658407Y-110708D01*
X658397Y-110781D01*
X658389Y-110868D01*
X658382Y-110959D01*
X658375Y-111061D01*
Y-111174D01*
Y-111177D01*
Y-111181D01*
Y-111199D01*
Y-111232D01*
X658378Y-111276D01*
Y-111323D01*
X658382Y-111381D01*
X658386Y-111443D01*
X658393Y-111512D01*
X658411Y-111651D01*
X658422Y-111720D01*
X658437Y-111785D01*
X658451Y-111847D01*
X658473Y-111905D01*
X658495Y-111956D01*
X658520Y-112000D01*
Y-112004D01*
X658528Y-112007D01*
X658535Y-112018D01*
X658546Y-112033D01*
X658578Y-112065D01*
X658619Y-112106D01*
X658673Y-112142D01*
X658735Y-112175D01*
X658768Y-112189D01*
X658804Y-112200D01*
X658844Y-112204D01*
X658884Y-112207D01*
X658906D01*
X658921Y-112204D01*
X658961Y-112197D01*
X659008Y-112186D01*
X659063Y-112164D01*
X659121Y-112131D01*
X659150Y-112109D01*
X659179Y-112087D01*
X659205Y-112058D01*
X659230Y-112025D01*
Y-112022D01*
X659237Y-112015D01*
X659245Y-112000D01*
X659256Y-111982D01*
X659267Y-111953D01*
X659281Y-111920D01*
X659292Y-111880D01*
X659306Y-111833D01*
X659321Y-111778D01*
X659336Y-111716D01*
X659350Y-111647D01*
X659361Y-111571D01*
X659372Y-111483D01*
X659379Y-111389D01*
X659383Y-111287D01*
X659387Y-111174D01*
Y-111166D01*
Y-111148D01*
Y-111116D01*
X659383Y-111072D01*
Y-111024D01*
X659379Y-110966D01*
X659376Y-110904D01*
X659368Y-110839D01*
X659350Y-110697D01*
X659339Y-110628D01*
X659325Y-110562D01*
X659310Y-110500D01*
X659288Y-110442D01*
X659267Y-110391D01*
X659241Y-110347D01*
Y-110344D01*
X659234Y-110340D01*
X659215Y-110315D01*
X659183Y-110282D01*
X659143Y-110246D01*
X659088Y-110209D01*
X659026Y-110176D01*
X658957Y-110151D01*
X658921Y-110147D01*
X658881Y-110144D01*
D02*
G37*
G36*
X699037Y-63823D02*
X698979D01*
X698964Y-63827D01*
X698924Y-63830D01*
X698877Y-63845D01*
X698819Y-63863D01*
X698757Y-63896D01*
X698695Y-63936D01*
X698666Y-63965D01*
X698637Y-63994D01*
Y-63998D01*
X698629Y-64002D01*
X698622Y-64012D01*
X698615Y-64023D01*
X698589Y-64060D01*
X698564Y-64111D01*
X698535Y-64173D01*
X698509Y-64249D01*
X698495Y-64336D01*
X698487Y-64431D01*
Y-64435D01*
Y-64442D01*
Y-64453D01*
X698491Y-64471D01*
Y-64493D01*
X698495Y-64515D01*
X698505Y-64569D01*
X698524Y-64631D01*
X698546Y-64697D01*
X698582Y-64762D01*
X698629Y-64820D01*
X698637Y-64828D01*
X698655Y-64842D01*
X698688Y-64868D01*
X698728Y-64893D01*
X698782Y-64922D01*
X698844Y-64948D01*
X698913Y-64962D01*
X698990Y-64970D01*
X699012D01*
X699026Y-64966D01*
X699066Y-64962D01*
X699113Y-64951D01*
X699172Y-64933D01*
X699230Y-64908D01*
X699288Y-64871D01*
X699343Y-64820D01*
X699350Y-64813D01*
X699365Y-64791D01*
X699386Y-64759D01*
X699415Y-64711D01*
X699441Y-64653D01*
X699463Y-64584D01*
X699477Y-64500D01*
X699485Y-64406D01*
Y-64402D01*
Y-64395D01*
Y-64380D01*
X699481Y-64362D01*
Y-64336D01*
X699477Y-64311D01*
X699467Y-64253D01*
X699452Y-64183D01*
X699427Y-64111D01*
X699390Y-64042D01*
X699343Y-63980D01*
Y-63976D01*
X699335Y-63972D01*
X699317Y-63954D01*
X699288Y-63929D01*
X699248Y-63899D01*
X699197Y-63874D01*
X699139Y-63849D01*
X699073Y-63830D01*
X699037Y-63823D01*
D02*
G37*
G36*
X697039D02*
X697010D01*
X696977Y-63830D01*
X696933Y-63838D01*
X696886Y-63852D01*
X696835Y-63870D01*
X696788Y-63899D01*
X696740Y-63940D01*
X696736Y-63943D01*
X696722Y-63958D01*
X696704Y-63983D01*
X696686Y-64016D01*
X696664Y-64056D01*
X696645Y-64103D01*
X696631Y-64154D01*
X696627Y-64213D01*
Y-64216D01*
Y-64220D01*
X696631Y-64242D01*
X696635Y-64275D01*
X696642Y-64315D01*
X696656Y-64362D01*
X696675Y-64409D01*
X696704Y-64460D01*
X696740Y-64504D01*
X696744Y-64507D01*
X696762Y-64522D01*
X696788Y-64540D01*
X696820Y-64558D01*
X696864Y-64580D01*
X696915Y-64598D01*
X696973Y-64613D01*
X697039Y-64617D01*
X697046D01*
X697068Y-64613D01*
X697100Y-64609D01*
X697144Y-64602D01*
X697191Y-64587D01*
X697239Y-64569D01*
X697290Y-64540D01*
X697333Y-64504D01*
X697337Y-64500D01*
X697352Y-64482D01*
X697370Y-64460D01*
X697392Y-64427D01*
X697413Y-64387D01*
X697432Y-64340D01*
X697446Y-64285D01*
X697450Y-64227D01*
Y-64223D01*
Y-64220D01*
Y-64198D01*
X697443Y-64165D01*
X697435Y-64125D01*
X697421Y-64082D01*
X697399Y-64034D01*
X697370Y-63987D01*
X697330Y-63940D01*
X697326Y-63936D01*
X697308Y-63921D01*
X697283Y-63903D01*
X697250Y-63881D01*
X697206Y-63859D01*
X697159Y-63841D01*
X697100Y-63827D01*
X697039Y-63823D01*
D02*
G37*
G36*
X697028Y-64868D02*
X697006D01*
X696991Y-64871D01*
X696951Y-64875D01*
X696900Y-64886D01*
X696842Y-64904D01*
X696784Y-64930D01*
X696722Y-64966D01*
X696667Y-65013D01*
X696660Y-65021D01*
X696645Y-65039D01*
X696624Y-65072D01*
X696598Y-65112D01*
X696569Y-65166D01*
X696547Y-65228D01*
X696533Y-65297D01*
X696525Y-65374D01*
Y-65381D01*
Y-65396D01*
X696529Y-65421D01*
X696533Y-65454D01*
X696540Y-65494D01*
X696551Y-65538D01*
X696565Y-65581D01*
X696584Y-65628D01*
X696587Y-65632D01*
X696594Y-65650D01*
X696609Y-65672D01*
X696631Y-65698D01*
X696656Y-65731D01*
X696689Y-65763D01*
X696726Y-65792D01*
X696769Y-65821D01*
X696776Y-65825D01*
X696791Y-65832D01*
X696817Y-65843D01*
X696849Y-65854D01*
X696889Y-65865D01*
X696937Y-65876D01*
X696988Y-65883D01*
X697039Y-65887D01*
X697060D01*
X697075Y-65883D01*
X697119Y-65880D01*
X697170Y-65869D01*
X697228Y-65851D01*
X697290Y-65829D01*
X697348Y-65792D01*
X697406Y-65745D01*
X697413Y-65738D01*
X697428Y-65719D01*
X697454Y-65687D01*
X697479Y-65647D01*
X697505Y-65596D01*
X697530Y-65534D01*
X697545Y-65461D01*
X697552Y-65385D01*
Y-65381D01*
Y-65374D01*
Y-65363D01*
X697548Y-65348D01*
X697545Y-65308D01*
X697534Y-65254D01*
X697515Y-65199D01*
X697490Y-65137D01*
X697454Y-65075D01*
X697403Y-65017D01*
X697395Y-65010D01*
X697377Y-64995D01*
X697344Y-64970D01*
X697301Y-64941D01*
X697246Y-64915D01*
X697181Y-64890D01*
X697108Y-64875D01*
X697028Y-64868D01*
D02*
G37*
G36*
X664360Y-94743D02*
X664342D01*
X664327Y-94747D01*
X664291Y-94750D01*
X664243Y-94761D01*
X664192Y-94783D01*
X664134Y-94809D01*
X664076Y-94849D01*
X664047Y-94870D01*
X664021Y-94899D01*
Y-94903D01*
X664014Y-94907D01*
X663999Y-94929D01*
X663978Y-94965D01*
X663948Y-95012D01*
X663923Y-95074D01*
X663901Y-95147D01*
X663887Y-95231D01*
X663879Y-95329D01*
Y-95333D01*
Y-95340D01*
Y-95354D01*
X663883Y-95373D01*
Y-95394D01*
X663887Y-95420D01*
X663898Y-95478D01*
X663912Y-95544D01*
X663938Y-95613D01*
X663974Y-95678D01*
X664021Y-95740D01*
X664029Y-95748D01*
X664047Y-95766D01*
X664076Y-95788D01*
X664116Y-95817D01*
X664167Y-95846D01*
X664225Y-95868D01*
X664294Y-95886D01*
X664371Y-95893D01*
X664393D01*
X664407Y-95890D01*
X664443Y-95886D01*
X664494Y-95875D01*
X664549Y-95857D01*
X664611Y-95828D01*
X664669Y-95791D01*
X664727Y-95740D01*
X664735Y-95733D01*
X664749Y-95715D01*
X664775Y-95682D01*
X664800Y-95635D01*
X664826Y-95580D01*
X664851Y-95511D01*
X664866Y-95434D01*
X664873Y-95347D01*
Y-95340D01*
Y-95322D01*
X664869Y-95289D01*
X664866Y-95249D01*
X664858Y-95202D01*
X664844Y-95151D01*
X664829Y-95096D01*
X664808Y-95041D01*
X664804Y-95034D01*
X664793Y-95016D01*
X664778Y-94990D01*
X664756Y-94958D01*
X664731Y-94925D01*
X664698Y-94885D01*
X664662Y-94852D01*
X664618Y-94819D01*
X664611Y-94816D01*
X664596Y-94809D01*
X664571Y-94794D01*
X664538Y-94783D01*
X664502Y-94768D01*
X664458Y-94754D01*
X664411Y-94747D01*
X664360Y-94743D01*
D02*
G37*
G36*
X666347D02*
X666325D01*
X666311Y-94747D01*
X666267Y-94750D01*
X666216Y-94761D01*
X666158Y-94779D01*
X666096Y-94801D01*
X666038Y-94838D01*
X665980Y-94885D01*
X665972Y-94892D01*
X665958Y-94910D01*
X665932Y-94943D01*
X665907Y-94983D01*
X665881Y-95034D01*
X665856Y-95096D01*
X665841Y-95169D01*
X665834Y-95245D01*
Y-95249D01*
Y-95256D01*
Y-95267D01*
X665838Y-95282D01*
X665841Y-95322D01*
X665852Y-95376D01*
X665870Y-95431D01*
X665896Y-95493D01*
X665932Y-95555D01*
X665983Y-95613D01*
X665990Y-95620D01*
X666009Y-95635D01*
X666041Y-95660D01*
X666085Y-95689D01*
X666140Y-95715D01*
X666205Y-95740D01*
X666278Y-95755D01*
X666358Y-95762D01*
X666380D01*
X666395Y-95758D01*
X666435Y-95755D01*
X666486Y-95744D01*
X666544Y-95726D01*
X666602Y-95700D01*
X666664Y-95664D01*
X666718Y-95617D01*
X666726Y-95609D01*
X666740Y-95591D01*
X666762Y-95558D01*
X666788Y-95518D01*
X666817Y-95464D01*
X666839Y-95402D01*
X666853Y-95333D01*
X666860Y-95256D01*
Y-95249D01*
Y-95234D01*
X666857Y-95209D01*
X666853Y-95176D01*
X666846Y-95136D01*
X666835Y-95092D01*
X666820Y-95049D01*
X666802Y-95001D01*
X666799Y-94998D01*
X666791Y-94980D01*
X666777Y-94958D01*
X666755Y-94932D01*
X666729Y-94899D01*
X666697Y-94867D01*
X666660Y-94838D01*
X666617Y-94809D01*
X666609Y-94805D01*
X666595Y-94797D01*
X666569Y-94787D01*
X666537Y-94776D01*
X666497Y-94765D01*
X666449Y-94754D01*
X666398Y-94747D01*
X666347Y-94743D01*
D02*
G37*
G36*
Y-96013D02*
X666340D01*
X666318Y-96017D01*
X666285Y-96021D01*
X666242Y-96028D01*
X666194Y-96042D01*
X666147Y-96061D01*
X666096Y-96090D01*
X666052Y-96126D01*
X666049Y-96130D01*
X666034Y-96148D01*
X666016Y-96170D01*
X665994Y-96203D01*
X665972Y-96243D01*
X665954Y-96290D01*
X665940Y-96345D01*
X665936Y-96403D01*
Y-96406D01*
Y-96410D01*
Y-96432D01*
X665943Y-96465D01*
X665950Y-96505D01*
X665965Y-96548D01*
X665987Y-96596D01*
X666016Y-96643D01*
X666056Y-96690D01*
X666060Y-96694D01*
X666078Y-96709D01*
X666103Y-96727D01*
X666136Y-96749D01*
X666180Y-96770D01*
X666227Y-96789D01*
X666285Y-96803D01*
X666347Y-96807D01*
X666376D01*
X666409Y-96799D01*
X666453Y-96792D01*
X666500Y-96778D01*
X666551Y-96759D01*
X666598Y-96730D01*
X666646Y-96690D01*
X666649Y-96687D01*
X666664Y-96672D01*
X666682Y-96647D01*
X666700Y-96614D01*
X666722Y-96574D01*
X666740Y-96526D01*
X666755Y-96476D01*
X666758Y-96417D01*
Y-96414D01*
Y-96410D01*
X666755Y-96388D01*
X666751Y-96355D01*
X666744Y-96315D01*
X666729Y-96268D01*
X666711Y-96221D01*
X666682Y-96170D01*
X666646Y-96126D01*
X666642Y-96122D01*
X666624Y-96108D01*
X666598Y-96090D01*
X666566Y-96071D01*
X666522Y-96050D01*
X666471Y-96031D01*
X666413Y-96017D01*
X666347Y-96013D01*
D02*
G37*
G36*
X677791Y-28064D02*
X677788D01*
X677780D01*
X677766D01*
X677748Y-28068D01*
X677722D01*
X677697Y-28071D01*
X677638Y-28082D01*
X677569Y-28097D01*
X677496Y-28122D01*
X677427Y-28159D01*
X677365Y-28206D01*
X677362D01*
X677358Y-28213D01*
X677340Y-28232D01*
X677315Y-28261D01*
X677285Y-28301D01*
X677260Y-28352D01*
X677234Y-28410D01*
X677216Y-28475D01*
X677209Y-28512D01*
Y-28570D01*
X677213Y-28585D01*
X677216Y-28625D01*
X677231Y-28672D01*
X677249Y-28730D01*
X677282Y-28792D01*
X677322Y-28854D01*
X677351Y-28883D01*
X677380Y-28912D01*
X677384D01*
X677387Y-28920D01*
X677398Y-28927D01*
X677409Y-28934D01*
X677446Y-28960D01*
X677496Y-28985D01*
X677558Y-29014D01*
X677635Y-29040D01*
X677722Y-29054D01*
X677817Y-29061D01*
X677820D01*
X677828D01*
X677839D01*
X677857Y-29058D01*
X677879D01*
X677901Y-29054D01*
X677955Y-29043D01*
X678017Y-29025D01*
X678083Y-29003D01*
X678148Y-28967D01*
X678206Y-28920D01*
X678214Y-28912D01*
X678228Y-28894D01*
X678254Y-28861D01*
X678279Y-28821D01*
X678308Y-28767D01*
X678334Y-28705D01*
X678348Y-28636D01*
X678356Y-28559D01*
Y-28537D01*
X678352Y-28523D01*
X678348Y-28483D01*
X678337Y-28435D01*
X678319Y-28377D01*
X678294Y-28319D01*
X678257Y-28261D01*
X678206Y-28206D01*
X678199Y-28199D01*
X678177Y-28184D01*
X678144Y-28162D01*
X678097Y-28133D01*
X678039Y-28108D01*
X677970Y-28086D01*
X677886Y-28071D01*
X677791Y-28064D01*
D02*
G37*
G36*
X692358Y-34105D02*
X692355D01*
X692347D01*
X692333D01*
X692315Y-34109D01*
X692289D01*
X692264Y-34113D01*
X692205Y-34124D01*
X692136Y-34138D01*
X692063Y-34164D01*
X691994Y-34200D01*
X691932Y-34247D01*
X691929D01*
X691925Y-34255D01*
X691907Y-34273D01*
X691881Y-34302D01*
X691852Y-34342D01*
X691827Y-34393D01*
X691801Y-34451D01*
X691783Y-34517D01*
X691776Y-34553D01*
Y-34611D01*
X691780Y-34626D01*
X691783Y-34666D01*
X691798Y-34713D01*
X691816Y-34771D01*
X691849Y-34833D01*
X691889Y-34895D01*
X691918Y-34924D01*
X691947Y-34953D01*
X691951D01*
X691954Y-34961D01*
X691965Y-34968D01*
X691976Y-34975D01*
X692012Y-35001D01*
X692063Y-35026D01*
X692125Y-35055D01*
X692202Y-35081D01*
X692289Y-35095D01*
X692384Y-35103D01*
X692387D01*
X692395D01*
X692406D01*
X692424Y-35099D01*
X692446D01*
X692467Y-35095D01*
X692522Y-35085D01*
X692584Y-35066D01*
X692649Y-35045D01*
X692715Y-35008D01*
X692773Y-34961D01*
X692780Y-34953D01*
X692795Y-34935D01*
X692821Y-34903D01*
X692846Y-34863D01*
X692875Y-34808D01*
X692901Y-34746D01*
X692915Y-34677D01*
X692922Y-34600D01*
Y-34579D01*
X692919Y-34564D01*
X692915Y-34524D01*
X692904Y-34477D01*
X692886Y-34418D01*
X692861Y-34360D01*
X692824Y-34302D01*
X692773Y-34247D01*
X692766Y-34240D01*
X692744Y-34225D01*
X692711Y-34204D01*
X692664Y-34174D01*
X692606Y-34149D01*
X692537Y-34127D01*
X692453Y-34113D01*
X692358Y-34105D01*
D02*
G37*
G36*
X630937Y-90988D02*
X630879D01*
X630864Y-90992D01*
X630824Y-90996D01*
X630777Y-91010D01*
X630719Y-91028D01*
X630657Y-91061D01*
X630595Y-91101D01*
X630566Y-91130D01*
X630537Y-91159D01*
Y-91163D01*
X630529Y-91167D01*
X630522Y-91178D01*
X630515Y-91189D01*
X630489Y-91225D01*
X630464Y-91276D01*
X630435Y-91338D01*
X630409Y-91414D01*
X630395Y-91502D01*
X630387Y-91596D01*
Y-91600D01*
Y-91607D01*
Y-91618D01*
X630391Y-91636D01*
Y-91658D01*
X630395Y-91680D01*
X630406Y-91735D01*
X630424Y-91796D01*
X630445Y-91862D01*
X630482Y-91928D01*
X630529Y-91986D01*
X630537Y-91993D01*
X630555Y-92008D01*
X630587Y-92033D01*
X630627Y-92059D01*
X630682Y-92088D01*
X630744Y-92113D01*
X630813Y-92128D01*
X630890Y-92135D01*
X630911D01*
X630926Y-92131D01*
X630966Y-92128D01*
X631013Y-92117D01*
X631072Y-92099D01*
X631130Y-92073D01*
X631188Y-92037D01*
X631243Y-91986D01*
X631250Y-91979D01*
X631264Y-91957D01*
X631286Y-91924D01*
X631316Y-91877D01*
X631341Y-91818D01*
X631363Y-91749D01*
X631377Y-91666D01*
X631385Y-91571D01*
Y-91567D01*
Y-91560D01*
Y-91545D01*
X631381Y-91527D01*
Y-91502D01*
X631377Y-91476D01*
X631366Y-91418D01*
X631352Y-91349D01*
X631326Y-91276D01*
X631290Y-91207D01*
X631243Y-91145D01*
Y-91141D01*
X631235Y-91138D01*
X631217Y-91119D01*
X631188Y-91094D01*
X631148Y-91065D01*
X631097Y-91039D01*
X631039Y-91014D01*
X630973Y-90996D01*
X630937Y-90988D01*
D02*
G37*
G36*
X633019Y-91247D02*
X632226Y-92375D01*
X633019D01*
Y-91247D01*
D02*
G37*
G36*
X595508Y-88300D02*
X595504D01*
X595497D01*
X595482D01*
X595464Y-88304D01*
X595439D01*
X595413Y-88308D01*
X595355Y-88319D01*
X595286Y-88333D01*
X595213Y-88359D01*
X595144Y-88395D01*
X595082Y-88442D01*
X595078D01*
X595075Y-88450D01*
X595056Y-88468D01*
X595031Y-88497D01*
X595002Y-88537D01*
X594976Y-88588D01*
X594951Y-88646D01*
X594933Y-88712D01*
X594925Y-88748D01*
Y-88806D01*
X594929Y-88821D01*
X594933Y-88861D01*
X594947Y-88908D01*
X594966Y-88967D01*
X594998Y-89028D01*
X595038Y-89090D01*
X595067Y-89119D01*
X595096Y-89148D01*
X595100D01*
X595104Y-89156D01*
X595115Y-89163D01*
X595126Y-89170D01*
X595162Y-89196D01*
X595213Y-89221D01*
X595275Y-89250D01*
X595351Y-89276D01*
X595439Y-89290D01*
X595533Y-89298D01*
X595537D01*
X595544D01*
X595555D01*
X595573Y-89294D01*
X595595D01*
X595617Y-89290D01*
X595672Y-89280D01*
X595733Y-89261D01*
X595799Y-89240D01*
X595865Y-89203D01*
X595923Y-89156D01*
X595930Y-89148D01*
X595945Y-89130D01*
X595970Y-89098D01*
X595996Y-89057D01*
X596025Y-89003D01*
X596050Y-88941D01*
X596065Y-88872D01*
X596072Y-88795D01*
Y-88774D01*
X596068Y-88759D01*
X596065Y-88719D01*
X596054Y-88672D01*
X596036Y-88613D01*
X596010Y-88555D01*
X595974Y-88497D01*
X595923Y-88442D01*
X595916Y-88435D01*
X595894Y-88420D01*
X595861Y-88399D01*
X595814Y-88370D01*
X595755Y-88344D01*
X595686Y-88322D01*
X595603Y-88308D01*
X595508Y-88300D01*
D02*
G37*
G36*
X411366Y-130256D02*
X409444D01*
Y-130853D01*
X409447Y-130879D01*
X409451Y-130933D01*
X409454Y-130995D01*
X409462Y-131061D01*
X409473Y-131126D01*
X409487Y-131181D01*
X409491Y-131188D01*
X409494Y-131206D01*
X409506Y-131232D01*
X409520Y-131264D01*
X409542Y-131301D01*
X409564Y-131337D01*
X409589Y-131374D01*
X409618Y-131410D01*
X409626Y-131414D01*
X409640Y-131428D01*
X409666Y-131450D01*
X409702Y-131475D01*
X409749Y-131505D01*
X409804Y-131537D01*
X409866Y-131567D01*
X409935Y-131592D01*
X409939D01*
X409946Y-131596D01*
X409957Y-131599D01*
X409971Y-131603D01*
X409990Y-131607D01*
X410015Y-131614D01*
X410041Y-131621D01*
X410070Y-131628D01*
X410143Y-131639D01*
X410226Y-131650D01*
X410321Y-131658D01*
X410423Y-131661D01*
X410426D01*
X410441D01*
X410459D01*
X410488Y-131658D01*
X410521D01*
X410557Y-131654D01*
X410601Y-131650D01*
X410645Y-131647D01*
X410743Y-131628D01*
X410845Y-131607D01*
X410940Y-131574D01*
X410987Y-131552D01*
X411027Y-131530D01*
X411031D01*
X411038Y-131523D01*
X411049Y-131516D01*
X411063Y-131508D01*
X411100Y-131479D01*
X411143Y-131443D01*
X411191Y-131395D01*
X411238Y-131341D01*
X411278Y-131279D01*
X411311Y-131213D01*
X411314Y-131206D01*
X411318Y-131188D01*
X411329Y-131155D01*
X411340Y-131108D01*
X411347Y-131050D01*
X411358Y-130977D01*
X411362Y-130933D01*
Y-130886D01*
X411366Y-130839D01*
Y-130256D01*
D02*
G37*
G36*
X438094Y-129862D02*
X436171D01*
Y-130459D01*
X436175Y-130485D01*
X436179Y-130540D01*
X436182Y-130601D01*
X436190Y-130667D01*
X436201Y-130732D01*
X436215Y-130787D01*
X436219Y-130794D01*
X436223Y-130813D01*
X436233Y-130838D01*
X436248Y-130871D01*
X436270Y-130907D01*
X436292Y-130944D01*
X436317Y-130980D01*
X436346Y-131016D01*
X436353Y-131020D01*
X436368Y-131035D01*
X436394Y-131056D01*
X436430Y-131082D01*
X436477Y-131111D01*
X436532Y-131144D01*
X436594Y-131173D01*
X436663Y-131198D01*
X436667D01*
X436674Y-131202D01*
X436685Y-131206D01*
X436699Y-131209D01*
X436718Y-131213D01*
X436743Y-131220D01*
X436768Y-131227D01*
X436798Y-131235D01*
X436870Y-131246D01*
X436954Y-131257D01*
X437049Y-131264D01*
X437151Y-131267D01*
X437154D01*
X437169D01*
X437187D01*
X437216Y-131264D01*
X437249D01*
X437285Y-131260D01*
X437329Y-131257D01*
X437373Y-131253D01*
X437471Y-131235D01*
X437573Y-131213D01*
X437668Y-131180D01*
X437715Y-131158D01*
X437755Y-131136D01*
X437759D01*
X437766Y-131129D01*
X437777Y-131122D01*
X437791Y-131115D01*
X437828Y-131086D01*
X437871Y-131049D01*
X437919Y-131002D01*
X437966Y-130947D01*
X438006Y-130885D01*
X438039Y-130820D01*
X438042Y-130813D01*
X438046Y-130794D01*
X438057Y-130762D01*
X438068Y-130714D01*
X438075Y-130656D01*
X438086Y-130583D01*
X438090Y-130540D01*
Y-130492D01*
X438094Y-130445D01*
Y-129862D01*
D02*
G37*
G36*
X436761Y-134096D02*
Y-134889D01*
X437890D01*
X436761Y-134096D01*
D02*
G37*
G36*
X249553Y-104824D02*
X249549D01*
X249542D01*
X249527D01*
X249509Y-104828D01*
X249487D01*
X249462Y-104831D01*
X249404Y-104842D01*
X249338Y-104857D01*
X249269Y-104882D01*
X249203Y-104919D01*
X249142Y-104966D01*
X249134Y-104973D01*
X249116Y-104992D01*
X249094Y-105021D01*
X249065Y-105061D01*
X249036Y-105112D01*
X249014Y-105170D01*
X248996Y-105239D01*
X248989Y-105316D01*
Y-105337D01*
X248992Y-105352D01*
X248996Y-105388D01*
X249007Y-105439D01*
X249025Y-105494D01*
X249054Y-105556D01*
X249091Y-105614D01*
X249142Y-105672D01*
X249149Y-105680D01*
X249167Y-105694D01*
X249200Y-105720D01*
X249247Y-105745D01*
X249302Y-105771D01*
X249371Y-105796D01*
X249447Y-105811D01*
X249535Y-105818D01*
X249542D01*
X249560D01*
X249593Y-105814D01*
X249633Y-105811D01*
X249680Y-105803D01*
X249731Y-105789D01*
X249786Y-105774D01*
X249840Y-105752D01*
X249848Y-105749D01*
X249866Y-105738D01*
X249891Y-105723D01*
X249924Y-105701D01*
X249957Y-105676D01*
X249997Y-105643D01*
X250030Y-105607D01*
X250062Y-105563D01*
X250066Y-105556D01*
X250073Y-105541D01*
X250088Y-105516D01*
X250099Y-105483D01*
X250114Y-105447D01*
X250128Y-105403D01*
X250135Y-105356D01*
X250139Y-105305D01*
Y-105286D01*
X250135Y-105272D01*
X250132Y-105236D01*
X250121Y-105188D01*
X250099Y-105137D01*
X250073Y-105079D01*
X250033Y-105021D01*
X250011Y-104992D01*
X249982Y-104966D01*
X249979D01*
X249975Y-104959D01*
X249953Y-104944D01*
X249917Y-104922D01*
X249870Y-104893D01*
X249808Y-104868D01*
X249735Y-104846D01*
X249651Y-104831D01*
X249553Y-104824D01*
D02*
G37*
G36*
X248657Y-106804D02*
X248654D01*
X248646D01*
X248632D01*
X248614Y-106808D01*
X248588D01*
X248563Y-106812D01*
X248505Y-106823D01*
X248435Y-106837D01*
X248363Y-106863D01*
X248293Y-106899D01*
X248232Y-106946D01*
X248228D01*
X248224Y-106954D01*
X248206Y-106972D01*
X248181Y-107001D01*
X248151Y-107041D01*
X248126Y-107092D01*
X248100Y-107150D01*
X248082Y-107216D01*
X248075Y-107252D01*
Y-107310D01*
X248079Y-107325D01*
X248082Y-107365D01*
X248097Y-107412D01*
X248115Y-107470D01*
X248148Y-107532D01*
X248188Y-107594D01*
X248217Y-107623D01*
X248246Y-107652D01*
X248250D01*
X248253Y-107660D01*
X248264Y-107667D01*
X248275Y-107674D01*
X248312Y-107700D01*
X248363Y-107725D01*
X248425Y-107754D01*
X248501Y-107780D01*
X248588Y-107794D01*
X248683Y-107802D01*
X248687D01*
X248694D01*
X248705D01*
X248723Y-107798D01*
X248745D01*
X248767Y-107794D01*
X248821Y-107783D01*
X248883Y-107765D01*
X248949Y-107743D01*
X249014Y-107707D01*
X249072Y-107660D01*
X249080Y-107652D01*
X249094Y-107634D01*
X249120Y-107601D01*
X249145Y-107561D01*
X249174Y-107507D01*
X249200Y-107445D01*
X249214Y-107376D01*
X249222Y-107299D01*
Y-107278D01*
X249218Y-107263D01*
X249214Y-107223D01*
X249203Y-107176D01*
X249185Y-107117D01*
X249160Y-107059D01*
X249123Y-107001D01*
X249072Y-106946D01*
X249065Y-106939D01*
X249043Y-106924D01*
X249010Y-106903D01*
X248963Y-106874D01*
X248905Y-106848D01*
X248836Y-106826D01*
X248752Y-106812D01*
X248657Y-106804D01*
D02*
G37*
G36*
X412012Y-118122D02*
X411179D01*
Y-118871D01*
X411182Y-118915D01*
X411186Y-118966D01*
X411190Y-119024D01*
X411197Y-119082D01*
X411208Y-119141D01*
X411223Y-119192D01*
X411226Y-119199D01*
X411233Y-119214D01*
X411244Y-119235D01*
X411259Y-119264D01*
X411281Y-119297D01*
X411306Y-119330D01*
X411339Y-119363D01*
X411375Y-119388D01*
X411379Y-119392D01*
X411393Y-119399D01*
X411415Y-119410D01*
X411445Y-119425D01*
X411477Y-119436D01*
X411514Y-119447D01*
X411557Y-119454D01*
X411601Y-119457D01*
X411605D01*
X411608D01*
X411630Y-119454D01*
X411663Y-119450D01*
X411707Y-119443D01*
X411750Y-119425D01*
X411801Y-119403D01*
X411848Y-119370D01*
X411896Y-119326D01*
X411900Y-119319D01*
X411914Y-119301D01*
X411932Y-119272D01*
X411954Y-119225D01*
X411976Y-119170D01*
X411994Y-119097D01*
X412009Y-119013D01*
X412012Y-118915D01*
Y-118122D01*
D02*
G37*
G36*
X411441Y-120513D02*
X411437D01*
X411430D01*
X411419D01*
X411401Y-120517D01*
X411379D01*
X411357Y-120520D01*
X411303Y-120531D01*
X411241Y-120549D01*
X411175Y-120571D01*
X411110Y-120608D01*
X411051Y-120655D01*
X411044Y-120662D01*
X411030Y-120680D01*
X411004Y-120713D01*
X410979Y-120753D01*
X410950Y-120808D01*
X410924Y-120870D01*
X410909Y-120939D01*
X410902Y-121015D01*
Y-121037D01*
X410906Y-121052D01*
X410909Y-121092D01*
X410920Y-121139D01*
X410939Y-121197D01*
X410964Y-121256D01*
X411000Y-121314D01*
X411051Y-121368D01*
X411059Y-121376D01*
X411081Y-121390D01*
X411113Y-121412D01*
X411161Y-121441D01*
X411219Y-121467D01*
X411288Y-121489D01*
X411372Y-121503D01*
X411466Y-121510D01*
X411470D01*
X411477D01*
X411492D01*
X411510Y-121507D01*
X411536D01*
X411561Y-121503D01*
X411619Y-121492D01*
X411688Y-121478D01*
X411761Y-121452D01*
X411830Y-121416D01*
X411892Y-121368D01*
X411896D01*
X411900Y-121361D01*
X411918Y-121343D01*
X411943Y-121314D01*
X411972Y-121274D01*
X411998Y-121223D01*
X412023Y-121165D01*
X412042Y-121099D01*
X412049Y-121063D01*
Y-121004D01*
X412045Y-120990D01*
X412042Y-120950D01*
X412027Y-120903D01*
X412009Y-120844D01*
X411976Y-120782D01*
X411936Y-120721D01*
X411907Y-120691D01*
X411878Y-120662D01*
X411874D01*
X411870Y-120655D01*
X411860Y-120648D01*
X411848Y-120640D01*
X411812Y-120615D01*
X411761Y-120589D01*
X411699Y-120560D01*
X411623Y-120535D01*
X411536Y-120520D01*
X411441Y-120513D01*
D02*
G37*
G36*
X438896Y-119224D02*
X438063D01*
Y-119974D01*
X438066Y-120018D01*
X438070Y-120069D01*
X438074Y-120127D01*
X438081Y-120185D01*
X438092Y-120243D01*
X438106Y-120294D01*
X438110Y-120301D01*
X438118Y-120316D01*
X438128Y-120338D01*
X438143Y-120367D01*
X438165Y-120400D01*
X438190Y-120432D01*
X438223Y-120465D01*
X438259Y-120491D01*
X438263Y-120494D01*
X438278Y-120502D01*
X438299Y-120513D01*
X438329Y-120527D01*
X438361Y-120538D01*
X438398Y-120549D01*
X438441Y-120556D01*
X438485Y-120560D01*
X438489D01*
X438492D01*
X438514Y-120556D01*
X438547Y-120553D01*
X438591Y-120545D01*
X438634Y-120527D01*
X438685Y-120505D01*
X438733Y-120473D01*
X438780Y-120429D01*
X438784Y-120422D01*
X438798Y-120403D01*
X438816Y-120374D01*
X438838Y-120327D01*
X438860Y-120272D01*
X438878Y-120200D01*
X438893Y-120116D01*
X438896Y-120018D01*
Y-119224D01*
D02*
G37*
G36*
X438325Y-121616D02*
X438321D01*
X438314D01*
X438303D01*
X438285Y-121619D01*
X438263D01*
X438241Y-121623D01*
X438187Y-121634D01*
X438125Y-121652D01*
X438059Y-121674D01*
X437994Y-121710D01*
X437935Y-121757D01*
X437928Y-121765D01*
X437914Y-121783D01*
X437888Y-121816D01*
X437863Y-121856D01*
X437833Y-121910D01*
X437808Y-121972D01*
X437793Y-122041D01*
X437786Y-122118D01*
Y-122140D01*
X437790Y-122154D01*
X437793Y-122194D01*
X437804Y-122242D01*
X437823Y-122300D01*
X437848Y-122358D01*
X437885Y-122416D01*
X437935Y-122471D01*
X437943Y-122478D01*
X437965Y-122493D01*
X437997Y-122515D01*
X438045Y-122544D01*
X438103Y-122569D01*
X438172Y-122591D01*
X438256Y-122606D01*
X438350Y-122613D01*
X438354D01*
X438361D01*
X438376D01*
X438394Y-122609D01*
X438420D01*
X438445Y-122606D01*
X438503Y-122595D01*
X438573Y-122580D01*
X438645Y-122555D01*
X438714Y-122518D01*
X438776Y-122471D01*
X438780D01*
X438784Y-122464D01*
X438802Y-122445D01*
X438827Y-122416D01*
X438856Y-122376D01*
X438882Y-122325D01*
X438907Y-122267D01*
X438926Y-122202D01*
X438933Y-122165D01*
Y-122107D01*
X438929Y-122092D01*
X438926Y-122052D01*
X438911Y-122005D01*
X438893Y-121947D01*
X438860Y-121885D01*
X438820Y-121823D01*
X438791Y-121794D01*
X438762Y-121765D01*
X438758D01*
X438754Y-121757D01*
X438743Y-121750D01*
X438733Y-121743D01*
X438696Y-121717D01*
X438645Y-121692D01*
X438583Y-121663D01*
X438507Y-121637D01*
X438420Y-121623D01*
X438325Y-121616D01*
D02*
G37*
G36*
X437546Y-123454D02*
Y-124247D01*
X438674D01*
X437546Y-123454D01*
D02*
G37*
G36*
X660427Y-188131D02*
Y-188925D01*
X661555D01*
X660427Y-188131D01*
D02*
G37*
G36*
X631626Y-231638D02*
X631043D01*
Y-233560D01*
X631640D01*
X631666Y-233556D01*
X631720Y-233553D01*
X631782Y-233549D01*
X631848Y-233542D01*
X631914Y-233531D01*
X631968Y-233516D01*
X631975Y-233512D01*
X631993Y-233509D01*
X632019Y-233498D01*
X632052Y-233483D01*
X632088Y-233462D01*
X632125Y-233440D01*
X632161Y-233414D01*
X632197Y-233385D01*
X632201Y-233378D01*
X632216Y-233363D01*
X632237Y-233338D01*
X632263Y-233301D01*
X632292Y-233254D01*
X632325Y-233200D01*
X632354Y-233138D01*
X632379Y-233068D01*
Y-233065D01*
X632383Y-233057D01*
X632387Y-233047D01*
X632390Y-233032D01*
X632394Y-233014D01*
X632401Y-232988D01*
X632409Y-232963D01*
X632416Y-232934D01*
X632427Y-232861D01*
X632438Y-232777D01*
X632445Y-232683D01*
X632448Y-232581D01*
Y-232577D01*
Y-232562D01*
Y-232544D01*
X632445Y-232515D01*
Y-232482D01*
X632441Y-232446D01*
X632438Y-232402D01*
X632434Y-232359D01*
X632416Y-232260D01*
X632394Y-232158D01*
X632361Y-232064D01*
X632339Y-232016D01*
X632317Y-231976D01*
Y-231973D01*
X632310Y-231965D01*
X632303Y-231955D01*
X632296Y-231940D01*
X632267Y-231904D01*
X632230Y-231860D01*
X632183Y-231813D01*
X632128Y-231765D01*
X632066Y-231725D01*
X632001Y-231693D01*
X631993Y-231689D01*
X631975Y-231685D01*
X631943Y-231674D01*
X631895Y-231663D01*
X631837Y-231656D01*
X631764Y-231645D01*
X631720Y-231642D01*
X631673D01*
X631626Y-231638D01*
D02*
G37*
G36*
X558709Y-222585D02*
X557916D01*
Y-223714D01*
X558709Y-222585D01*
D02*
G37*
G36*
X600923Y-242592D02*
X600920D01*
X600912D01*
X600902D01*
X600883Y-242596D01*
X600862D01*
X600840Y-242599D01*
X600785Y-242610D01*
X600723Y-242628D01*
X600658Y-242650D01*
X600592Y-242687D01*
X600534Y-242734D01*
X600527Y-242741D01*
X600512Y-242759D01*
X600487Y-242792D01*
X600461Y-242832D01*
X600432Y-242887D01*
X600407Y-242949D01*
X600392Y-243018D01*
X600385Y-243094D01*
Y-243116D01*
X600388Y-243131D01*
X600392Y-243171D01*
X600403Y-243218D01*
X600421Y-243276D01*
X600447Y-243335D01*
X600483Y-243393D01*
X600534Y-243447D01*
X600541Y-243455D01*
X600563Y-243469D01*
X600596Y-243491D01*
X600643Y-243520D01*
X600701Y-243546D01*
X600771Y-243567D01*
X600854Y-243582D01*
X600949Y-243589D01*
X600952D01*
X600960D01*
X600974D01*
X600992Y-243586D01*
X601018D01*
X601044Y-243582D01*
X601102Y-243571D01*
X601171Y-243557D01*
X601244Y-243531D01*
X601313Y-243495D01*
X601375Y-243447D01*
X601378D01*
X601382Y-243440D01*
X601400Y-243422D01*
X601426Y-243393D01*
X601455Y-243353D01*
X601480Y-243302D01*
X601506Y-243244D01*
X601524Y-243178D01*
X601531Y-243142D01*
Y-243083D01*
X601528Y-243069D01*
X601524Y-243029D01*
X601509Y-242982D01*
X601491Y-242923D01*
X601458Y-242861D01*
X601418Y-242799D01*
X601389Y-242770D01*
X601360Y-242741D01*
X601357D01*
X601353Y-242734D01*
X601342Y-242727D01*
X601331Y-242719D01*
X601295Y-242694D01*
X601244Y-242669D01*
X601182Y-242639D01*
X601105Y-242614D01*
X601018Y-242599D01*
X600923Y-242592D01*
D02*
G37*
G36*
X683819Y-212107D02*
X683815D01*
X683812D01*
X683790Y-212111D01*
X683757Y-212114D01*
X683717Y-212122D01*
X683670Y-212136D01*
X683622Y-212155D01*
X683571Y-212184D01*
X683528Y-212220D01*
X683524Y-212224D01*
X683509Y-212242D01*
X683491Y-212267D01*
X683473Y-212300D01*
X683451Y-212344D01*
X683433Y-212395D01*
X683419Y-212453D01*
X683415Y-212519D01*
Y-212526D01*
X683419Y-212548D01*
X683422Y-212580D01*
X683429Y-212624D01*
X683444Y-212671D01*
X683462Y-212719D01*
X683491Y-212770D01*
X683528Y-212813D01*
X683531Y-212817D01*
X683549Y-212831D01*
X683571Y-212850D01*
X683604Y-212872D01*
X683644Y-212893D01*
X683692Y-212912D01*
X683746Y-212926D01*
X683804Y-212930D01*
X683808D01*
X683812D01*
X683834D01*
X683866Y-212923D01*
X683906Y-212915D01*
X683950Y-212901D01*
X683997Y-212879D01*
X684045Y-212850D01*
X684092Y-212810D01*
X684095Y-212806D01*
X684110Y-212788D01*
X684128Y-212762D01*
X684150Y-212730D01*
X684172Y-212686D01*
X684190Y-212639D01*
X684205Y-212580D01*
X684208Y-212519D01*
Y-212489D01*
X684201Y-212457D01*
X684194Y-212413D01*
X684179Y-212366D01*
X684161Y-212315D01*
X684132Y-212267D01*
X684092Y-212220D01*
X684088Y-212216D01*
X684074Y-212202D01*
X684048Y-212184D01*
X684016Y-212165D01*
X683975Y-212143D01*
X683928Y-212125D01*
X683877Y-212111D01*
X683819Y-212107D01*
D02*
G37*
G36*
X682658Y-212005D02*
X682651D01*
X682636D01*
X682610Y-212009D01*
X682578Y-212013D01*
X682538Y-212020D01*
X682494Y-212031D01*
X682450Y-212045D01*
X682403Y-212064D01*
X682399Y-212067D01*
X682381Y-212074D01*
X682359Y-212089D01*
X682334Y-212111D01*
X682301Y-212136D01*
X682268Y-212169D01*
X682239Y-212205D01*
X682210Y-212249D01*
X682206Y-212256D01*
X682199Y-212271D01*
X682188Y-212296D01*
X682177Y-212329D01*
X682166Y-212369D01*
X682155Y-212417D01*
X682148Y-212468D01*
X682144Y-212519D01*
Y-212540D01*
X682148Y-212555D01*
X682152Y-212598D01*
X682163Y-212649D01*
X682181Y-212708D01*
X682203Y-212770D01*
X682239Y-212828D01*
X682287Y-212886D01*
X682294Y-212893D01*
X682312Y-212908D01*
X682345Y-212933D01*
X682385Y-212959D01*
X682436Y-212984D01*
X682498Y-213010D01*
X682570Y-213024D01*
X682647Y-213032D01*
X682651D01*
X682658D01*
X682669D01*
X682683Y-213028D01*
X682723Y-213024D01*
X682778Y-213014D01*
X682832Y-212995D01*
X682894Y-212970D01*
X682956Y-212933D01*
X683014Y-212882D01*
X683022Y-212875D01*
X683036Y-212857D01*
X683062Y-212824D01*
X683091Y-212780D01*
X683116Y-212726D01*
X683142Y-212660D01*
X683156Y-212588D01*
X683164Y-212508D01*
Y-212486D01*
X683160Y-212471D01*
X683156Y-212431D01*
X683146Y-212380D01*
X683127Y-212322D01*
X683102Y-212264D01*
X683065Y-212202D01*
X683018Y-212147D01*
X683011Y-212140D01*
X682993Y-212125D01*
X682960Y-212104D01*
X682920Y-212078D01*
X682865Y-212049D01*
X682803Y-212027D01*
X682734Y-212013D01*
X682658Y-212005D01*
D02*
G37*
G36*
X667788Y-212292D02*
X667781D01*
X667763D01*
X667730Y-212296D01*
X667690Y-212300D01*
X667642Y-212307D01*
X667592Y-212321D01*
X667537Y-212336D01*
X667482Y-212358D01*
X667475Y-212362D01*
X667457Y-212372D01*
X667431Y-212387D01*
X667399Y-212409D01*
X667366Y-212434D01*
X667326Y-212467D01*
X667293Y-212504D01*
X667260Y-212547D01*
X667257Y-212554D01*
X667249Y-212569D01*
X667235Y-212595D01*
X667224Y-212627D01*
X667209Y-212664D01*
X667195Y-212707D01*
X667188Y-212755D01*
X667184Y-212806D01*
Y-212824D01*
X667188Y-212838D01*
X667191Y-212875D01*
X667202Y-212922D01*
X667224Y-212973D01*
X667249Y-213031D01*
X667289Y-213089D01*
X667311Y-213119D01*
X667340Y-213144D01*
X667344D01*
X667348Y-213151D01*
X667370Y-213166D01*
X667406Y-213188D01*
X667453Y-213217D01*
X667515Y-213242D01*
X667588Y-213264D01*
X667672Y-213279D01*
X667770Y-213286D01*
X667774D01*
X667781D01*
X667795D01*
X667814Y-213282D01*
X667835D01*
X667861Y-213279D01*
X667919Y-213268D01*
X667985Y-213253D01*
X668054Y-213228D01*
X668119Y-213191D01*
X668181Y-213144D01*
X668188Y-213137D01*
X668207Y-213119D01*
X668229Y-213089D01*
X668258Y-213050D01*
X668287Y-212999D01*
X668309Y-212940D01*
X668327Y-212871D01*
X668334Y-212795D01*
Y-212773D01*
X668330Y-212758D01*
X668327Y-212722D01*
X668316Y-212671D01*
X668298Y-212616D01*
X668269Y-212554D01*
X668232Y-212496D01*
X668181Y-212438D01*
X668174Y-212431D01*
X668156Y-212416D01*
X668123Y-212391D01*
X668076Y-212365D01*
X668021Y-212340D01*
X667952Y-212314D01*
X667875Y-212300D01*
X667788Y-212292D01*
D02*
G37*
G36*
X612030Y-190852D02*
X612008D01*
X611994Y-190856D01*
X611958Y-190863D01*
X611906Y-190878D01*
X611852Y-190903D01*
X611790Y-190940D01*
X611761Y-190962D01*
X611732Y-190991D01*
X611703Y-191020D01*
X611673Y-191056D01*
Y-191060D01*
X611666Y-191067D01*
X611659Y-191078D01*
X611652Y-191096D01*
X611637Y-191122D01*
X611626Y-191154D01*
X611612Y-191191D01*
X611597Y-191235D01*
X611586Y-191289D01*
X611572Y-191347D01*
X611557Y-191417D01*
X611546Y-191489D01*
X611539Y-191577D01*
X611532Y-191668D01*
X611524Y-191770D01*
Y-191882D01*
Y-191886D01*
Y-191890D01*
Y-191908D01*
Y-191941D01*
X611528Y-191984D01*
Y-192032D01*
X611532Y-192090D01*
X611535Y-192152D01*
X611543Y-192221D01*
X611561Y-192359D01*
X611572Y-192428D01*
X611586Y-192494D01*
X611601Y-192556D01*
X611623Y-192614D01*
X611644Y-192665D01*
X611670Y-192709D01*
Y-192712D01*
X611677Y-192716D01*
X611685Y-192727D01*
X611695Y-192741D01*
X611728Y-192774D01*
X611768Y-192814D01*
X611823Y-192851D01*
X611885Y-192883D01*
X611917Y-192898D01*
X611954Y-192909D01*
X611994Y-192912D01*
X612034Y-192916D01*
X612056D01*
X612070Y-192912D01*
X612110Y-192905D01*
X612158Y-192894D01*
X612212Y-192873D01*
X612270Y-192840D01*
X612300Y-192818D01*
X612329Y-192796D01*
X612354Y-192767D01*
X612380Y-192734D01*
Y-192730D01*
X612387Y-192723D01*
X612394Y-192709D01*
X612405Y-192691D01*
X612416Y-192661D01*
X612431Y-192629D01*
X612442Y-192588D01*
X612456Y-192541D01*
X612471Y-192487D01*
X612485Y-192425D01*
X612500Y-192356D01*
X612511Y-192279D01*
X612522Y-192192D01*
X612529Y-192097D01*
X612533Y-191995D01*
X612536Y-191882D01*
Y-191875D01*
Y-191857D01*
Y-191824D01*
X612533Y-191780D01*
Y-191733D01*
X612529Y-191675D01*
X612525Y-191613D01*
X612518Y-191548D01*
X612500Y-191405D01*
X612489Y-191336D01*
X612474Y-191271D01*
X612460Y-191209D01*
X612438Y-191151D01*
X612416Y-191100D01*
X612391Y-191056D01*
Y-191052D01*
X612383Y-191049D01*
X612365Y-191023D01*
X612332Y-190991D01*
X612292Y-190954D01*
X612238Y-190918D01*
X612176Y-190885D01*
X612107Y-190859D01*
X612070Y-190856D01*
X612030Y-190852D01*
D02*
G37*
G36*
X562165Y-202533D02*
X562162D01*
X562158D01*
X562136Y-202537D01*
X562104Y-202540D01*
X562063Y-202547D01*
X562016Y-202562D01*
X561969Y-202580D01*
X561918Y-202609D01*
X561874Y-202646D01*
X561870Y-202649D01*
X561856Y-202667D01*
X561838Y-202693D01*
X561820Y-202726D01*
X561798Y-202769D01*
X561779Y-202820D01*
X561765Y-202879D01*
X561761Y-202944D01*
Y-202951D01*
X561765Y-202973D01*
X561769Y-203006D01*
X561776Y-203050D01*
X561790Y-203097D01*
X561809Y-203144D01*
X561838Y-203195D01*
X561874Y-203239D01*
X561878Y-203243D01*
X561896Y-203257D01*
X561918Y-203275D01*
X561951Y-203297D01*
X561991Y-203319D01*
X562038Y-203337D01*
X562093Y-203352D01*
X562151Y-203356D01*
X562154D01*
X562158D01*
X562180D01*
X562213Y-203348D01*
X562253Y-203341D01*
X562296Y-203326D01*
X562344Y-203305D01*
X562391Y-203275D01*
X562438Y-203235D01*
X562442Y-203232D01*
X562457Y-203214D01*
X562475Y-203188D01*
X562497Y-203155D01*
X562518Y-203112D01*
X562537Y-203064D01*
X562551Y-203006D01*
X562555Y-202944D01*
Y-202915D01*
X562548Y-202882D01*
X562540Y-202839D01*
X562526Y-202791D01*
X562507Y-202740D01*
X562478Y-202693D01*
X562438Y-202646D01*
X562435Y-202642D01*
X562420Y-202627D01*
X562395Y-202609D01*
X562362Y-202591D01*
X562322Y-202569D01*
X562275Y-202551D01*
X562224Y-202537D01*
X562165Y-202533D01*
D02*
G37*
G36*
X561004Y-202431D02*
X560997D01*
X560982D01*
X560957Y-202434D01*
X560924Y-202438D01*
X560884Y-202446D01*
X560840Y-202456D01*
X560797Y-202471D01*
X560749Y-202489D01*
X560746Y-202493D01*
X560728Y-202500D01*
X560706Y-202515D01*
X560680Y-202537D01*
X560647Y-202562D01*
X560615Y-202595D01*
X560586Y-202631D01*
X560557Y-202675D01*
X560553Y-202682D01*
X560546Y-202697D01*
X560535Y-202722D01*
X560524Y-202755D01*
X560513Y-202795D01*
X560502Y-202842D01*
X560495Y-202893D01*
X560491Y-202944D01*
Y-202966D01*
X560495Y-202980D01*
X560498Y-203024D01*
X560509Y-203075D01*
X560527Y-203133D01*
X560549Y-203195D01*
X560586Y-203254D01*
X560633Y-203312D01*
X560640Y-203319D01*
X560658Y-203334D01*
X560691Y-203359D01*
X560731Y-203385D01*
X560782Y-203410D01*
X560844Y-203435D01*
X560917Y-203450D01*
X560993Y-203457D01*
X560997D01*
X561004D01*
X561015D01*
X561030Y-203454D01*
X561070Y-203450D01*
X561124Y-203439D01*
X561179Y-203421D01*
X561241Y-203396D01*
X561303Y-203359D01*
X561361Y-203308D01*
X561368Y-203301D01*
X561383Y-203283D01*
X561408Y-203250D01*
X561437Y-203206D01*
X561463Y-203152D01*
X561488Y-203086D01*
X561503Y-203013D01*
X561510Y-202933D01*
Y-202911D01*
X561507Y-202897D01*
X561503Y-202857D01*
X561492Y-202806D01*
X561474Y-202748D01*
X561448Y-202689D01*
X561412Y-202627D01*
X561365Y-202573D01*
X561357Y-202566D01*
X561339Y-202551D01*
X561306Y-202529D01*
X561266Y-202504D01*
X561212Y-202475D01*
X561150Y-202453D01*
X561081Y-202438D01*
X561004Y-202431D01*
D02*
G37*
G36*
X561758Y-210719D02*
X561754D01*
X561747D01*
X561732D01*
X561714Y-210723D01*
X561692D01*
X561667Y-210727D01*
X561608Y-210738D01*
X561543Y-210752D01*
X561474Y-210778D01*
X561408Y-210814D01*
X561346Y-210861D01*
X561339Y-210869D01*
X561321Y-210887D01*
X561299Y-210916D01*
X561270Y-210956D01*
X561241Y-211007D01*
X561219Y-211065D01*
X561201Y-211135D01*
X561193Y-211211D01*
Y-211233D01*
X561197Y-211247D01*
X561201Y-211284D01*
X561212Y-211335D01*
X561230Y-211389D01*
X561259Y-211451D01*
X561295Y-211509D01*
X561346Y-211568D01*
X561354Y-211575D01*
X561372Y-211590D01*
X561405Y-211615D01*
X561452Y-211640D01*
X561507Y-211666D01*
X561576Y-211691D01*
X561652Y-211706D01*
X561739Y-211713D01*
X561747D01*
X561765D01*
X561798Y-211710D01*
X561838Y-211706D01*
X561885Y-211699D01*
X561936Y-211684D01*
X561991Y-211669D01*
X562045Y-211648D01*
X562052Y-211644D01*
X562071Y-211633D01*
X562096Y-211619D01*
X562129Y-211597D01*
X562162Y-211571D01*
X562202Y-211539D01*
X562234Y-211502D01*
X562267Y-211458D01*
X562271Y-211451D01*
X562278Y-211437D01*
X562293Y-211411D01*
X562304Y-211378D01*
X562318Y-211342D01*
X562333Y-211298D01*
X562340Y-211251D01*
X562344Y-211200D01*
Y-211182D01*
X562340Y-211167D01*
X562336Y-211131D01*
X562325Y-211084D01*
X562304Y-211033D01*
X562278Y-210974D01*
X562238Y-210916D01*
X562216Y-210887D01*
X562187Y-210861D01*
X562184D01*
X562180Y-210854D01*
X562158Y-210840D01*
X562122Y-210818D01*
X562074Y-210789D01*
X562012Y-210763D01*
X561940Y-210741D01*
X561856Y-210727D01*
X561758Y-210719D01*
D02*
G37*
G36*
X594785Y-132512D02*
X594782D01*
X594767D01*
X594749D01*
X594720Y-132516D01*
X594687D01*
X594651Y-132519D01*
X594607Y-132523D01*
X594563Y-132527D01*
X594465Y-132545D01*
X594363Y-132567D01*
X594269Y-132599D01*
X594221Y-132621D01*
X594181Y-132643D01*
X594177D01*
X594170Y-132650D01*
X594159Y-132658D01*
X594145Y-132665D01*
X594108Y-132694D01*
X594065Y-132730D01*
X594017Y-132778D01*
X593970Y-132832D01*
X593930Y-132894D01*
X593897Y-132960D01*
X593894Y-132967D01*
X593890Y-132985D01*
X593879Y-133018D01*
X593868Y-133065D01*
X593861Y-133124D01*
X593850Y-133196D01*
X593846Y-133240D01*
Y-133287D01*
X593843Y-133335D01*
Y-133917D01*
X595764D01*
Y-133320D01*
X595761Y-133295D01*
X595757Y-133240D01*
X595754Y-133178D01*
X595746Y-133113D01*
X595735Y-133047D01*
X595721Y-132993D01*
X595717Y-132985D01*
X595714Y-132967D01*
X595703Y-132942D01*
X595688Y-132909D01*
X595666Y-132872D01*
X595644Y-132836D01*
X595619Y-132800D01*
X595590Y-132763D01*
X595582Y-132760D01*
X595568Y-132745D01*
X595542Y-132723D01*
X595506Y-132698D01*
X595459Y-132669D01*
X595404Y-132636D01*
X595342Y-132607D01*
X595273Y-132581D01*
X595269D01*
X595262Y-132578D01*
X595251Y-132574D01*
X595237Y-132570D01*
X595219Y-132567D01*
X595193Y-132559D01*
X595168Y-132552D01*
X595139Y-132545D01*
X595066Y-132534D01*
X594982Y-132523D01*
X594887Y-132516D01*
X594785Y-132512D01*
D02*
G37*
G36*
X657071Y-130694D02*
X657067D01*
X657063D01*
X657041D01*
X657009Y-130701D01*
X656969Y-130708D01*
X656925Y-130723D01*
X656878Y-130745D01*
X656830Y-130774D01*
X656783Y-130814D01*
X656779Y-130817D01*
X656765Y-130835D01*
X656747Y-130861D01*
X656725Y-130894D01*
X656703Y-130937D01*
X656685Y-130985D01*
X656670Y-131043D01*
X656667Y-131105D01*
Y-131134D01*
X656674Y-131167D01*
X656681Y-131210D01*
X656696Y-131258D01*
X656714Y-131309D01*
X656743Y-131356D01*
X656783Y-131403D01*
X656787Y-131407D01*
X656801Y-131422D01*
X656827Y-131440D01*
X656859Y-131458D01*
X656899Y-131480D01*
X656947Y-131498D01*
X656998Y-131513D01*
X657056Y-131516D01*
X657060D01*
X657063D01*
X657085Y-131513D01*
X657118Y-131509D01*
X657158Y-131502D01*
X657205Y-131487D01*
X657253Y-131469D01*
X657303Y-131440D01*
X657347Y-131403D01*
X657351Y-131400D01*
X657365Y-131381D01*
X657384Y-131356D01*
X657402Y-131323D01*
X657424Y-131280D01*
X657442Y-131229D01*
X657456Y-131170D01*
X657460Y-131105D01*
Y-131098D01*
X657456Y-131076D01*
X657453Y-131043D01*
X657445Y-130999D01*
X657431Y-130952D01*
X657413Y-130905D01*
X657384Y-130854D01*
X657347Y-130810D01*
X657344Y-130806D01*
X657325Y-130792D01*
X657303Y-130774D01*
X657271Y-130752D01*
X657231Y-130730D01*
X657183Y-130712D01*
X657129Y-130697D01*
X657071Y-130694D01*
D02*
G37*
G36*
X658228Y-130592D02*
X658224D01*
X658217D01*
X658206D01*
X658192Y-130595D01*
X658152Y-130599D01*
X658097Y-130610D01*
X658042Y-130628D01*
X657981Y-130654D01*
X657919Y-130690D01*
X657861Y-130741D01*
X657853Y-130748D01*
X657839Y-130766D01*
X657813Y-130799D01*
X657784Y-130843D01*
X657759Y-130897D01*
X657733Y-130963D01*
X657719Y-131036D01*
X657711Y-131116D01*
Y-131138D01*
X657715Y-131152D01*
X657719Y-131192D01*
X657729Y-131243D01*
X657748Y-131301D01*
X657773Y-131360D01*
X657809Y-131422D01*
X657857Y-131476D01*
X657864Y-131483D01*
X657882Y-131498D01*
X657915Y-131520D01*
X657955Y-131545D01*
X658010Y-131574D01*
X658072Y-131596D01*
X658141Y-131611D01*
X658217Y-131618D01*
X658224D01*
X658239D01*
X658264Y-131614D01*
X658297Y-131611D01*
X658337Y-131604D01*
X658381Y-131593D01*
X658425Y-131578D01*
X658472Y-131560D01*
X658476Y-131556D01*
X658494Y-131549D01*
X658516Y-131534D01*
X658541Y-131513D01*
X658574Y-131487D01*
X658607Y-131454D01*
X658636Y-131418D01*
X658665Y-131374D01*
X658669Y-131367D01*
X658676Y-131352D01*
X658687Y-131327D01*
X658698Y-131294D01*
X658709Y-131254D01*
X658719Y-131207D01*
X658727Y-131156D01*
X658730Y-131105D01*
Y-131083D01*
X658727Y-131069D01*
X658723Y-131025D01*
X658712Y-130974D01*
X658694Y-130916D01*
X658672Y-130854D01*
X658636Y-130796D01*
X658589Y-130737D01*
X658581Y-130730D01*
X658563Y-130715D01*
X658530Y-130690D01*
X658490Y-130664D01*
X658439Y-130639D01*
X658377Y-130614D01*
X658305Y-130599D01*
X658228Y-130592D01*
D02*
G37*
G36*
X564626Y-169633D02*
X564029D01*
X564003Y-169637D01*
X563949Y-169641D01*
X563887Y-169644D01*
X563821Y-169652D01*
X563756Y-169663D01*
X563701Y-169677D01*
X563694Y-169681D01*
X563676Y-169684D01*
X563650Y-169695D01*
X563618Y-169710D01*
X563581Y-169732D01*
X563545Y-169754D01*
X563508Y-169779D01*
X563472Y-169808D01*
X563468Y-169816D01*
X563454Y-169830D01*
X563432Y-169855D01*
X563406Y-169892D01*
X563377Y-169939D01*
X563344Y-169994D01*
X563315Y-170056D01*
X563290Y-170125D01*
Y-170129D01*
X563286Y-170136D01*
X563283Y-170147D01*
X563279Y-170161D01*
X563275Y-170179D01*
X563268Y-170205D01*
X563261Y-170230D01*
X563253Y-170259D01*
X563243Y-170332D01*
X563232Y-170416D01*
X563224Y-170511D01*
X563221Y-170613D01*
Y-170616D01*
Y-170631D01*
Y-170649D01*
X563224Y-170678D01*
Y-170711D01*
X563228Y-170747D01*
X563232Y-170791D01*
X563235Y-170835D01*
X563253Y-170933D01*
X563275Y-171035D01*
X563308Y-171130D01*
X563330Y-171177D01*
X563352Y-171217D01*
Y-171221D01*
X563359Y-171228D01*
X563366Y-171239D01*
X563374Y-171253D01*
X563403Y-171290D01*
X563439Y-171333D01*
X563486Y-171381D01*
X563541Y-171428D01*
X563603Y-171468D01*
X563668Y-171501D01*
X563676Y-171504D01*
X563694Y-171508D01*
X563727Y-171519D01*
X563774Y-171530D01*
X563832Y-171537D01*
X563905Y-171548D01*
X563949Y-171552D01*
X563996D01*
X564043Y-171555D01*
X564626D01*
Y-169633D01*
D02*
G37*
G36*
X620602Y-293843D02*
X620020D01*
Y-295765D01*
X620617D01*
X620642Y-295761D01*
X620697Y-295757D01*
X620759Y-295754D01*
X620824Y-295746D01*
X620890Y-295735D01*
X620944Y-295721D01*
X620952Y-295717D01*
X620970Y-295714D01*
X620995Y-295703D01*
X621028Y-295688D01*
X621065Y-295666D01*
X621101Y-295644D01*
X621137Y-295619D01*
X621174Y-295590D01*
X621177Y-295583D01*
X621192Y-295568D01*
X621214Y-295543D01*
X621239Y-295506D01*
X621268Y-295459D01*
X621301Y-295404D01*
X621330Y-295342D01*
X621356Y-295273D01*
Y-295269D01*
X621359Y-295262D01*
X621363Y-295251D01*
X621367Y-295237D01*
X621370Y-295219D01*
X621378Y-295193D01*
X621385Y-295168D01*
X621392Y-295139D01*
X621403Y-295066D01*
X621414Y-294982D01*
X621421Y-294887D01*
X621425Y-294785D01*
Y-294782D01*
Y-294767D01*
Y-294749D01*
X621421Y-294720D01*
Y-294687D01*
X621418Y-294651D01*
X621414Y-294607D01*
X621410Y-294563D01*
X621392Y-294465D01*
X621370Y-294363D01*
X621338Y-294268D01*
X621316Y-294221D01*
X621294Y-294181D01*
Y-294178D01*
X621287Y-294170D01*
X621279Y-294159D01*
X621272Y-294145D01*
X621243Y-294108D01*
X621207Y-294065D01*
X621159Y-294017D01*
X621105Y-293970D01*
X621043Y-293930D01*
X620977Y-293897D01*
X620970Y-293894D01*
X620952Y-293890D01*
X620919Y-293879D01*
X620872Y-293868D01*
X620813Y-293861D01*
X620741Y-293850D01*
X620697Y-293846D01*
X620650D01*
X620602Y-293843D01*
D02*
G37*
G36*
X597027Y-295924D02*
X597009D01*
X596994Y-295928D01*
X596958Y-295931D01*
X596910Y-295942D01*
X596859Y-295964D01*
X596801Y-295990D01*
X596743Y-296030D01*
X596714Y-296051D01*
X596688Y-296081D01*
Y-296084D01*
X596681Y-296088D01*
X596666Y-296110D01*
X596644Y-296146D01*
X596615Y-296193D01*
X596590Y-296255D01*
X596568Y-296328D01*
X596554Y-296412D01*
X596546Y-296510D01*
Y-296514D01*
Y-296521D01*
Y-296536D01*
X596550Y-296554D01*
Y-296576D01*
X596554Y-296601D01*
X596564Y-296659D01*
X596579Y-296725D01*
X596604Y-296794D01*
X596641Y-296860D01*
X596688Y-296921D01*
X596696Y-296929D01*
X596714Y-296947D01*
X596743Y-296969D01*
X596783Y-296998D01*
X596834Y-297027D01*
X596892Y-297049D01*
X596961Y-297067D01*
X597038Y-297074D01*
X597059D01*
X597074Y-297071D01*
X597111Y-297067D01*
X597161Y-297056D01*
X597216Y-297038D01*
X597278Y-297009D01*
X597336Y-296972D01*
X597394Y-296921D01*
X597402Y-296914D01*
X597416Y-296896D01*
X597442Y-296863D01*
X597467Y-296816D01*
X597493Y-296761D01*
X597518Y-296692D01*
X597533Y-296616D01*
X597540Y-296528D01*
Y-296521D01*
Y-296503D01*
X597536Y-296470D01*
X597533Y-296430D01*
X597525Y-296383D01*
X597511Y-296332D01*
X597496Y-296277D01*
X597474Y-296222D01*
X597471Y-296215D01*
X597460Y-296197D01*
X597445Y-296172D01*
X597424Y-296139D01*
X597398Y-296106D01*
X597365Y-296066D01*
X597329Y-296033D01*
X597285Y-296001D01*
X597278Y-295997D01*
X597263Y-295990D01*
X597238Y-295975D01*
X597205Y-295964D01*
X597169Y-295950D01*
X597125Y-295935D01*
X597078Y-295928D01*
X597027Y-295924D01*
D02*
G37*
G36*
X595097D02*
X595076D01*
X595061Y-295928D01*
X595017Y-295931D01*
X594967Y-295942D01*
X594908Y-295960D01*
X594846Y-295982D01*
X594788Y-296019D01*
X594730Y-296066D01*
X594723Y-296073D01*
X594708Y-296092D01*
X594683Y-296124D01*
X594657Y-296164D01*
X594632Y-296215D01*
X594606Y-296277D01*
X594592Y-296350D01*
X594584Y-296426D01*
Y-296430D01*
Y-296437D01*
Y-296448D01*
X594588Y-296463D01*
X594592Y-296503D01*
X594602Y-296557D01*
X594621Y-296612D01*
X594646Y-296674D01*
X594683Y-296736D01*
X594734Y-296794D01*
X594741Y-296801D01*
X594759Y-296816D01*
X594792Y-296841D01*
X594836Y-296870D01*
X594890Y-296896D01*
X594956Y-296921D01*
X595028Y-296936D01*
X595109Y-296943D01*
X595130D01*
X595145Y-296940D01*
X595185Y-296936D01*
X595236Y-296925D01*
X595294Y-296907D01*
X595352Y-296881D01*
X595414Y-296845D01*
X595469Y-296798D01*
X595476Y-296790D01*
X595491Y-296772D01*
X595512Y-296739D01*
X595538Y-296699D01*
X595567Y-296645D01*
X595589Y-296583D01*
X595604Y-296514D01*
X595611Y-296437D01*
Y-296430D01*
Y-296415D01*
X595607Y-296390D01*
X595604Y-296357D01*
X595596Y-296317D01*
X595585Y-296273D01*
X595571Y-296230D01*
X595552Y-296182D01*
X595549Y-296179D01*
X595542Y-296161D01*
X595527Y-296139D01*
X595505Y-296113D01*
X595480Y-296081D01*
X595447Y-296048D01*
X595411Y-296019D01*
X595367Y-295990D01*
X595360Y-295986D01*
X595345Y-295979D01*
X595320Y-295968D01*
X595287Y-295957D01*
X595247Y-295946D01*
X595199Y-295935D01*
X595149Y-295928D01*
X595097Y-295924D01*
D02*
G37*
G36*
Y-297194D02*
X595090D01*
X595068Y-297198D01*
X595036Y-297202D01*
X594992Y-297209D01*
X594945Y-297223D01*
X594897Y-297242D01*
X594846Y-297271D01*
X594803Y-297307D01*
X594799Y-297311D01*
X594784Y-297329D01*
X594766Y-297351D01*
X594744Y-297384D01*
X594723Y-297424D01*
X594704Y-297471D01*
X594690Y-297526D01*
X594686Y-297584D01*
Y-297587D01*
Y-297591D01*
Y-297613D01*
X594694Y-297646D01*
X594701Y-297686D01*
X594715Y-297729D01*
X594737Y-297777D01*
X594766Y-297824D01*
X594806Y-297871D01*
X594810Y-297875D01*
X594828Y-297890D01*
X594854Y-297908D01*
X594886Y-297930D01*
X594930Y-297952D01*
X594977Y-297970D01*
X595036Y-297984D01*
X595097Y-297988D01*
X595127D01*
X595159Y-297981D01*
X595203Y-297973D01*
X595250Y-297959D01*
X595301Y-297941D01*
X595349Y-297912D01*
X595396Y-297871D01*
X595400Y-297868D01*
X595414Y-297853D01*
X595432Y-297828D01*
X595451Y-297795D01*
X595472Y-297755D01*
X595491Y-297708D01*
X595505Y-297657D01*
X595509Y-297598D01*
Y-297595D01*
Y-297591D01*
X595505Y-297569D01*
X595502Y-297537D01*
X595494Y-297497D01*
X595480Y-297449D01*
X595462Y-297402D01*
X595432Y-297351D01*
X595396Y-297307D01*
X595392Y-297304D01*
X595374Y-297289D01*
X595349Y-297271D01*
X595316Y-297253D01*
X595272Y-297231D01*
X595221Y-297213D01*
X595163Y-297198D01*
X595097Y-297194D01*
D02*
G37*
G36*
X554682Y-292774D02*
X554660D01*
X554645Y-292778D01*
X554609Y-292785D01*
X554558Y-292800D01*
X554503Y-292825D01*
X554441Y-292862D01*
X554412Y-292884D01*
X554383Y-292913D01*
X554354Y-292942D01*
X554325Y-292978D01*
Y-292982D01*
X554318Y-292989D01*
X554310Y-293000D01*
X554303Y-293018D01*
X554288Y-293044D01*
X554278Y-293077D01*
X554263Y-293113D01*
X554248Y-293157D01*
X554238Y-293211D01*
X554223Y-293269D01*
X554208Y-293339D01*
X554198Y-293411D01*
X554190Y-293499D01*
X554183Y-293590D01*
X554176Y-293692D01*
Y-293805D01*
Y-293808D01*
Y-293812D01*
Y-293830D01*
Y-293863D01*
X554179Y-293906D01*
Y-293954D01*
X554183Y-294012D01*
X554186Y-294074D01*
X554194Y-294143D01*
X554212Y-294281D01*
X554223Y-294351D01*
X554238Y-294416D01*
X554252Y-294478D01*
X554274Y-294536D01*
X554296Y-294587D01*
X554321Y-294631D01*
Y-294635D01*
X554328Y-294638D01*
X554336Y-294649D01*
X554347Y-294664D01*
X554380Y-294696D01*
X554420Y-294736D01*
X554474Y-294773D01*
X554536Y-294806D01*
X554569Y-294820D01*
X554605Y-294831D01*
X554645Y-294835D01*
X554685Y-294838D01*
X554707D01*
X554722Y-294835D01*
X554762Y-294827D01*
X554809Y-294816D01*
X554864Y-294795D01*
X554922Y-294762D01*
X554951Y-294740D01*
X554980Y-294718D01*
X555006Y-294689D01*
X555031Y-294656D01*
Y-294653D01*
X555038Y-294645D01*
X555046Y-294631D01*
X555056Y-294613D01*
X555067Y-294584D01*
X555082Y-294551D01*
X555093Y-294511D01*
X555107Y-294463D01*
X555122Y-294409D01*
X555137Y-294347D01*
X555151Y-294278D01*
X555162Y-294201D01*
X555173Y-294114D01*
X555180Y-294019D01*
X555184Y-293917D01*
X555188Y-293805D01*
Y-293797D01*
Y-293779D01*
Y-293746D01*
X555184Y-293703D01*
Y-293655D01*
X555180Y-293597D01*
X555177Y-293535D01*
X555169Y-293470D01*
X555151Y-293328D01*
X555140Y-293259D01*
X555126Y-293193D01*
X555111Y-293131D01*
X555089Y-293073D01*
X555067Y-293022D01*
X555042Y-292978D01*
Y-292975D01*
X555035Y-292971D01*
X555017Y-292946D01*
X554984Y-292913D01*
X554944Y-292876D01*
X554889Y-292840D01*
X554827Y-292807D01*
X554758Y-292782D01*
X554722Y-292778D01*
X554682Y-292774D01*
D02*
G37*
G36*
X544711Y-292904D02*
X544689D01*
X544675Y-292908D01*
X544635Y-292912D01*
X544587Y-292922D01*
X544529Y-292941D01*
X544471Y-292966D01*
X544413Y-293003D01*
X544358Y-293054D01*
X544351Y-293061D01*
X544336Y-293083D01*
X544314Y-293115D01*
X544285Y-293163D01*
X544260Y-293221D01*
X544238Y-293290D01*
X544223Y-293374D01*
X544216Y-293468D01*
Y-293472D01*
Y-293479D01*
Y-293494D01*
X544220Y-293512D01*
Y-293538D01*
X544223Y-293563D01*
X544234Y-293621D01*
X544249Y-293691D01*
X544274Y-293763D01*
X544311Y-293832D01*
X544358Y-293894D01*
Y-293898D01*
X544365Y-293902D01*
X544383Y-293920D01*
X544413Y-293945D01*
X544453Y-293974D01*
X544504Y-294000D01*
X544562Y-294025D01*
X544627Y-294044D01*
X544664Y-294051D01*
X544722D01*
X544737Y-294047D01*
X544777Y-294044D01*
X544824Y-294029D01*
X544882Y-294011D01*
X544944Y-293978D01*
X545006Y-293938D01*
X545035Y-293909D01*
X545064Y-293880D01*
Y-293876D01*
X545072Y-293873D01*
X545079Y-293862D01*
X545086Y-293851D01*
X545112Y-293814D01*
X545137Y-293763D01*
X545166Y-293702D01*
X545192Y-293625D01*
X545206Y-293538D01*
X545214Y-293443D01*
Y-293439D01*
Y-293432D01*
Y-293421D01*
X545210Y-293403D01*
Y-293381D01*
X545206Y-293359D01*
X545195Y-293305D01*
X545177Y-293243D01*
X545155Y-293177D01*
X545119Y-293112D01*
X545072Y-293054D01*
X545064Y-293046D01*
X545046Y-293032D01*
X545013Y-293006D01*
X544973Y-292981D01*
X544919Y-292952D01*
X544857Y-292926D01*
X544788Y-292912D01*
X544711Y-292904D01*
D02*
G37*
G36*
X546633Y-291987D02*
X546615D01*
X546600Y-291991D01*
X546564Y-291994D01*
X546517Y-292005D01*
X546466Y-292027D01*
X546407Y-292053D01*
X546349Y-292093D01*
X546320Y-292114D01*
X546294Y-292144D01*
Y-292147D01*
X546287Y-292151D01*
X546273Y-292173D01*
X546251Y-292209D01*
X546222Y-292256D01*
X546196Y-292318D01*
X546174Y-292391D01*
X546160Y-292475D01*
X546153Y-292573D01*
Y-292577D01*
Y-292584D01*
Y-292599D01*
X546156Y-292617D01*
Y-292639D01*
X546160Y-292664D01*
X546171Y-292722D01*
X546185Y-292788D01*
X546211Y-292857D01*
X546247Y-292922D01*
X546294Y-292984D01*
X546302Y-292992D01*
X546320Y-293010D01*
X546349Y-293032D01*
X546389Y-293061D01*
X546440Y-293090D01*
X546498Y-293112D01*
X546567Y-293130D01*
X546644Y-293137D01*
X546666D01*
X546680Y-293134D01*
X546717Y-293130D01*
X546768Y-293119D01*
X546822Y-293101D01*
X546884Y-293072D01*
X546943Y-293035D01*
X547001Y-292984D01*
X547008Y-292977D01*
X547022Y-292959D01*
X547048Y-292926D01*
X547074Y-292879D01*
X547099Y-292824D01*
X547124Y-292755D01*
X547139Y-292679D01*
X547146Y-292591D01*
Y-292584D01*
Y-292566D01*
X547143Y-292533D01*
X547139Y-292493D01*
X547132Y-292446D01*
X547117Y-292395D01*
X547103Y-292340D01*
X547081Y-292285D01*
X547077Y-292278D01*
X547066Y-292260D01*
X547052Y-292235D01*
X547030Y-292202D01*
X547004Y-292169D01*
X546972Y-292129D01*
X546935Y-292096D01*
X546891Y-292063D01*
X546884Y-292060D01*
X546870Y-292053D01*
X546844Y-292038D01*
X546811Y-292027D01*
X546775Y-292013D01*
X546731Y-291998D01*
X546684Y-291991D01*
X546633Y-291987D01*
D02*
G37*
G36*
X567774Y-292664D02*
X566981D01*
Y-293793D01*
X567774Y-292664D01*
D02*
G37*
G36*
X604671Y-248131D02*
X604667D01*
X604660D01*
X604645D01*
X604627Y-248135D01*
X604605D01*
X604580Y-248138D01*
X604522Y-248149D01*
X604456Y-248164D01*
X604387Y-248189D01*
X604322Y-248226D01*
X604260Y-248273D01*
X604252Y-248281D01*
X604234Y-248299D01*
X604212Y-248328D01*
X604183Y-248368D01*
X604154Y-248419D01*
X604132Y-248477D01*
X604114Y-248546D01*
X604107Y-248623D01*
Y-248644D01*
X604110Y-248659D01*
X604114Y-248695D01*
X604125Y-248746D01*
X604143Y-248801D01*
X604172Y-248863D01*
X604209Y-248921D01*
X604260Y-248979D01*
X604267Y-248987D01*
X604285Y-249001D01*
X604318Y-249027D01*
X604365Y-249052D01*
X604420Y-249078D01*
X604489Y-249103D01*
X604565Y-249118D01*
X604653Y-249125D01*
X604660D01*
X604678D01*
X604711Y-249121D01*
X604751Y-249118D01*
X604798Y-249110D01*
X604849Y-249096D01*
X604904Y-249081D01*
X604959Y-249060D01*
X604966Y-249056D01*
X604984Y-249045D01*
X605010Y-249030D01*
X605042Y-249008D01*
X605075Y-248983D01*
X605115Y-248950D01*
X605148Y-248914D01*
X605181Y-248870D01*
X605184Y-248863D01*
X605192Y-248848D01*
X605206Y-248823D01*
X605217Y-248790D01*
X605232Y-248754D01*
X605246Y-248710D01*
X605253Y-248663D01*
X605257Y-248612D01*
Y-248594D01*
X605253Y-248579D01*
X605250Y-248543D01*
X605239Y-248495D01*
X605217Y-248444D01*
X605192Y-248386D01*
X605152Y-248328D01*
X605130Y-248299D01*
X605100Y-248273D01*
X605097D01*
X605093Y-248266D01*
X605071Y-248251D01*
X605035Y-248230D01*
X604988Y-248200D01*
X604926Y-248175D01*
X604853Y-248153D01*
X604769Y-248138D01*
X604671Y-248131D01*
D02*
G37*
G36*
X669469Y-266185D02*
X669440D01*
X669408Y-266193D01*
X669364Y-266200D01*
X669316Y-266214D01*
X669266Y-266233D01*
X669218Y-266262D01*
X669171Y-266302D01*
X669167Y-266305D01*
X669153Y-266320D01*
X669135Y-266346D01*
X669116Y-266378D01*
X669095Y-266418D01*
X669076Y-266466D01*
X669062Y-266517D01*
X669058Y-266575D01*
Y-266578D01*
Y-266582D01*
X669062Y-266604D01*
X669065Y-266637D01*
X669073Y-266677D01*
X669087Y-266724D01*
X669105Y-266771D01*
X669135Y-266822D01*
X669171Y-266866D01*
X669174Y-266870D01*
X669193Y-266884D01*
X669218Y-266902D01*
X669251Y-266921D01*
X669295Y-266942D01*
X669346Y-266961D01*
X669404Y-266975D01*
X669469Y-266979D01*
X669477D01*
X669498Y-266975D01*
X669531Y-266971D01*
X669575Y-266964D01*
X669622Y-266950D01*
X669670Y-266932D01*
X669721Y-266902D01*
X669764Y-266866D01*
X669768Y-266862D01*
X669782Y-266844D01*
X669801Y-266822D01*
X669823Y-266790D01*
X669844Y-266750D01*
X669863Y-266702D01*
X669877Y-266648D01*
X669881Y-266589D01*
Y-266586D01*
Y-266582D01*
Y-266560D01*
X669873Y-266528D01*
X669866Y-266487D01*
X669852Y-266444D01*
X669830Y-266396D01*
X669801Y-266349D01*
X669761Y-266302D01*
X669757Y-266298D01*
X669739Y-266284D01*
X669713Y-266265D01*
X669681Y-266244D01*
X669637Y-266222D01*
X669590Y-266203D01*
X669531Y-266189D01*
X669469Y-266185D01*
D02*
G37*
G36*
X669458Y-267230D02*
X669437D01*
X669422Y-267234D01*
X669382Y-267237D01*
X669331Y-267248D01*
X669273Y-267266D01*
X669215Y-267292D01*
X669153Y-267328D01*
X669098Y-267376D01*
X669091Y-267383D01*
X669076Y-267401D01*
X669054Y-267434D01*
X669029Y-267474D01*
X669000Y-267529D01*
X668978Y-267590D01*
X668963Y-267659D01*
X668956Y-267736D01*
Y-267743D01*
Y-267758D01*
X668960Y-267783D01*
X668963Y-267816D01*
X668971Y-267856D01*
X668982Y-267900D01*
X668996Y-267943D01*
X669014Y-267991D01*
X669018Y-267994D01*
X669025Y-268013D01*
X669040Y-268034D01*
X669062Y-268060D01*
X669087Y-268093D01*
X669120Y-268125D01*
X669156Y-268155D01*
X669200Y-268184D01*
X669207Y-268187D01*
X669222Y-268195D01*
X669247Y-268205D01*
X669280Y-268216D01*
X669320Y-268227D01*
X669368Y-268238D01*
X669418Y-268246D01*
X669469Y-268249D01*
X669491D01*
X669506Y-268246D01*
X669550Y-268242D01*
X669600Y-268231D01*
X669659Y-268213D01*
X669721Y-268191D01*
X669779Y-268155D01*
X669837Y-268107D01*
X669844Y-268100D01*
X669859Y-268082D01*
X669884Y-268049D01*
X669910Y-268009D01*
X669935Y-267958D01*
X669961Y-267896D01*
X669975Y-267823D01*
X669983Y-267747D01*
Y-267743D01*
Y-267736D01*
Y-267725D01*
X669979Y-267710D01*
X669975Y-267670D01*
X669964Y-267616D01*
X669946Y-267561D01*
X669921Y-267499D01*
X669884Y-267438D01*
X669833Y-267379D01*
X669826Y-267372D01*
X669808Y-267357D01*
X669775Y-267332D01*
X669732Y-267303D01*
X669677Y-267277D01*
X669611Y-267252D01*
X669538Y-267237D01*
X669458Y-267230D01*
D02*
G37*
G36*
X638394Y-278207D02*
X638373D01*
X638358Y-278211D01*
X638314Y-278215D01*
X638263Y-278226D01*
X638205Y-278244D01*
X638143Y-278266D01*
X638085Y-278302D01*
X638027Y-278349D01*
X638020Y-278357D01*
X638005Y-278375D01*
X637980Y-278408D01*
X637954Y-278448D01*
X637928Y-278499D01*
X637903Y-278561D01*
X637888Y-278633D01*
X637881Y-278710D01*
Y-278713D01*
Y-278721D01*
Y-278732D01*
X637885Y-278746D01*
X637888Y-278786D01*
X637899Y-278841D01*
X637918Y-278895D01*
X637943Y-278957D01*
X637980Y-279019D01*
X638030Y-279078D01*
X638038Y-279085D01*
X638056Y-279099D01*
X638089Y-279125D01*
X638132Y-279154D01*
X638187Y-279179D01*
X638252Y-279205D01*
X638325Y-279220D01*
X638405Y-279227D01*
X638427D01*
X638442Y-279223D01*
X638482Y-279220D01*
X638533Y-279208D01*
X638591Y-279190D01*
X638649Y-279165D01*
X638711Y-279129D01*
X638766Y-279081D01*
X638773Y-279074D01*
X638788Y-279056D01*
X638809Y-279023D01*
X638835Y-278983D01*
X638864Y-278928D01*
X638886Y-278866D01*
X638900Y-278797D01*
X638908Y-278721D01*
Y-278713D01*
Y-278699D01*
X638904Y-278674D01*
X638900Y-278641D01*
X638893Y-278601D01*
X638882Y-278557D01*
X638868Y-278513D01*
X638849Y-278466D01*
X638846Y-278462D01*
X638838Y-278444D01*
X638824Y-278422D01*
X638802Y-278397D01*
X638777Y-278364D01*
X638744Y-278331D01*
X638707Y-278302D01*
X638664Y-278273D01*
X638657Y-278269D01*
X638642Y-278262D01*
X638617Y-278251D01*
X638584Y-278240D01*
X638544Y-278229D01*
X638496Y-278218D01*
X638445Y-278211D01*
X638394Y-278207D01*
D02*
G37*
G36*
Y-279478D02*
X638387D01*
X638365Y-279482D01*
X638333Y-279485D01*
X638289Y-279492D01*
X638242Y-279507D01*
X638194Y-279525D01*
X638143Y-279554D01*
X638100Y-279591D01*
X638096Y-279594D01*
X638081Y-279613D01*
X638063Y-279634D01*
X638041Y-279667D01*
X638020Y-279707D01*
X638001Y-279754D01*
X637987Y-279809D01*
X637983Y-279867D01*
Y-279871D01*
Y-279875D01*
Y-279896D01*
X637990Y-279929D01*
X637998Y-279969D01*
X638012Y-280013D01*
X638034Y-280060D01*
X638063Y-280108D01*
X638103Y-280155D01*
X638107Y-280159D01*
X638125Y-280173D01*
X638151Y-280191D01*
X638183Y-280213D01*
X638227Y-280235D01*
X638274Y-280253D01*
X638333Y-280268D01*
X638394Y-280271D01*
X638424D01*
X638456Y-280264D01*
X638500Y-280257D01*
X638547Y-280242D01*
X638598Y-280224D01*
X638646Y-280195D01*
X638693Y-280155D01*
X638697Y-280151D01*
X638711Y-280137D01*
X638729Y-280111D01*
X638748Y-280079D01*
X638769Y-280038D01*
X638788Y-279991D01*
X638802Y-279940D01*
X638806Y-279882D01*
Y-279878D01*
Y-279875D01*
X638802Y-279853D01*
X638799Y-279820D01*
X638791Y-279780D01*
X638777Y-279733D01*
X638758Y-279685D01*
X638729Y-279634D01*
X638693Y-279591D01*
X638689Y-279587D01*
X638671Y-279573D01*
X638646Y-279554D01*
X638613Y-279536D01*
X638569Y-279514D01*
X638518Y-279496D01*
X638460Y-279482D01*
X638394Y-279478D01*
D02*
G37*
G36*
X667905Y-274059D02*
X667876D01*
X667843Y-274067D01*
X667799Y-274074D01*
X667752Y-274088D01*
X667701Y-274107D01*
X667654Y-274136D01*
X667606Y-274176D01*
X667603Y-274179D01*
X667588Y-274194D01*
X667570Y-274219D01*
X667552Y-274252D01*
X667530Y-274292D01*
X667512Y-274340D01*
X667497Y-274391D01*
X667493Y-274449D01*
Y-274452D01*
Y-274456D01*
X667497Y-274478D01*
X667501Y-274511D01*
X667508Y-274551D01*
X667523Y-274598D01*
X667541Y-274645D01*
X667570Y-274696D01*
X667606Y-274740D01*
X667610Y-274744D01*
X667628Y-274758D01*
X667654Y-274776D01*
X667686Y-274795D01*
X667730Y-274816D01*
X667781Y-274835D01*
X667839Y-274849D01*
X667905Y-274853D01*
X667912D01*
X667934Y-274849D01*
X667967Y-274846D01*
X668010Y-274838D01*
X668058Y-274824D01*
X668105Y-274805D01*
X668156Y-274776D01*
X668200Y-274740D01*
X668203Y-274736D01*
X668218Y-274718D01*
X668236Y-274696D01*
X668258Y-274664D01*
X668280Y-274623D01*
X668298Y-274576D01*
X668312Y-274522D01*
X668316Y-274463D01*
Y-274460D01*
Y-274456D01*
Y-274434D01*
X668309Y-274401D01*
X668301Y-274361D01*
X668287Y-274318D01*
X668265Y-274270D01*
X668236Y-274223D01*
X668196Y-274176D01*
X668192Y-274172D01*
X668174Y-274158D01*
X668149Y-274139D01*
X668116Y-274118D01*
X668072Y-274096D01*
X668025Y-274078D01*
X667967Y-274063D01*
X667905Y-274059D01*
D02*
G37*
G36*
X667894Y-275104D02*
X667872D01*
X667857Y-275108D01*
X667817Y-275111D01*
X667766Y-275122D01*
X667708Y-275140D01*
X667650Y-275166D01*
X667588Y-275202D01*
X667533Y-275250D01*
X667526Y-275257D01*
X667512Y-275275D01*
X667490Y-275308D01*
X667464Y-275348D01*
X667435Y-275402D01*
X667413Y-275464D01*
X667399Y-275534D01*
X667391Y-275610D01*
Y-275617D01*
Y-275632D01*
X667395Y-275657D01*
X667399Y-275690D01*
X667406Y-275730D01*
X667417Y-275774D01*
X667432Y-275817D01*
X667450Y-275865D01*
X667453Y-275868D01*
X667461Y-275887D01*
X667475Y-275908D01*
X667497Y-275934D01*
X667523Y-275967D01*
X667555Y-275999D01*
X667592Y-276029D01*
X667635Y-276058D01*
X667643Y-276061D01*
X667657Y-276069D01*
X667683Y-276080D01*
X667716Y-276090D01*
X667756Y-276101D01*
X667803Y-276112D01*
X667854Y-276120D01*
X667905Y-276123D01*
X667927D01*
X667941Y-276120D01*
X667985Y-276116D01*
X668036Y-276105D01*
X668094Y-276087D01*
X668156Y-276065D01*
X668214Y-276029D01*
X668272Y-275981D01*
X668280Y-275974D01*
X668294Y-275956D01*
X668320Y-275923D01*
X668345Y-275883D01*
X668371Y-275832D01*
X668396Y-275770D01*
X668411Y-275697D01*
X668418Y-275621D01*
Y-275617D01*
Y-275610D01*
Y-275599D01*
X668414Y-275585D01*
X668411Y-275544D01*
X668400Y-275490D01*
X668382Y-275435D01*
X668356Y-275373D01*
X668320Y-275311D01*
X668269Y-275253D01*
X668261Y-275246D01*
X668243Y-275231D01*
X668211Y-275206D01*
X668167Y-275177D01*
X668112Y-275151D01*
X668047Y-275126D01*
X667974Y-275111D01*
X667894Y-275104D01*
D02*
G37*
G36*
X668718Y-249984D02*
X668689D01*
X668656Y-249991D01*
X668612Y-249999D01*
X668565Y-250013D01*
X668514Y-250031D01*
X668467Y-250061D01*
X668419Y-250101D01*
X668416Y-250104D01*
X668401Y-250119D01*
X668383Y-250144D01*
X668365Y-250177D01*
X668343Y-250217D01*
X668325Y-250264D01*
X668310Y-250315D01*
X668306Y-250374D01*
Y-250377D01*
Y-250381D01*
X668310Y-250403D01*
X668314Y-250435D01*
X668321Y-250476D01*
X668336Y-250523D01*
X668354Y-250570D01*
X668383Y-250621D01*
X668419Y-250665D01*
X668423Y-250668D01*
X668441Y-250683D01*
X668467Y-250701D01*
X668499Y-250719D01*
X668543Y-250741D01*
X668594Y-250760D01*
X668652Y-250774D01*
X668718Y-250778D01*
X668725D01*
X668747Y-250774D01*
X668780Y-250770D01*
X668823Y-250763D01*
X668871Y-250748D01*
X668918Y-250730D01*
X668969Y-250701D01*
X669013Y-250665D01*
X669016Y-250661D01*
X669031Y-250643D01*
X669049Y-250621D01*
X669071Y-250588D01*
X669093Y-250548D01*
X669111Y-250501D01*
X669126Y-250446D01*
X669129Y-250388D01*
Y-250384D01*
Y-250381D01*
Y-250359D01*
X669122Y-250326D01*
X669115Y-250286D01*
X669100Y-250243D01*
X669078Y-250195D01*
X669049Y-250148D01*
X669009Y-250101D01*
X669005Y-250097D01*
X668987Y-250082D01*
X668962Y-250064D01*
X668929Y-250042D01*
X668885Y-250021D01*
X668838Y-250002D01*
X668780Y-249988D01*
X668718Y-249984D01*
D02*
G37*
G36*
X668707Y-251029D02*
X668685D01*
X668671Y-251032D01*
X668631Y-251036D01*
X668579Y-251047D01*
X668521Y-251065D01*
X668463Y-251091D01*
X668401Y-251127D01*
X668347Y-251174D01*
X668339Y-251182D01*
X668325Y-251200D01*
X668303Y-251233D01*
X668277Y-251273D01*
X668248Y-251327D01*
X668226Y-251389D01*
X668212Y-251458D01*
X668205Y-251535D01*
Y-251542D01*
Y-251557D01*
X668208Y-251582D01*
X668212Y-251615D01*
X668219Y-251655D01*
X668230Y-251699D01*
X668245Y-251742D01*
X668263Y-251790D01*
X668266Y-251793D01*
X668274Y-251811D01*
X668288Y-251833D01*
X668310Y-251859D01*
X668336Y-251891D01*
X668368Y-251924D01*
X668405Y-251953D01*
X668448Y-251982D01*
X668456Y-251986D01*
X668470Y-251993D01*
X668496Y-252004D01*
X668529Y-252015D01*
X668569Y-252026D01*
X668616Y-252037D01*
X668667Y-252044D01*
X668718Y-252048D01*
X668740D01*
X668754Y-252044D01*
X668798Y-252041D01*
X668849Y-252030D01*
X668907Y-252012D01*
X668969Y-251990D01*
X669027Y-251953D01*
X669086Y-251906D01*
X669093Y-251899D01*
X669107Y-251881D01*
X669133Y-251848D01*
X669158Y-251808D01*
X669184Y-251757D01*
X669209Y-251695D01*
X669224Y-251622D01*
X669231Y-251546D01*
Y-251542D01*
Y-251535D01*
Y-251524D01*
X669227Y-251509D01*
X669224Y-251469D01*
X669213Y-251415D01*
X669195Y-251360D01*
X669169Y-251298D01*
X669133Y-251236D01*
X669082Y-251178D01*
X669074Y-251171D01*
X669056Y-251156D01*
X669024Y-251131D01*
X668980Y-251102D01*
X668925Y-251076D01*
X668860Y-251051D01*
X668787Y-251036D01*
X668707Y-251029D01*
D02*
G37*
G36*
X670643Y-257918D02*
X670621D01*
X670607Y-257921D01*
X670567Y-257928D01*
X670519Y-257939D01*
X670465Y-257961D01*
X670407Y-257994D01*
X670377Y-258016D01*
X670348Y-258038D01*
X670323Y-258067D01*
X670297Y-258100D01*
Y-258103D01*
X670290Y-258110D01*
X670283Y-258125D01*
X670272Y-258143D01*
X670261Y-258172D01*
X670246Y-258205D01*
X670235Y-258245D01*
X670221Y-258293D01*
X670206Y-258347D01*
X670192Y-258409D01*
X670177Y-258478D01*
X670166Y-258555D01*
X670155Y-258642D01*
X670148Y-258737D01*
X670145Y-258839D01*
X670141Y-258951D01*
Y-258959D01*
Y-258977D01*
Y-259010D01*
X670145Y-259053D01*
Y-259101D01*
X670148Y-259159D01*
X670152Y-259221D01*
X670159Y-259286D01*
X670177Y-259428D01*
X670188Y-259497D01*
X670203Y-259563D01*
X670217Y-259625D01*
X670239Y-259683D01*
X670261Y-259734D01*
X670287Y-259778D01*
Y-259781D01*
X670294Y-259785D01*
X670312Y-259810D01*
X670345Y-259843D01*
X670385Y-259880D01*
X670439Y-259916D01*
X670501Y-259949D01*
X670570Y-259974D01*
X670607Y-259978D01*
X670647Y-259981D01*
X670669D01*
X670683Y-259978D01*
X670720Y-259971D01*
X670771Y-259956D01*
X670825Y-259930D01*
X670887Y-259894D01*
X670916Y-259872D01*
X670945Y-259843D01*
X670974Y-259814D01*
X671004Y-259778D01*
Y-259774D01*
X671011Y-259767D01*
X671018Y-259756D01*
X671025Y-259738D01*
X671040Y-259712D01*
X671051Y-259679D01*
X671065Y-259643D01*
X671080Y-259599D01*
X671091Y-259545D01*
X671105Y-259486D01*
X671120Y-259417D01*
X671131Y-259345D01*
X671138Y-259257D01*
X671145Y-259166D01*
X671153Y-259064D01*
Y-258951D01*
Y-258948D01*
Y-258944D01*
Y-258926D01*
Y-258893D01*
X671149Y-258849D01*
Y-258802D01*
X671145Y-258744D01*
X671142Y-258682D01*
X671135Y-258613D01*
X671116Y-258474D01*
X671105Y-258405D01*
X671091Y-258340D01*
X671076Y-258278D01*
X671055Y-258220D01*
X671033Y-258169D01*
X671007Y-258125D01*
Y-258121D01*
X671000Y-258118D01*
X670993Y-258107D01*
X670982Y-258092D01*
X670949Y-258060D01*
X670909Y-258019D01*
X670854Y-257983D01*
X670792Y-257950D01*
X670760Y-257936D01*
X670723Y-257925D01*
X670683Y-257921D01*
X670643Y-257918D01*
D02*
G37*
G36*
X668692D02*
X668663D01*
X668630Y-257925D01*
X668587Y-257932D01*
X668539Y-257947D01*
X668488Y-257965D01*
X668441Y-257994D01*
X668394Y-258034D01*
X668390Y-258038D01*
X668375Y-258052D01*
X668357Y-258078D01*
X668339Y-258110D01*
X668317Y-258151D01*
X668299Y-258198D01*
X668285Y-258249D01*
X668281Y-258307D01*
Y-258311D01*
Y-258314D01*
X668285Y-258336D01*
X668288Y-258369D01*
X668295Y-258409D01*
X668310Y-258456D01*
X668328Y-258504D01*
X668357Y-258555D01*
X668394Y-258598D01*
X668397Y-258602D01*
X668415Y-258616D01*
X668441Y-258635D01*
X668474Y-258653D01*
X668517Y-258675D01*
X668568Y-258693D01*
X668627Y-258707D01*
X668692Y-258711D01*
X668699D01*
X668721Y-258707D01*
X668754Y-258704D01*
X668798Y-258697D01*
X668845Y-258682D01*
X668892Y-258664D01*
X668943Y-258635D01*
X668987Y-258598D01*
X668991Y-258595D01*
X669005Y-258576D01*
X669023Y-258555D01*
X669045Y-258522D01*
X669067Y-258482D01*
X669085Y-258435D01*
X669100Y-258380D01*
X669103Y-258322D01*
Y-258318D01*
Y-258314D01*
Y-258293D01*
X669096Y-258260D01*
X669089Y-258220D01*
X669074Y-258176D01*
X669053Y-258129D01*
X669023Y-258081D01*
X668983Y-258034D01*
X668980Y-258030D01*
X668961Y-258016D01*
X668936Y-257998D01*
X668903Y-257976D01*
X668860Y-257954D01*
X668812Y-257936D01*
X668754Y-257921D01*
X668692Y-257918D01*
D02*
G37*
G36*
X668681Y-258962D02*
X668659D01*
X668645Y-258966D01*
X668605Y-258969D01*
X668554Y-258980D01*
X668496Y-258999D01*
X668437Y-259024D01*
X668375Y-259061D01*
X668321Y-259108D01*
X668314Y-259115D01*
X668299Y-259133D01*
X668277Y-259166D01*
X668252Y-259206D01*
X668223Y-259261D01*
X668201Y-259323D01*
X668186Y-259392D01*
X668179Y-259468D01*
Y-259475D01*
Y-259490D01*
X668183Y-259516D01*
X668186Y-259548D01*
X668193Y-259588D01*
X668204Y-259632D01*
X668219Y-259676D01*
X668237Y-259723D01*
X668241Y-259727D01*
X668248Y-259745D01*
X668263Y-259767D01*
X668285Y-259792D01*
X668310Y-259825D01*
X668343Y-259858D01*
X668379Y-259887D01*
X668423Y-259916D01*
X668430Y-259920D01*
X668445Y-259927D01*
X668470Y-259938D01*
X668503Y-259949D01*
X668543Y-259960D01*
X668590Y-259971D01*
X668641Y-259978D01*
X668692Y-259981D01*
X668714D01*
X668729Y-259978D01*
X668772Y-259974D01*
X668823Y-259963D01*
X668881Y-259945D01*
X668943Y-259923D01*
X669002Y-259887D01*
X669060Y-259840D01*
X669067Y-259832D01*
X669082Y-259814D01*
X669107Y-259781D01*
X669133Y-259741D01*
X669158Y-259690D01*
X669184Y-259628D01*
X669198Y-259556D01*
X669205Y-259479D01*
Y-259475D01*
Y-259468D01*
Y-259457D01*
X669202Y-259443D01*
X669198Y-259403D01*
X669187Y-259348D01*
X669169Y-259294D01*
X669143Y-259232D01*
X669107Y-259170D01*
X669056Y-259111D01*
X669049Y-259104D01*
X669031Y-259090D01*
X668998Y-259064D01*
X668954Y-259035D01*
X668900Y-259010D01*
X668834Y-258984D01*
X668761Y-258969D01*
X668681Y-258962D01*
D02*
G37*
G36*
X648643Y-252753D02*
X648585D01*
X648570Y-252757D01*
X648530Y-252760D01*
X648483Y-252775D01*
X648425Y-252793D01*
X648363Y-252826D01*
X648301Y-252866D01*
X648272Y-252895D01*
X648243Y-252924D01*
Y-252928D01*
X648236Y-252931D01*
X648228Y-252942D01*
X648221Y-252953D01*
X648196Y-252990D01*
X648170Y-253041D01*
X648141Y-253103D01*
X648115Y-253179D01*
X648101Y-253266D01*
X648094Y-253361D01*
Y-253365D01*
Y-253372D01*
Y-253383D01*
X648097Y-253401D01*
Y-253423D01*
X648101Y-253445D01*
X648112Y-253499D01*
X648130Y-253561D01*
X648152Y-253627D01*
X648188Y-253692D01*
X648236Y-253750D01*
X648243Y-253758D01*
X648261Y-253772D01*
X648294Y-253798D01*
X648334Y-253823D01*
X648388Y-253852D01*
X648450Y-253878D01*
X648520Y-253892D01*
X648596Y-253900D01*
X648618D01*
X648632Y-253896D01*
X648672Y-253892D01*
X648720Y-253882D01*
X648778Y-253863D01*
X648836Y-253838D01*
X648895Y-253801D01*
X648949Y-253750D01*
X648956Y-253743D01*
X648971Y-253721D01*
X648993Y-253689D01*
X649022Y-253641D01*
X649047Y-253583D01*
X649069Y-253514D01*
X649084Y-253430D01*
X649091Y-253336D01*
Y-253332D01*
Y-253325D01*
Y-253310D01*
X649087Y-253292D01*
Y-253266D01*
X649084Y-253241D01*
X649073Y-253183D01*
X649058Y-253114D01*
X649033Y-253041D01*
X648996Y-252972D01*
X648949Y-252910D01*
Y-252906D01*
X648942Y-252902D01*
X648924Y-252884D01*
X648895Y-252859D01*
X648854Y-252830D01*
X648804Y-252804D01*
X648745Y-252779D01*
X648680Y-252760D01*
X648643Y-252753D01*
D02*
G37*
G36*
X656230Y-301172D02*
X656209D01*
X656194Y-301176D01*
X656154Y-301179D01*
X656107Y-301190D01*
X656048Y-301208D01*
X655990Y-301234D01*
X655932Y-301270D01*
X655877Y-301321D01*
X655870Y-301329D01*
X655855Y-301350D01*
X655834Y-301383D01*
X655804Y-301431D01*
X655779Y-301489D01*
X655757Y-301558D01*
X655743Y-301642D01*
X655735Y-301736D01*
Y-301740D01*
Y-301747D01*
Y-301762D01*
X655739Y-301780D01*
Y-301805D01*
X655743Y-301831D01*
X655754Y-301889D01*
X655768Y-301958D01*
X655794Y-302031D01*
X655830Y-302100D01*
X655877Y-302162D01*
Y-302166D01*
X655885Y-302169D01*
X655903Y-302188D01*
X655932Y-302213D01*
X655972Y-302242D01*
X656023Y-302268D01*
X656081Y-302293D01*
X656147Y-302311D01*
X656183Y-302319D01*
X656241D01*
X656256Y-302315D01*
X656296Y-302311D01*
X656343Y-302297D01*
X656401Y-302279D01*
X656463Y-302246D01*
X656525Y-302206D01*
X656554Y-302177D01*
X656583Y-302148D01*
Y-302144D01*
X656591Y-302140D01*
X656598Y-302129D01*
X656605Y-302118D01*
X656631Y-302082D01*
X656656Y-302031D01*
X656685Y-301969D01*
X656711Y-301893D01*
X656725Y-301805D01*
X656733Y-301711D01*
Y-301707D01*
Y-301700D01*
Y-301689D01*
X656729Y-301671D01*
Y-301649D01*
X656725Y-301627D01*
X656714Y-301572D01*
X656696Y-301511D01*
X656674Y-301445D01*
X656638Y-301379D01*
X656591Y-301321D01*
X656583Y-301314D01*
X656565Y-301299D01*
X656532Y-301274D01*
X656492Y-301249D01*
X656438Y-301219D01*
X656376Y-301194D01*
X656307Y-301179D01*
X656230Y-301172D01*
D02*
G37*
G36*
X645236Y-297808D02*
X645233D01*
X645229D01*
X645207Y-297812D01*
X645174Y-297816D01*
X645134Y-297823D01*
X645087Y-297837D01*
X645040Y-297856D01*
X644989Y-297885D01*
X644945Y-297921D01*
X644941Y-297925D01*
X644927Y-297943D01*
X644909Y-297969D01*
X644890Y-298001D01*
X644869Y-298045D01*
X644850Y-298096D01*
X644836Y-298154D01*
X644832Y-298220D01*
Y-298227D01*
X644836Y-298249D01*
X644839Y-298282D01*
X644847Y-298325D01*
X644861Y-298373D01*
X644879Y-298420D01*
X644909Y-298471D01*
X644945Y-298515D01*
X644949Y-298518D01*
X644967Y-298533D01*
X644989Y-298551D01*
X645021Y-298573D01*
X645061Y-298595D01*
X645109Y-298613D01*
X645163Y-298627D01*
X645222Y-298631D01*
X645225D01*
X645229D01*
X645251D01*
X645284Y-298624D01*
X645324Y-298617D01*
X645367Y-298602D01*
X645415Y-298580D01*
X645462Y-298551D01*
X645509Y-298511D01*
X645513Y-298507D01*
X645528Y-298489D01*
X645546Y-298464D01*
X645568Y-298431D01*
X645589Y-298387D01*
X645608Y-298340D01*
X645622Y-298282D01*
X645626Y-298220D01*
Y-298191D01*
X645618Y-298158D01*
X645611Y-298114D01*
X645597Y-298067D01*
X645578Y-298016D01*
X645549Y-297969D01*
X645509Y-297921D01*
X645506Y-297918D01*
X645491Y-297903D01*
X645466Y-297885D01*
X645433Y-297867D01*
X645393Y-297845D01*
X645345Y-297827D01*
X645295Y-297812D01*
X645236Y-297808D01*
D02*
G37*
G36*
X644075Y-297707D02*
X644068D01*
X644053D01*
X644028Y-297710D01*
X643995Y-297714D01*
X643955Y-297721D01*
X643911Y-297732D01*
X643868Y-297746D01*
X643820Y-297765D01*
X643817Y-297768D01*
X643798Y-297776D01*
X643777Y-297790D01*
X643751Y-297812D01*
X643718Y-297837D01*
X643686Y-297870D01*
X643656Y-297907D01*
X643627Y-297950D01*
X643624Y-297958D01*
X643616Y-297972D01*
X643606Y-297998D01*
X643595Y-298030D01*
X643584Y-298071D01*
X643573Y-298118D01*
X643566Y-298169D01*
X643562Y-298220D01*
Y-298242D01*
X643566Y-298256D01*
X643569Y-298300D01*
X643580Y-298351D01*
X643598Y-298409D01*
X643620Y-298471D01*
X643656Y-298529D01*
X643704Y-298587D01*
X643711Y-298595D01*
X643729Y-298609D01*
X643762Y-298635D01*
X643802Y-298660D01*
X643853Y-298686D01*
X643915Y-298711D01*
X643988Y-298726D01*
X644064Y-298733D01*
X644068D01*
X644075D01*
X644086D01*
X644101Y-298729D01*
X644141Y-298726D01*
X644195Y-298715D01*
X644250Y-298697D01*
X644312Y-298671D01*
X644374Y-298635D01*
X644432Y-298584D01*
X644439Y-298576D01*
X644454Y-298558D01*
X644479Y-298526D01*
X644508Y-298482D01*
X644534Y-298427D01*
X644559Y-298362D01*
X644574Y-298289D01*
X644581Y-298209D01*
Y-298187D01*
X644577Y-298172D01*
X644574Y-298132D01*
X644563Y-298081D01*
X644545Y-298023D01*
X644519Y-297965D01*
X644483Y-297903D01*
X644436Y-297849D01*
X644428Y-297841D01*
X644410Y-297827D01*
X644377Y-297805D01*
X644337Y-297779D01*
X644283Y-297750D01*
X644221Y-297728D01*
X644151Y-297714D01*
X644075Y-297707D01*
D02*
G37*
G36*
X529353Y-134113D02*
X529331D01*
X529317Y-134117D01*
X529280Y-134124D01*
X529229Y-134139D01*
X529175Y-134164D01*
X529113Y-134200D01*
X529084Y-134222D01*
X529055Y-134251D01*
X529026Y-134281D01*
X528996Y-134317D01*
Y-134320D01*
X528989Y-134328D01*
X528982Y-134339D01*
X528975Y-134357D01*
X528960Y-134382D01*
X528949Y-134415D01*
X528934Y-134451D01*
X528920Y-134495D01*
X528909Y-134550D01*
X528895Y-134608D01*
X528880Y-134677D01*
X528869Y-134750D01*
X528862Y-134837D01*
X528855Y-134928D01*
X528847Y-135030D01*
Y-135143D01*
Y-135147D01*
Y-135150D01*
Y-135169D01*
Y-135201D01*
X528851Y-135245D01*
Y-135292D01*
X528855Y-135351D01*
X528858Y-135413D01*
X528865Y-135482D01*
X528884Y-135620D01*
X528895Y-135689D01*
X528909Y-135755D01*
X528924Y-135817D01*
X528945Y-135875D01*
X528967Y-135926D01*
X528993Y-135969D01*
Y-135973D01*
X529000Y-135977D01*
X529007Y-135988D01*
X529018Y-136002D01*
X529051Y-136035D01*
X529091Y-136075D01*
X529146Y-136111D01*
X529208Y-136144D01*
X529240Y-136159D01*
X529277Y-136170D01*
X529317Y-136173D01*
X529357Y-136177D01*
X529379D01*
X529393Y-136173D01*
X529433Y-136166D01*
X529481Y-136155D01*
X529535Y-136133D01*
X529593Y-136100D01*
X529623Y-136079D01*
X529652Y-136057D01*
X529677Y-136028D01*
X529703Y-135995D01*
Y-135991D01*
X529710Y-135984D01*
X529717Y-135969D01*
X529728Y-135951D01*
X529739Y-135922D01*
X529753Y-135889D01*
X529765Y-135849D01*
X529779Y-135802D01*
X529794Y-135747D01*
X529808Y-135686D01*
X529823Y-135616D01*
X529834Y-135540D01*
X529845Y-135452D01*
X529852Y-135358D01*
X529855Y-135256D01*
X529859Y-135143D01*
Y-135136D01*
Y-135118D01*
Y-135085D01*
X529855Y-135041D01*
Y-134994D01*
X529852Y-134936D01*
X529848Y-134874D01*
X529841Y-134808D01*
X529823Y-134666D01*
X529812Y-134597D01*
X529797Y-134532D01*
X529783Y-134470D01*
X529761Y-134412D01*
X529739Y-134361D01*
X529713Y-134317D01*
Y-134313D01*
X529706Y-134310D01*
X529688Y-134284D01*
X529655Y-134251D01*
X529615Y-134215D01*
X529561Y-134178D01*
X529499Y-134146D01*
X529430Y-134120D01*
X529393Y-134117D01*
X529353Y-134113D01*
D02*
G37*
G36*
X502175Y-108438D02*
X502153D01*
X502139Y-108441D01*
X502102Y-108445D01*
X502051Y-108456D01*
X501997Y-108474D01*
X501935Y-108503D01*
X501876Y-108539D01*
X501818Y-108590D01*
X501811Y-108598D01*
X501796Y-108616D01*
X501771Y-108649D01*
X501745Y-108696D01*
X501720Y-108751D01*
X501694Y-108820D01*
X501680Y-108896D01*
X501673Y-108984D01*
Y-108991D01*
Y-109009D01*
X501676Y-109042D01*
X501680Y-109082D01*
X501687Y-109129D01*
X501702Y-109180D01*
X501716Y-109235D01*
X501738Y-109289D01*
X501742Y-109297D01*
X501753Y-109315D01*
X501767Y-109340D01*
X501789Y-109373D01*
X501815Y-109406D01*
X501847Y-109446D01*
X501884Y-109479D01*
X501927Y-109511D01*
X501935Y-109515D01*
X501949Y-109522D01*
X501975Y-109537D01*
X502007Y-109548D01*
X502044Y-109562D01*
X502088Y-109577D01*
X502135Y-109584D01*
X502186Y-109588D01*
X502204D01*
X502219Y-109584D01*
X502255Y-109581D01*
X502302Y-109570D01*
X502353Y-109548D01*
X502412Y-109522D01*
X502470Y-109482D01*
X502499Y-109460D01*
X502524Y-109431D01*
Y-109428D01*
X502532Y-109424D01*
X502546Y-109402D01*
X502568Y-109366D01*
X502597Y-109318D01*
X502623Y-109256D01*
X502644Y-109184D01*
X502659Y-109100D01*
X502666Y-109002D01*
Y-108998D01*
Y-108991D01*
Y-108976D01*
X502663Y-108958D01*
Y-108936D01*
X502659Y-108911D01*
X502648Y-108853D01*
X502634Y-108787D01*
X502608Y-108718D01*
X502572Y-108652D01*
X502524Y-108590D01*
X502517Y-108583D01*
X502499Y-108565D01*
X502470Y-108543D01*
X502430Y-108514D01*
X502379Y-108485D01*
X502320Y-108463D01*
X502251Y-108445D01*
X502175Y-108438D01*
D02*
G37*
G36*
X46312Y-35868D02*
X45184D01*
X46312Y-36662D01*
Y-35868D01*
D02*
G37*
G36*
X123478Y-37443D02*
X122349D01*
X123478Y-38237D01*
Y-37443D01*
D02*
G37*
G36*
X673031Y-55288D02*
X673009D01*
X672995Y-55292D01*
X672958Y-55295D01*
X672907Y-55306D01*
X672853Y-55324D01*
X672791Y-55353D01*
X672732Y-55390D01*
X672674Y-55441D01*
X672667Y-55448D01*
X672652Y-55466D01*
X672627Y-55499D01*
X672601Y-55546D01*
X672576Y-55601D01*
X672550Y-55670D01*
X672536Y-55747D01*
X672529Y-55834D01*
Y-55841D01*
Y-55859D01*
X672532Y-55892D01*
X672536Y-55932D01*
X672543Y-55980D01*
X672558Y-56030D01*
X672572Y-56085D01*
X672594Y-56140D01*
X672598Y-56147D01*
X672609Y-56165D01*
X672623Y-56191D01*
X672645Y-56223D01*
X672671Y-56256D01*
X672703Y-56296D01*
X672740Y-56329D01*
X672783Y-56362D01*
X672791Y-56365D01*
X672805Y-56373D01*
X672831Y-56387D01*
X672863Y-56398D01*
X672900Y-56413D01*
X672943Y-56427D01*
X672991Y-56435D01*
X673042Y-56438D01*
X673060D01*
X673075Y-56435D01*
X673111Y-56431D01*
X673158Y-56420D01*
X673209Y-56398D01*
X673268Y-56373D01*
X673326Y-56333D01*
X673355Y-56311D01*
X673380Y-56282D01*
Y-56278D01*
X673388Y-56274D01*
X673402Y-56252D01*
X673424Y-56216D01*
X673453Y-56169D01*
X673479Y-56107D01*
X673500Y-56034D01*
X673515Y-55950D01*
X673522Y-55852D01*
Y-55848D01*
Y-55841D01*
Y-55827D01*
X673519Y-55808D01*
Y-55787D01*
X673515Y-55761D01*
X673504Y-55703D01*
X673490Y-55637D01*
X673464Y-55568D01*
X673428Y-55503D01*
X673380Y-55441D01*
X673373Y-55433D01*
X673355Y-55415D01*
X673326Y-55393D01*
X673286Y-55364D01*
X673235Y-55335D01*
X673176Y-55313D01*
X673107Y-55295D01*
X673031Y-55288D01*
D02*
G37*
G36*
X630435Y-166185D02*
X630376D01*
X630362Y-166189D01*
X630322Y-166193D01*
X630275Y-166207D01*
X630216Y-166225D01*
X630155Y-166258D01*
X630093Y-166298D01*
X630063Y-166327D01*
X630034Y-166356D01*
Y-166360D01*
X630027Y-166364D01*
X630020Y-166375D01*
X630013Y-166385D01*
X629987Y-166422D01*
X629962Y-166473D01*
X629932Y-166535D01*
X629907Y-166611D01*
X629892Y-166699D01*
X629885Y-166793D01*
Y-166797D01*
Y-166804D01*
Y-166815D01*
X629889Y-166833D01*
Y-166855D01*
X629892Y-166877D01*
X629903Y-166931D01*
X629921Y-166993D01*
X629943Y-167059D01*
X629980Y-167124D01*
X630027Y-167183D01*
X630034Y-167190D01*
X630053Y-167204D01*
X630085Y-167230D01*
X630125Y-167255D01*
X630180Y-167285D01*
X630242Y-167310D01*
X630311Y-167325D01*
X630387Y-167332D01*
X630409D01*
X630424Y-167328D01*
X630464Y-167325D01*
X630511Y-167314D01*
X630569Y-167296D01*
X630628Y-167270D01*
X630686Y-167234D01*
X630740Y-167183D01*
X630748Y-167175D01*
X630762Y-167154D01*
X630784Y-167121D01*
X630813Y-167074D01*
X630839Y-167015D01*
X630861Y-166946D01*
X630875Y-166862D01*
X630883Y-166768D01*
Y-166764D01*
Y-166757D01*
Y-166742D01*
X630879Y-166724D01*
Y-166699D01*
X630875Y-166673D01*
X630864Y-166615D01*
X630850Y-166546D01*
X630824Y-166473D01*
X630788Y-166404D01*
X630740Y-166342D01*
Y-166338D01*
X630733Y-166334D01*
X630715Y-166316D01*
X630686Y-166291D01*
X630646Y-166262D01*
X630595Y-166236D01*
X630537Y-166211D01*
X630471Y-166193D01*
X630435Y-166185D01*
D02*
G37*
G36*
X626114Y-166240D02*
X625532D01*
Y-168162D01*
X626129D01*
X626154Y-168158D01*
X626209Y-168155D01*
X626271Y-168151D01*
X626336Y-168144D01*
X626402Y-168133D01*
X626456Y-168118D01*
X626464Y-168114D01*
X626482Y-168111D01*
X626507Y-168100D01*
X626540Y-168085D01*
X626576Y-168064D01*
X626613Y-168042D01*
X626649Y-168016D01*
X626686Y-167987D01*
X626689Y-167980D01*
X626704Y-167965D01*
X626726Y-167940D01*
X626751Y-167903D01*
X626780Y-167856D01*
X626813Y-167801D01*
X626842Y-167740D01*
X626868Y-167670D01*
Y-167667D01*
X626871Y-167659D01*
X626875Y-167649D01*
X626878Y-167634D01*
X626882Y-167616D01*
X626889Y-167590D01*
X626897Y-167565D01*
X626904Y-167536D01*
X626915Y-167463D01*
X626926Y-167379D01*
X626933Y-167285D01*
X626937Y-167183D01*
Y-167179D01*
Y-167165D01*
Y-167146D01*
X626933Y-167117D01*
Y-167084D01*
X626929Y-167048D01*
X626926Y-167004D01*
X626922Y-166961D01*
X626904Y-166862D01*
X626882Y-166760D01*
X626849Y-166666D01*
X626827Y-166619D01*
X626806Y-166578D01*
Y-166575D01*
X626798Y-166568D01*
X626791Y-166557D01*
X626784Y-166542D01*
X626755Y-166506D01*
X626718Y-166462D01*
X626671Y-166415D01*
X626616Y-166367D01*
X626554Y-166327D01*
X626489Y-166295D01*
X626482Y-166291D01*
X626464Y-166287D01*
X626431Y-166276D01*
X626383Y-166265D01*
X626325Y-166258D01*
X626252Y-166247D01*
X626209Y-166244D01*
X626161D01*
X626114Y-166240D01*
D02*
G37*
G36*
X32469Y15538D02*
X32466D01*
X32458D01*
X32444D01*
X32426Y15535D01*
X32400D01*
X32375Y15531D01*
X32316Y15520D01*
X32247Y15506D01*
X32175Y15480D01*
X32105Y15444D01*
X32043Y15396D01*
X32040D01*
X32036Y15389D01*
X32018Y15371D01*
X31993Y15342D01*
X31963Y15302D01*
X31938Y15251D01*
X31912Y15193D01*
X31894Y15127D01*
X31887Y15091D01*
Y15032D01*
X31891Y15018D01*
X31894Y14978D01*
X31909Y14931D01*
X31927Y14872D01*
X31960Y14810D01*
X32000Y14749D01*
X32029Y14719D01*
X32058Y14690D01*
X32062D01*
X32065Y14683D01*
X32076Y14676D01*
X32087Y14668D01*
X32124Y14643D01*
X32175Y14617D01*
X32236Y14588D01*
X32313Y14563D01*
X32400Y14548D01*
X32495Y14541D01*
X32498D01*
X32506D01*
X32517D01*
X32535Y14545D01*
X32557D01*
X32579Y14548D01*
X32633Y14559D01*
X32695Y14577D01*
X32761Y14599D01*
X32826Y14636D01*
X32884Y14683D01*
X32892Y14690D01*
X32906Y14708D01*
X32932Y14741D01*
X32957Y14781D01*
X32986Y14836D01*
X33012Y14898D01*
X33026Y14967D01*
X33034Y15043D01*
Y15065D01*
X33030Y15080D01*
X33026Y15120D01*
X33015Y15167D01*
X32997Y15225D01*
X32972Y15284D01*
X32935Y15342D01*
X32884Y15396D01*
X32877Y15404D01*
X32855Y15418D01*
X32822Y15440D01*
X32775Y15469D01*
X32717Y15495D01*
X32648Y15517D01*
X32564Y15531D01*
X32469Y15538D01*
D02*
G37*
G36*
X32884Y13551D02*
X32881D01*
X32866D01*
X32848D01*
X32819Y13547D01*
X32786D01*
X32750Y13544D01*
X32706Y13540D01*
X32662Y13536D01*
X32564Y13518D01*
X32462Y13496D01*
X32368Y13464D01*
X32320Y13442D01*
X32280Y13420D01*
X32276D01*
X32269Y13413D01*
X32258Y13405D01*
X32244Y13398D01*
X32207Y13369D01*
X32164Y13333D01*
X32116Y13285D01*
X32069Y13231D01*
X32029Y13169D01*
X31996Y13103D01*
X31993Y13096D01*
X31989Y13078D01*
X31978Y13045D01*
X31967Y12998D01*
X31960Y12939D01*
X31949Y12867D01*
X31945Y12823D01*
Y12776D01*
X31942Y12728D01*
Y12146D01*
X33863D01*
Y12743D01*
X33860Y12768D01*
X33856Y12823D01*
X33853Y12885D01*
X33845Y12950D01*
X33834Y13016D01*
X33820Y13070D01*
X33816Y13078D01*
X33813Y13096D01*
X33802Y13121D01*
X33787Y13154D01*
X33765Y13191D01*
X33743Y13227D01*
X33718Y13263D01*
X33689Y13300D01*
X33681Y13303D01*
X33667Y13318D01*
X33641Y13340D01*
X33605Y13365D01*
X33558Y13394D01*
X33503Y13427D01*
X33441Y13456D01*
X33372Y13482D01*
X33369D01*
X33361Y13485D01*
X33350Y13489D01*
X33336Y13493D01*
X33318Y13496D01*
X33292Y13504D01*
X33267Y13511D01*
X33237Y13518D01*
X33165Y13529D01*
X33081Y13540D01*
X32986Y13547D01*
X32884Y13551D01*
D02*
G37*
G36*
X25995Y13551D02*
X25991D01*
X25976D01*
X25958D01*
X25929Y13547D01*
X25896D01*
X25860Y13544D01*
X25816Y13540D01*
X25773Y13536D01*
X25674Y13518D01*
X25572Y13496D01*
X25478Y13464D01*
X25430Y13442D01*
X25390Y13420D01*
X25387D01*
X25379Y13413D01*
X25368Y13405D01*
X25354Y13398D01*
X25317Y13369D01*
X25274Y13333D01*
X25227Y13285D01*
X25179Y13231D01*
X25139Y13169D01*
X25106Y13103D01*
X25103Y13096D01*
X25099Y13078D01*
X25088Y13045D01*
X25077Y12998D01*
X25070Y12939D01*
X25059Y12867D01*
X25056Y12823D01*
Y12776D01*
X25052Y12728D01*
Y12146D01*
X26974D01*
Y12743D01*
X26970Y12768D01*
X26967Y12823D01*
X26963Y12885D01*
X26956Y12950D01*
X26945Y13016D01*
X26930Y13070D01*
X26926Y13078D01*
X26923Y13096D01*
X26912Y13121D01*
X26897Y13154D01*
X26875Y13191D01*
X26854Y13227D01*
X26828Y13263D01*
X26799Y13300D01*
X26792Y13303D01*
X26777Y13318D01*
X26752Y13340D01*
X26715Y13365D01*
X26668Y13394D01*
X26613Y13427D01*
X26551Y13456D01*
X26482Y13482D01*
X26479D01*
X26471Y13485D01*
X26460Y13489D01*
X26446Y13493D01*
X26428Y13496D01*
X26402Y13504D01*
X26377Y13511D01*
X26348Y13518D01*
X26275Y13529D01*
X26191Y13540D01*
X26096Y13547D01*
X25995Y13551D01*
D02*
G37*
G36*
X608523Y-22437D02*
X607729D01*
Y-23566D01*
X608523Y-22437D01*
D02*
G37*
G36*
X90426Y-97194D02*
X90419D01*
X90400D01*
X90368Y-97198D01*
X90328Y-97201D01*
X90280Y-97208D01*
X90229Y-97223D01*
X90175Y-97238D01*
X90120Y-97259D01*
X90113Y-97263D01*
X90095Y-97274D01*
X90069Y-97289D01*
X90036Y-97310D01*
X90004Y-97336D01*
X89964Y-97369D01*
X89931Y-97405D01*
X89898Y-97449D01*
X89894Y-97456D01*
X89887Y-97470D01*
X89873Y-97496D01*
X89862Y-97529D01*
X89847Y-97565D01*
X89833Y-97609D01*
X89825Y-97656D01*
X89822Y-97707D01*
Y-97725D01*
X89825Y-97740D01*
X89829Y-97776D01*
X89840Y-97824D01*
X89862Y-97875D01*
X89887Y-97933D01*
X89927Y-97991D01*
X89949Y-98020D01*
X89978Y-98046D01*
X89982D01*
X89986Y-98053D01*
X90007Y-98067D01*
X90044Y-98089D01*
X90091Y-98118D01*
X90153Y-98144D01*
X90226Y-98166D01*
X90310Y-98180D01*
X90408Y-98188D01*
X90411D01*
X90419D01*
X90433D01*
X90451Y-98184D01*
X90473D01*
X90499Y-98180D01*
X90557Y-98169D01*
X90623Y-98155D01*
X90692Y-98129D01*
X90757Y-98093D01*
X90819Y-98046D01*
X90826Y-98038D01*
X90845Y-98020D01*
X90866Y-97991D01*
X90895Y-97951D01*
X90925Y-97900D01*
X90947Y-97842D01*
X90965Y-97773D01*
X90972Y-97696D01*
Y-97674D01*
X90968Y-97660D01*
X90965Y-97623D01*
X90954Y-97572D01*
X90936Y-97518D01*
X90906Y-97456D01*
X90870Y-97398D01*
X90819Y-97339D01*
X90812Y-97332D01*
X90794Y-97318D01*
X90761Y-97292D01*
X90714Y-97267D01*
X90659Y-97241D01*
X90590Y-97216D01*
X90513Y-97201D01*
X90426Y-97194D01*
D02*
G37*
G36*
X90852Y-99127D02*
X90845D01*
X90826D01*
X90794D01*
X90750Y-99130D01*
X90703D01*
X90644Y-99134D01*
X90583Y-99138D01*
X90517Y-99145D01*
X90375Y-99163D01*
X90306Y-99174D01*
X90240Y-99189D01*
X90178Y-99203D01*
X90120Y-99225D01*
X90069Y-99247D01*
X90026Y-99272D01*
X90022D01*
X90018Y-99280D01*
X89993Y-99298D01*
X89960Y-99331D01*
X89924Y-99371D01*
X89887Y-99425D01*
X89855Y-99487D01*
X89829Y-99556D01*
X89825Y-99593D01*
X89822Y-99633D01*
Y-99655D01*
X89825Y-99669D01*
X89833Y-99705D01*
X89847Y-99756D01*
X89873Y-99811D01*
X89909Y-99873D01*
X89931Y-99902D01*
X89960Y-99931D01*
X89989Y-99960D01*
X90026Y-99989D01*
X90029D01*
X90036Y-99997D01*
X90047Y-100004D01*
X90066Y-100011D01*
X90091Y-100026D01*
X90124Y-100037D01*
X90160Y-100051D01*
X90204Y-100066D01*
X90259Y-100077D01*
X90317Y-100091D01*
X90386Y-100106D01*
X90459Y-100117D01*
X90546Y-100124D01*
X90637Y-100131D01*
X90739Y-100139D01*
X90852D01*
X90855D01*
X90859D01*
X90877D01*
X90910D01*
X90954Y-100135D01*
X91001D01*
X91059Y-100131D01*
X91121Y-100128D01*
X91190Y-100120D01*
X91329Y-100102D01*
X91398Y-100091D01*
X91463Y-100077D01*
X91525Y-100062D01*
X91584Y-100040D01*
X91634Y-100019D01*
X91678Y-99993D01*
X91682D01*
X91685Y-99986D01*
X91696Y-99979D01*
X91711Y-99968D01*
X91744Y-99935D01*
X91784Y-99895D01*
X91820Y-99840D01*
X91853Y-99778D01*
X91867Y-99746D01*
X91878Y-99709D01*
X91882Y-99669D01*
X91886Y-99629D01*
Y-99607D01*
X91882Y-99593D01*
X91875Y-99553D01*
X91864Y-99505D01*
X91842Y-99451D01*
X91809Y-99392D01*
X91787Y-99363D01*
X91765Y-99334D01*
X91736Y-99309D01*
X91704Y-99283D01*
X91700D01*
X91693Y-99276D01*
X91678Y-99269D01*
X91660Y-99258D01*
X91631Y-99247D01*
X91598Y-99232D01*
X91558Y-99221D01*
X91511Y-99207D01*
X91456Y-99192D01*
X91394Y-99178D01*
X91325Y-99163D01*
X91249Y-99152D01*
X91161Y-99141D01*
X91067Y-99134D01*
X90965Y-99130D01*
X90852Y-99127D01*
D02*
G37*
G36*
X124961Y-80918D02*
X124957D01*
X124953D01*
X124932Y-80922D01*
X124899Y-80925D01*
X124859Y-80932D01*
X124811Y-80947D01*
X124764Y-80965D01*
X124713Y-80994D01*
X124670Y-81031D01*
X124666Y-81034D01*
X124651Y-81053D01*
X124633Y-81078D01*
X124615Y-81111D01*
X124593Y-81155D01*
X124575Y-81205D01*
X124560Y-81264D01*
X124557Y-81329D01*
Y-81336D01*
X124560Y-81358D01*
X124564Y-81391D01*
X124571Y-81435D01*
X124586Y-81482D01*
X124604Y-81529D01*
X124633Y-81580D01*
X124670Y-81624D01*
X124673Y-81628D01*
X124691Y-81642D01*
X124713Y-81660D01*
X124746Y-81682D01*
X124786Y-81704D01*
X124833Y-81722D01*
X124888Y-81737D01*
X124946Y-81741D01*
X124950D01*
X124953D01*
X124975D01*
X125008Y-81733D01*
X125048Y-81726D01*
X125092Y-81711D01*
X125139Y-81690D01*
X125186Y-81660D01*
X125234Y-81620D01*
X125237Y-81617D01*
X125252Y-81599D01*
X125270Y-81573D01*
X125292Y-81540D01*
X125314Y-81497D01*
X125332Y-81449D01*
X125347Y-81391D01*
X125350Y-81329D01*
Y-81300D01*
X125343Y-81267D01*
X125336Y-81224D01*
X125321Y-81176D01*
X125303Y-81125D01*
X125274Y-81078D01*
X125234Y-81031D01*
X125230Y-81027D01*
X125215Y-81013D01*
X125190Y-80994D01*
X125157Y-80976D01*
X125117Y-80954D01*
X125070Y-80936D01*
X125019Y-80922D01*
X124961Y-80918D01*
D02*
G37*
G36*
X123800Y-80816D02*
X123792D01*
X123778D01*
X123752Y-80820D01*
X123719Y-80823D01*
X123679Y-80831D01*
X123636Y-80841D01*
X123592Y-80856D01*
X123545Y-80874D01*
X123541Y-80878D01*
X123523Y-80885D01*
X123501Y-80900D01*
X123476Y-80922D01*
X123443Y-80947D01*
X123410Y-80980D01*
X123381Y-81016D01*
X123352Y-81060D01*
X123348Y-81067D01*
X123341Y-81082D01*
X123330Y-81107D01*
X123319Y-81140D01*
X123308Y-81180D01*
X123297Y-81227D01*
X123290Y-81278D01*
X123286Y-81329D01*
Y-81351D01*
X123290Y-81366D01*
X123293Y-81409D01*
X123304Y-81460D01*
X123323Y-81519D01*
X123345Y-81580D01*
X123381Y-81639D01*
X123428Y-81697D01*
X123435Y-81704D01*
X123454Y-81719D01*
X123486Y-81744D01*
X123527Y-81770D01*
X123577Y-81795D01*
X123639Y-81821D01*
X123712Y-81835D01*
X123789Y-81842D01*
X123792D01*
X123800D01*
X123810D01*
X123825Y-81839D01*
X123865Y-81835D01*
X123920Y-81824D01*
X123974Y-81806D01*
X124036Y-81781D01*
X124098Y-81744D01*
X124156Y-81693D01*
X124163Y-81686D01*
X124178Y-81668D01*
X124204Y-81635D01*
X124233Y-81591D01*
X124258Y-81537D01*
X124284Y-81471D01*
X124298Y-81398D01*
X124305Y-81318D01*
Y-81296D01*
X124302Y-81282D01*
X124298Y-81242D01*
X124287Y-81191D01*
X124269Y-81133D01*
X124244Y-81074D01*
X124207Y-81013D01*
X124160Y-80958D01*
X124153Y-80951D01*
X124134Y-80936D01*
X124102Y-80914D01*
X124062Y-80889D01*
X124007Y-80860D01*
X123945Y-80838D01*
X123876Y-80823D01*
X123800Y-80816D01*
D02*
G37*
G36*
X521106Y-123533D02*
X520313Y-124661D01*
X521106D01*
Y-123533D01*
D02*
G37*
%LPD*%
D15*
X684350Y-24213D02*
X687303D01*
X684350Y-30906D02*
Y-24213D01*
Y-30906D02*
X687303D01*
Y-24213D01*
X549193Y-235433D02*
X581516D01*
Y-254331D02*
Y-235433D01*
X549193Y-254331D02*
X581516D01*
X549193D02*
Y-235433D01*
X596348Y-262354D02*
X629636D01*
Y-289614D02*
Y-262354D01*
X596348Y-289614D02*
X629636D01*
X596348D02*
Y-262354D01*
X682141Y-324552D02*
X690300D01*
X682141D02*
Y-320330D01*
X690300D01*
Y-324552D02*
Y-320330D01*
X667913Y-325689D02*
X677756D01*
X667913D02*
Y-320768D01*
X677756D01*
Y-325689D02*
Y-320768D01*
X667913Y-318209D02*
X677756D01*
X667913D02*
Y-313287D01*
X677756D01*
Y-318209D02*
Y-313287D01*
X682141Y-317859D02*
X690300D01*
X682141D02*
Y-313637D01*
X690300D01*
Y-317859D02*
Y-313637D01*
X678346Y-108169D02*
X708169D01*
Y-69784D01*
X678346D02*
X708169D01*
X678346Y-108169D02*
Y-69784D01*
X678543Y-61360D02*
X692323D01*
Y-44940D01*
X678543D02*
X692323D01*
X678543Y-61360D02*
Y-44940D01*
X668389Y-96342D02*
X676493D01*
X668389Y-111532D02*
Y-96342D01*
Y-111532D02*
X676493D01*
Y-96342D01*
X667072Y-112106D02*
Y-109153D01*
X661275D02*
X667072D01*
X661275Y-112106D02*
Y-109153D01*
Y-112106D02*
X667072D01*
X690724Y-67716D02*
Y-64567D01*
Y-67716D02*
X696677D01*
Y-64567D01*
X690724D02*
X696677D01*
X673130Y-96358D02*
Y-92618D01*
X666240D02*
X673130D01*
X666240Y-96358D02*
Y-92618D01*
Y-96358D02*
X673130D01*
X677658Y-35335D02*
X681398D01*
Y-28445D01*
X677658D02*
X681398D01*
X677658Y-35335D02*
Y-28445D01*
X685039Y-40772D02*
X688189D01*
Y-34819D01*
X685039D02*
X688189D01*
X685039Y-40772D02*
Y-34819D01*
X692520Y-40908D02*
X695669D01*
Y-34954D01*
X692520D02*
X695669D01*
X692520Y-40908D02*
Y-34954D01*
X612992Y-98032D02*
Y-88583D01*
Y-98032D02*
X621260D01*
Y-88583D01*
X612992D02*
X621260D01*
X624582Y-94882D02*
Y-91732D01*
Y-94882D02*
X630536D01*
Y-91732D01*
X624582D02*
X630536D01*
X580118Y-98032D02*
Y-88583D01*
Y-98032D02*
X588386D01*
Y-88583D01*
X580118D02*
X588386D01*
X595669Y-95103D02*
X598819D01*
Y-89149D01*
X595669D02*
X598819D01*
X595669Y-95103D02*
Y-89149D01*
X415413Y-139764D02*
Y-109843D01*
Y-139764D02*
X431831D01*
Y-109843D01*
X415413D02*
X431831D01*
X407382Y-125000D02*
X412303D01*
X407382Y-134843D02*
Y-125000D01*
Y-134843D02*
X412303D01*
Y-125000D01*
X434154Y-124606D02*
X439075D01*
X434154Y-134449D02*
Y-124606D01*
Y-134449D02*
X439075D01*
Y-124606D01*
X243701Y-125394D02*
X253150D01*
Y-117126D01*
X243701D02*
X253150D01*
X243701Y-125394D02*
Y-117126D01*
X248819Y-113607D02*
X251969D01*
Y-107653D01*
X248819D02*
X251969D01*
X248819Y-113607D02*
Y-107653D01*
X407619Y-113707D02*
X411841D01*
X407619Y-121866D02*
Y-113707D01*
Y-121866D02*
X411841D01*
Y-113707D01*
X434503Y-114810D02*
X438725D01*
X434503Y-122969D02*
Y-114810D01*
Y-122969D02*
X438725D01*
Y-114810D01*
X547023Y-281496D02*
X552977D01*
X547023D02*
Y-278346D01*
X552977D01*
Y-281496D02*
Y-278346D01*
X599892Y-229378D02*
Y-202118D01*
Y-229378D02*
X633179D01*
Y-202118D01*
X599892D02*
X633179D01*
X650787Y-167303D02*
X669685D01*
X650787Y-199626D02*
Y-167303D01*
Y-199626D02*
X669685D01*
Y-167303D01*
X681250Y-189259D02*
X685473D01*
Y-181100D01*
X681250D02*
X685473D01*
X681250Y-189259D02*
Y-181100D01*
X625000Y-237008D02*
Y-230709D01*
Y-237008D02*
X636417D01*
Y-230709D01*
X625000D02*
X636417D01*
X648032Y-220276D02*
X652756D01*
X648032Y-229331D02*
Y-220276D01*
Y-229331D02*
X652756D01*
Y-220276D01*
X565497Y-223765D02*
Y-219542D01*
X557338D02*
X565497D01*
X557338Y-223765D02*
Y-219542D01*
Y-223765D02*
X565497D01*
X594237Y-238878D02*
Y-235925D01*
X588440D02*
X594237D01*
X588440Y-238878D02*
Y-235925D01*
Y-238878D02*
X594237D01*
X596260Y-234449D02*
X602165D01*
X596260Y-245079D02*
Y-234449D01*
Y-245079D02*
X602165D01*
Y-234449D01*
X622244Y-236417D02*
Y-230512D01*
X611614D02*
X622244D01*
X611614Y-236417D02*
Y-230512D01*
Y-236417D02*
X622244D01*
X680315Y-204246D02*
X683465D01*
X680315Y-210199D02*
Y-204246D01*
Y-210199D02*
X683465D01*
Y-204246D01*
X671654Y-193701D02*
X679528D01*
Y-175591D01*
X671654D02*
X679528D01*
X671654Y-193701D02*
Y-175591D01*
X664818Y-203401D02*
X669040D01*
X664818Y-211560D02*
Y-203401D01*
Y-211560D02*
X669040D01*
Y-203401D01*
X683366Y-239173D02*
Y-217520D01*
X655217D02*
X683366D01*
X655217Y-239173D02*
Y-217520D01*
Y-239173D02*
X683366D01*
X633484Y-200787D02*
Y-181890D01*
X601161D02*
X633484D01*
X601161Y-200787D02*
Y-181890D01*
Y-200787D02*
X633484D01*
X592126Y-196272D02*
X600000D01*
Y-180893D01*
X592126D02*
X600000D01*
X592126Y-196272D02*
Y-180893D01*
X672047Y-202953D02*
X676772D01*
X672047Y-212008D02*
Y-202953D01*
Y-212008D02*
X676772D01*
Y-202953D01*
X582677Y-196272D02*
X590551D01*
Y-180893D01*
X582677D02*
X590551D01*
X582677Y-196272D02*
Y-180893D01*
X558366Y-196161D02*
X562106D01*
X558366Y-203051D02*
Y-196161D01*
Y-203051D02*
X562106D01*
Y-196161D01*
X551432Y-227308D02*
X555654D01*
Y-219149D01*
X551432D02*
X555654D01*
X551432Y-227308D02*
Y-219149D01*
X561024Y-217544D02*
X564173D01*
Y-211590D01*
X561024D02*
X564173D01*
X561024Y-217544D02*
Y-211590D01*
X583366Y-150768D02*
Y-117736D01*
X608760D01*
Y-150768D02*
Y-117736D01*
X583366Y-150768D02*
X608760D01*
X616194Y-155839D02*
Y-115551D01*
X700294D01*
Y-155839D02*
Y-115551D01*
X616194Y-155839D02*
X700294D01*
X583071Y-181929D02*
Y-156653D01*
X546850D02*
X583071D01*
X546850Y-181929D02*
Y-156653D01*
Y-181929D02*
X583071D01*
X613976Y-299213D02*
Y-292913D01*
Y-299213D02*
X625394D01*
Y-292913D01*
X613976D02*
X625394D01*
X605709Y-298622D02*
Y-292717D01*
X595079D02*
X605709D01*
X595079Y-298622D02*
Y-292717D01*
Y-298622D02*
X605709D01*
X564054Y-294631D02*
Y-290408D01*
X555894D02*
X564054D01*
X555894Y-294631D02*
Y-290408D01*
Y-294631D02*
X564054D01*
X554080Y-293843D02*
Y-289621D01*
X545920D02*
X554080D01*
X545920Y-293843D02*
Y-289621D01*
Y-293843D02*
X554080D01*
X590256Y-288440D02*
X593209D01*
X590256Y-294237D02*
Y-288440D01*
Y-294237D02*
X593209D01*
Y-288440D01*
X545965Y-256201D02*
X549705D01*
X545965Y-263090D02*
Y-256201D01*
Y-263090D02*
X549705D01*
Y-256201D01*
X577756Y-294685D02*
Y-288779D01*
X567126D02*
X577756D01*
X567126Y-294685D02*
Y-288779D01*
Y-294685D02*
X577756D01*
X590551Y-261233D02*
X598425D01*
Y-245854D01*
X590551D02*
X598425D01*
X590551Y-261233D02*
Y-245854D01*
X601575Y-261626D02*
X609449D01*
Y-246248D01*
X601575D02*
X609449D01*
X601575Y-261626D02*
Y-246248D01*
X655118Y-272441D02*
Y-264567D01*
Y-272441D02*
X673228D01*
Y-264567D01*
X655118D02*
X673228D01*
X644709Y-279528D02*
Y-276378D01*
X638756D02*
X644709D01*
X638756Y-279528D02*
Y-276378D01*
Y-279528D02*
X644709D01*
X660487Y-278489D02*
Y-274267D01*
Y-278489D02*
X668647D01*
Y-274267D01*
X660487D02*
X668647D01*
X661300Y-254414D02*
Y-250192D01*
Y-254414D02*
X669460D01*
Y-250192D01*
X661300D02*
X669460D01*
X660827Y-262598D02*
Y-257874D01*
Y-262598D02*
X669882D01*
Y-257874D01*
X660827D02*
X669882D01*
X627146Y-263779D02*
Y-244882D01*
Y-263779D02*
X659469D01*
Y-244882D01*
X627146D02*
X659469D01*
X675492Y-310827D02*
Y-289173D01*
X647342D02*
X675492D01*
X647342Y-310827D02*
Y-289173D01*
Y-310827D02*
X675492D01*
X640945Y-290354D02*
X645669D01*
X640945Y-299410D02*
Y-290354D01*
Y-299410D02*
X645669D01*
Y-290354D01*
X540354Y-112303D02*
X562008D01*
X540354Y-140453D02*
Y-112303D01*
Y-140453D02*
X562008D01*
Y-112303D01*
X539173Y-136221D02*
Y-131496D01*
X530118D02*
X539173D01*
X530118Y-136221D02*
Y-131496D01*
Y-136221D02*
X539173D01*
X495920Y-111319D02*
Y-108366D01*
Y-111319D02*
X501718D01*
Y-108366D01*
X495920D02*
X501718D01*
X476575Y-112795D02*
X501378D01*
X476575Y-132087D02*
Y-112795D01*
Y-132087D02*
X501378D01*
Y-112795D01*
X43996Y-45669D02*
X50492D01*
Y-33071D01*
X43996D02*
X50492D01*
X43996Y-45669D02*
Y-33071D01*
X121161Y-47244D02*
X127657D01*
Y-34646D01*
X121161D02*
X127657D01*
X121161Y-47244D02*
Y-34646D01*
X661417Y-59941D02*
Y-53445D01*
Y-59941D02*
X674016D01*
Y-53445D01*
X661417D02*
X674016D01*
X611811Y-57185D02*
Y-50689D01*
X599213D02*
X611811D01*
X599213Y-57185D02*
Y-50689D01*
Y-57185D02*
X611811D01*
X608681Y-181201D02*
Y-155807D01*
Y-181201D02*
X641713D01*
Y-155807D01*
X608681D02*
X641713D01*
X38189Y6890D02*
X42520D01*
Y16732D01*
X38189D02*
X42520D01*
X38189Y6890D02*
Y16732D01*
X31299Y6890D02*
X35630D01*
Y16732D01*
X31299D02*
X35630D01*
X31299Y6890D02*
Y16732D01*
X24409Y6890D02*
X28740D01*
Y16732D01*
X24409D02*
X28740D01*
X24409Y6890D02*
Y16732D01*
X45079Y6890D02*
X49409D01*
Y16732D01*
X45079D02*
X49409D01*
X45079Y6890D02*
Y16732D01*
X74410Y-112402D02*
Y-108071D01*
Y-112402D02*
X85433D01*
Y-108071D01*
X74410D02*
X85433D01*
X73425Y-120669D02*
X78150D01*
X73425Y-130118D02*
Y-120669D01*
Y-130118D02*
X78150D01*
Y-120669D01*
X663386Y-26870D02*
Y-20374D01*
Y-26870D02*
X675984D01*
Y-20374D01*
X663386D02*
X675984D01*
X619488Y-24754D02*
Y-18258D01*
X606890D02*
X619488D01*
X606890Y-24754D02*
Y-18258D01*
Y-24754D02*
X619488D01*
X86319Y-88041D02*
X92815D01*
X86319Y-100639D02*
Y-88041D01*
Y-100639D02*
X92815D01*
Y-88041D01*
X119783Y-69734D02*
X126279D01*
X119783Y-82332D02*
Y-69734D01*
Y-82332D02*
X126279D01*
Y-69734D01*
X508661Y-117765D02*
X522835D01*
Y-131939D02*
Y-117765D01*
X508661Y-131939D02*
X522835D01*
X508661D02*
Y-117765D01*
X454528Y-119201D02*
X466732D01*
X454528Y-132472D02*
Y-119201D01*
Y-132472D02*
X466732D01*
Y-119201D01*
M02*
